G04 ================== begin FILE IDENTIFICATION RECORD ==================*
G04 Layout Name:  15669-1.brd*
G04 Film Name:    L1*
G04 File Format:  Gerber RS274X*
G04 File Origin:  Cadence Allegro 16.5-S056*
G04 Origin Date:  Wed Nov 16 04:08:34 2016*
G04 *
G04 Layer:  VIA CLASS/TOP*
G04 Layer:  PIN/TOP*
G04 Layer:  ETCH/TOP*
G04 Layer:  DRAWING FORMAT/LAYER_PCB_STORY*
G04 Layer:  DRAWING FORMAT/LAYER_L1*
G04 *
G04 Offset:    (0.00 0.00)*
G04 Mirror:    No*
G04 Mode:      Positive*
G04 Rotation:  0*
G04 FullContactRelief:  No*
G04 UndefLineWidth:     6.00*
G04 ================== end FILE IDENTIFICATION RECORD ====================*
%FSLAX35Y35*MOIN*%
%IR0*IPPOS*OFA0.00000B0.00000*MIA0B0*SFA1.00000B1.00000*%
%AMMACRO62*
4,1,40,.013,.017,
-.013,.017,
-.013695,.016939,
-.014368,.016759,
-.015,.016464,
-.015571,.016064,
-.016064,.015571,
-.016464,.015,
-.016759,.014368,
-.016939,.013695,
-.017,.013,
-.017,-.013,
-.016939,-.013695,
-.016759,-.014368,
-.016464,-.015,
-.016064,-.015571,
-.015571,-.016064,
-.015,-.016464,
-.014368,-.016759,
-.013695,-.016939,
-.013,-.017,
.013,-.017,
.013695,-.016939,
.014368,-.016759,
.015,-.016464,
.015571,-.016064,
.016064,-.015571,
.016464,-.015,
.016759,-.014368,
.016939,-.013695,
.017,-.013,
.017,.013,
.016939,.013695,
.016759,.014368,
.016464,.015,
.016064,.015571,
.015571,.016064,
.015,.016464,
.014368,.016759,
.013695,.016939,
.013,.017,
0.0*
%
%ADD62MACRO62*%
%AMMACRO36*
4,1,40,.017,-.013,
.017,.013,
.016939,.013695,
.016759,.014368,
.016464,.015,
.016064,.015571,
.015571,.016064,
.015,.016464,
.014368,.016759,
.013695,.016939,
.013,.017,
-.013,.017,
-.013695,.016939,
-.014368,.016759,
-.015,.016464,
-.015571,.016064,
-.016064,.015571,
-.016464,.015,
-.016759,.014368,
-.016939,.013695,
-.017,.013,
-.017,-.013,
-.016939,-.013695,
-.016759,-.014368,
-.016464,-.015,
-.016064,-.015571,
-.015571,-.016064,
-.015,-.016464,
-.014368,-.016759,
-.013695,-.016939,
-.013,-.017,
.013,-.017,
.013695,-.016939,
.014368,-.016759,
.015,-.016464,
.015571,-.016064,
.016064,-.015571,
.016464,-.015,
.016759,-.014368,
.016939,-.013695,
.017,-.013,
0.0*
%
%ADD36MACRO36*%
%ADD34O,.103X.06*%
%ADD92R,.23X.032*%
%ADD35R,.11X.045*%
%ADD53R,.045X.11*%
%ADD17R,.11X.045*%
%ADD80R,.01X.007*%
%ADD10C,.01*%
%ADD12C,.02*%
%ADD16C,.022*%
%ADD11C,.04*%
%ADD57C,.032*%
%ADD13C,.034*%
%ADD15C,.028*%
%AMMACRO39*
4,1,40,.0225,-.007,
.022378,-.008389,
.022018,-.009736,
.021428,-.011,
.020628,-.012142,
.019642,-.013128,
.0185,-.013928,
.017236,-.014518,
.015889,-.014878,
.0145,-.015,
-.0145,-.015,
-.015889,-.014878,
-.017236,-.014518,
-.0185,-.013928,
-.019642,-.013128,
-.020628,-.012142,
-.021428,-.011,
-.022018,-.009736,
-.022378,-.008389,
-.0225,-.007,
-.0225,.007,
-.022378,.008389,
-.022018,.009736,
-.021428,.011,
-.020628,.012142,
-.019642,.013128,
-.0185,.013928,
-.017236,.014518,
-.015889,.014878,
-.0145,.015,
.0145,.015,
.015889,.014878,
.017236,.014518,
.0185,.013928,
.019642,.013128,
.020628,.012142,
.021428,.011,
.022018,.009736,
.022378,.008389,
.0225,.007,
.0225,-.007,
0.0*
%
%ADD39MACRO39*%
%AMMACRO40*
4,1,40,-.007,-.0225,
-.008389,-.022378,
-.009736,-.022018,
-.011,-.021428,
-.012142,-.020628,
-.013128,-.019642,
-.013928,-.0185,
-.014518,-.017236,
-.014878,-.015889,
-.015,-.0145,
-.015,.0145,
-.014878,.015889,
-.014518,.017236,
-.013928,.0185,
-.013128,.019642,
-.012142,.020628,
-.011,.021428,
-.009736,.022018,
-.008389,.022378,
-.007,.0225,
.007,.0225,
.008389,.022378,
.009736,.022018,
.011,.021428,
.012142,.020628,
.013128,.019642,
.013928,.0185,
.014518,.017236,
.014878,.015889,
.015,.0145,
.015,-.0145,
.014878,-.015889,
.014518,-.017236,
.013928,-.0185,
.013128,-.019642,
.012142,-.020628,
.011,-.021428,
.009736,-.022018,
.008389,-.022378,
.007,-.0225,
-.007,-.0225,
0.0*
%
%ADD40MACRO40*%
%AMMACRO87*
4,1,8,.197,-.186,
-.197,-.186,
-.197,.186,
.197,.186,
.197,.00925,
-.059,.00925,
-.059,-.00925,
.197,-.00925,
.197,-.186,
0.0*
%
%ADD87MACRO87*%
%AMMACRO41*
4,1,40,.007,.011,
-.007,.011,
-.007695,.010939,
-.008368,.010759,
-.009,.010464,
-.009571,.010064,
-.010064,.009571,
-.010464,.009,
-.010759,.008368,
-.010939,.007695,
-.011,.007,
-.011,-.007,
-.010939,-.007695,
-.010759,-.008368,
-.010464,-.009,
-.010064,-.009571,
-.009571,-.010064,
-.009,-.010464,
-.008368,-.010759,
-.007695,-.010939,
-.007,-.011,
.007,-.011,
.007695,-.010939,
.008368,-.010759,
.009,-.010464,
.009571,-.010064,
.010064,-.009571,
.010464,-.009,
.010759,-.008368,
.010939,-.007695,
.011,-.007,
.011,.007,
.010939,.007695,
.010759,.008368,
.010464,.009,
.010064,.009571,
.009571,.010064,
.009,.010464,
.008368,.010759,
.007695,.010939,
.007,.011,
0.0*
%
%ADD41MACRO41*%
%AMMACRO28*
4,1,40,.011,-.007,
.011,.007,
.010939,.007695,
.010759,.008368,
.010464,.009,
.010064,.009571,
.009571,.010064,
.009,.010464,
.008368,.010759,
.007695,.010939,
.007,.011,
-.007,.011,
-.007695,.010939,
-.008368,.010759,
-.009,.010464,
-.009571,.010064,
-.010064,.009571,
-.010464,.009,
-.010759,.008368,
-.010939,.007695,
-.011,.007,
-.011,-.007,
-.010939,-.007695,
-.010759,-.008368,
-.010464,-.009,
-.010064,-.009571,
-.009571,-.010064,
-.009,-.010464,
-.008368,-.010759,
-.007695,-.010939,
-.007,-.011,
.007,-.011,
.007695,-.010939,
.008368,-.010759,
.009,-.010464,
.009571,-.010064,
.010064,-.009571,
.010464,-.009,
.010759,-.008368,
.010939,-.007695,
.011,-.007,
0.0*
%
%ADD28MACRO28*%
%ADD83R,.066X.066*%
%AMMACRO24*
4,1,40,-.012,.008,
-.012,-.008,
-.011939,-.008695,
-.011759,-.009368,
-.011464,-.01,
-.011064,-.010571,
-.010571,-.011064,
-.01,-.011464,
-.009368,-.011759,
-.008695,-.011939,
-.008,-.012,
.008,-.012,
.008695,-.011939,
.009368,-.011759,
.01,-.011464,
.010571,-.011064,
.011064,-.010571,
.011464,-.01,
.011759,-.009368,
.011939,-.008695,
.012,-.008,
.012,.008,
.011939,.008695,
.011759,.009368,
.011464,.01,
.011064,.010571,
.010571,.011064,
.01,.011464,
.009368,.011759,
.008695,.011939,
.008,.012,
-.008,.012,
-.008695,.011939,
-.009368,.011759,
-.01,.011464,
-.010571,.011064,
-.011064,.010571,
-.011464,.01,
-.011759,.009368,
-.011939,.008695,
-.012,.008,
0.0*
%
%ADD24MACRO24*%
%ADD67R,.089X.089*%
%AMMACRO47*
4,1,40,.008,.012,
-.008,.012,
-.008695,.011939,
-.009368,.011759,
-.01,.011464,
-.010571,.011064,
-.011064,.010571,
-.011464,.01,
-.011759,.009368,
-.011939,.008695,
-.012,.008,
-.012,-.008,
-.011939,-.008695,
-.011759,-.009368,
-.011464,-.01,
-.011064,-.010571,
-.010571,-.011064,
-.01,-.011464,
-.009368,-.011759,
-.008695,-.011939,
-.008,-.012,
.008,-.012,
.008695,-.011939,
.009368,-.011759,
.01,-.011464,
.010571,-.011064,
.011064,-.010571,
.011464,-.01,
.011759,-.009368,
.011939,-.008695,
.012,-.008,
.012,.008,
.011939,.008695,
.011759,.009368,
.011464,.01,
.011064,.010571,
.010571,.011064,
.01,.011464,
.009368,.011759,
.008695,.011939,
.008,.012,
0.0*
%
%ADD47MACRO47*%
%AMMACRO25*
4,1,40,-.013,-.017,
.013,-.017,
.013695,-.016939,
.014368,-.016759,
.015,-.016464,
.015571,-.016064,
.016064,-.015571,
.016464,-.015,
.016759,-.014368,
.016939,-.013695,
.017,-.013,
.017,.013,
.016939,.013695,
.016759,.014368,
.016464,.015,
.016064,.015571,
.015571,.016064,
.015,.016464,
.014368,.016759,
.013695,.016939,
.013,.017,
-.013,.017,
-.013695,.016939,
-.014368,.016759,
-.015,.016464,
-.015571,.016064,
-.016064,.015571,
-.016464,.015,
-.016759,.014368,
-.016939,.013695,
-.017,.013,
-.017,-.013,
-.016939,-.013695,
-.016759,-.014368,
-.016464,-.015,
-.016064,-.015571,
-.015571,-.016064,
-.015,-.016464,
-.014368,-.016759,
-.013695,-.016939,
-.013,-.017,
0.0*
%
%ADD25MACRO25*%
%AMMACRO48*
4,1,40,-.017,.013,
-.017,-.013,
-.016939,-.013695,
-.016759,-.014368,
-.016464,-.015,
-.016064,-.015571,
-.015571,-.016064,
-.015,-.016464,
-.014368,-.016759,
-.013695,-.016939,
-.013,-.017,
.013,-.017,
.013695,-.016939,
.014368,-.016759,
.015,-.016464,
.015571,-.016064,
.016064,-.015571,
.016464,-.015,
.016759,-.014368,
.016939,-.013695,
.017,-.013,
.017,.013,
.016939,.013695,
.016759,.014368,
.016464,.015,
.016064,.015571,
.015571,.016064,
.015,.016464,
.014368,.016759,
.013695,.016939,
.013,.017,
-.013,.017,
-.013695,.016939,
-.014368,.016759,
-.015,.016464,
-.015571,.016064,
-.016064,.015571,
-.016464,.015,
-.016759,.014368,
-.016939,.013695,
-.017,.013,
0.0*
%
%ADD48MACRO48*%
%AMMACRO90*
4,1,6,.005,.0135,
.005,.0065,
.025,-.0135,
-.025,-.0135,
-.005,.0065,
-.005,.0135,
.005,.0135,
0.0*
%
%ADD90MACRO90*%
%AMMACRO42*
4,1,40,.007,.011,
-.007,.011,
-.007695,.010939,
-.008368,.010759,
-.009,.010464,
-.009571,.010064,
-.010064,.009571,
-.010464,.009,
-.010759,.008368,
-.010939,.007695,
-.011,.007,
-.011,-.007,
-.010939,-.007695,
-.010759,-.008368,
-.010464,-.009,
-.010064,-.009571,
-.009571,-.010064,
-.009,-.010464,
-.008368,-.010759,
-.007695,-.010939,
-.007,-.011,
.007,-.011,
.007695,-.010939,
.008368,-.010759,
.009,-.010464,
.009571,-.010064,
.010064,-.009571,
.010464,-.009,
.010759,-.008368,
.010939,-.007695,
.011,-.007,
.011,.007,
.010939,.007695,
.010759,.008368,
.010464,.009,
.010064,.009571,
.009571,.010064,
.009,.010464,
.008368,.010759,
.007695,.010939,
.007,.011,
0.0*
%
%ADD42MACRO42*%
%AMMACRO29*
4,1,40,.011,-.007,
.011,.007,
.010939,.007695,
.010759,.008368,
.010464,.009,
.010064,.009571,
.009571,.010064,
.009,.010464,
.008368,.010759,
.007695,.010939,
.007,.011,
-.007,.011,
-.007695,.010939,
-.008368,.010759,
-.009,.010464,
-.009571,.010064,
-.010064,.009571,
-.010464,.009,
-.010759,.008368,
-.010939,.007695,
-.011,.007,
-.011,-.007,
-.010939,-.007695,
-.010759,-.008368,
-.010464,-.009,
-.010064,-.009571,
-.009571,-.010064,
-.009,-.010464,
-.008368,-.010759,
-.007695,-.010939,
-.007,-.011,
.007,-.011,
.007695,-.010939,
.008368,-.010759,
.009,-.010464,
.009571,-.010064,
.010064,-.009571,
.010464,-.009,
.010759,-.008368,
.010939,-.007695,
.011,-.007,
0.0*
%
%ADD29MACRO29*%
%AMMACRO23*
4,1,40,-.012,.008,
-.012,-.008,
-.011939,-.008695,
-.011759,-.009368,
-.011464,-.01,
-.011064,-.010571,
-.010571,-.011064,
-.01,-.011464,
-.009368,-.011759,
-.008695,-.011939,
-.008,-.012,
.008,-.012,
.008695,-.011939,
.009368,-.011759,
.01,-.011464,
.010571,-.011064,
.011064,-.010571,
.011464,-.01,
.011759,-.009368,
.011939,-.008695,
.012,-.008,
.012,.008,
.011939,.008695,
.011759,.009368,
.011464,.01,
.011064,.010571,
.010571,.011064,
.01,.011464,
.009368,.011759,
.008695,.011939,
.008,.012,
-.008,.012,
-.008695,.011939,
-.009368,.011759,
-.01,.011464,
-.010571,.011064,
-.011064,.010571,
-.011464,.01,
-.011759,.009368,
-.011939,.008695,
-.012,.008,
0.0*
%
%ADD23MACRO23*%
%AMMACRO46*
4,1,40,.008,.012,
-.008,.012,
-.008695,.011939,
-.009368,.011759,
-.01,.011464,
-.010571,.011064,
-.011064,.010571,
-.011464,.01,
-.011759,.009368,
-.011939,.008695,
-.012,.008,
-.012,-.008,
-.011939,-.008695,
-.011759,-.009368,
-.011464,-.01,
-.011064,-.010571,
-.010571,-.011064,
-.01,-.011464,
-.009368,-.011759,
-.008695,-.011939,
-.008,-.012,
.008,-.012,
.008695,-.011939,
.009368,-.011759,
.01,-.011464,
.010571,-.011064,
.011064,-.010571,
.011464,-.01,
.011759,-.009368,
.011939,-.008695,
.012,-.008,
.012,.008,
.011939,.008695,
.011759,.009368,
.011464,.01,
.011064,.010571,
.010571,.011064,
.01,.011464,
.009368,.011759,
.008695,.011939,
.008,.012,
0.0*
%
%ADD46MACRO46*%
%AMMACRO26*
4,1,40,-.013,-.017,
.013,-.017,
.013695,-.016939,
.014368,-.016759,
.015,-.016464,
.015571,-.016064,
.016064,-.015571,
.016464,-.015,
.016759,-.014368,
.016939,-.013695,
.017,-.013,
.017,.013,
.016939,.013695,
.016759,.014368,
.016464,.015,
.016064,.015571,
.015571,.016064,
.015,.016464,
.014368,.016759,
.013695,.016939,
.013,.017,
-.013,.017,
-.013695,.016939,
-.014368,.016759,
-.015,.016464,
-.015571,.016064,
-.016064,.015571,
-.016464,.015,
-.016759,.014368,
-.016939,.013695,
-.017,.013,
-.017,-.013,
-.016939,-.013695,
-.016759,-.014368,
-.016464,-.015,
-.016064,-.015571,
-.015571,-.016064,
-.015,-.016464,
-.014368,-.016759,
-.013695,-.016939,
-.013,-.017,
0.0*
%
%ADD26MACRO26*%
%AMMACRO56*
4,1,40,-.017,.013,
-.017,-.013,
-.016939,-.013695,
-.016759,-.014368,
-.016464,-.015,
-.016064,-.015571,
-.015571,-.016064,
-.015,-.016464,
-.014368,-.016759,
-.013695,-.016939,
-.013,-.017,
.013,-.017,
.013695,-.016939,
.014368,-.016759,
.015,-.016464,
.015571,-.016064,
.016064,-.015571,
.016464,-.015,
.016759,-.014368,
.016939,-.013695,
.017,-.013,
.017,.013,
.016939,.013695,
.016759,.014368,
.016464,.015,
.016064,.015571,
.015571,.016064,
.015,.016464,
.014368,.016759,
.013695,.016939,
.013,.017,
-.013,.017,
-.013695,.016939,
-.014368,.016759,
-.015,.016464,
-.015571,.016064,
-.016064,.015571,
-.016464,.015,
-.016759,.014368,
-.016939,.013695,
-.017,.013,
0.0*
%
%ADD56MACRO56*%
%ADD91R,.001X.001*%
%ADD71R,.042X.012*%
%ADD70R,.012X.042*%
%ADD55R,.022X.04*%
%ADD74R,.012X.06*%
%ADD66R,.012X.042*%
%ADD65R,.042X.012*%
%ADD58R,.06X.014*%
%ADD73R,.014X.06*%
%ADD69R,.036X.012*%
%ADD68R,.012X.036*%
%ADD82R,.012X.037*%
%ADD81R,.037X.012*%
%ADD77R,.012X.046*%
%ADD76R,.046X.012*%
%ADD64R,.012X.036*%
%ADD63R,.036X.012*%
%ADD84R,.115X.138*%
%AMMACRO72*
4,1,40,-.004,-.007,
.004,-.007,
.004347,-.00697,
.004684,-.006879,
.005,-.006732,
.005286,-.006532,
.005532,-.006286,
.005732,-.006,
.005879,-.005684,
.00597,-.005347,
.006,-.005,
.006,.005,
.00597,.005347,
.005879,.005684,
.005732,.006,
.005532,.006286,
.005286,.006532,
.005,.006732,
.004684,.006879,
.004347,.00697,
.004,.007,
-.004,.007,
-.004347,.00697,
-.004684,.006879,
-.005,.006732,
-.005286,.006532,
-.005532,.006286,
-.005732,.006,
-.005879,.005684,
-.00597,.005347,
-.006,.005,
-.006,-.005,
-.00597,-.005347,
-.005879,-.005684,
-.005732,-.006,
-.005532,-.006286,
-.005286,-.006532,
-.005,-.006732,
-.004684,-.006879,
-.004347,-.00697,
-.004,-.007,
0.0*
%
%ADD72MACRO72*%
%ADD79R,.05X.065*%
%ADD38R,.036X.024*%
%ADD86R,.065X.05*%
%ADD33R,.081X.026*%
%ADD52R,.065X.025*%
%ADD32R,.079X.02*%
%ADD18C,.315*%
%ADD51R,.045X.055*%
%ADD45R,.048X.016*%
%ADD14R,.098X.02*%
%ADD60R,.055X.045*%
%ADD59R,.016X.048*%
%ADD88R,.394X.172*%
%ADD27R,.057X.083*%
%AMMACRO85*
4,1,40,.014,.008,
.014,-.008,
.013939,-.008695,
.013759,-.009368,
.013464,-.01,
.013064,-.010571,
.012571,-.011064,
.012,-.011464,
.011368,-.011759,
.010695,-.011939,
.01,-.012,
-.01,-.012,
-.010695,-.011939,
-.011368,-.011759,
-.012,-.011464,
-.012571,-.011064,
-.013064,-.010571,
-.013464,-.01,
-.013759,-.009368,
-.013939,-.008695,
-.014,-.008,
-.014,.008,
-.013939,.008695,
-.013759,.009368,
-.013464,.01,
-.013064,.010571,
-.012571,.011064,
-.012,.011464,
-.011368,.011759,
-.010695,.011939,
-.01,.012,
.01,.012,
.010695,.011939,
.011368,.011759,
.012,.011464,
.012571,.011064,
.013064,.010571,
.013464,.01,
.013759,.009368,
.013939,.008695,
.014,.008,
0.0*
%
%ADD85MACRO85*%
%ADD54R,.083X.057*%
%AMMACRO50*
4,1,40,-.0225,.007,
-.022378,.008389,
-.022018,.009736,
-.021428,.011,
-.020628,.012142,
-.019642,.013128,
-.0185,.013928,
-.017236,.014518,
-.015889,.014878,
-.0145,.015,
.0145,.015,
.015889,.014878,
.017236,.014518,
.0185,.013928,
.019642,.013128,
.020628,.012142,
.021428,.011,
.022018,.009736,
.022378,.008389,
.0225,.007,
.0225,-.007,
.022378,-.008389,
.022018,-.009736,
.021428,-.011,
.020628,-.012142,
.019642,-.013128,
.0185,-.013928,
.017236,-.014518,
.015889,-.014878,
.0145,-.015,
-.0145,-.015,
-.015889,-.014878,
-.017236,-.014518,
-.0185,-.013928,
-.019642,-.013128,
-.020628,-.012142,
-.021428,-.011,
-.022018,-.009736,
-.022378,-.008389,
-.0225,-.007,
-.0225,.007,
0.0*
%
%ADD50MACRO50*%
%AMMACRO49*
4,1,40,.007,.0225,
.008389,.022378,
.009736,.022018,
.011,.021428,
.012142,.020628,
.013128,.019642,
.013928,.0185,
.014518,.017236,
.014878,.015889,
.015,.0145,
.015,-.0145,
.014878,-.015889,
.014518,-.017236,
.013928,-.0185,
.013128,-.019642,
.012142,-.020628,
.011,-.021428,
.009736,-.022018,
.008389,-.022378,
.007,-.0225,
-.007,-.0225,
-.008389,-.022378,
-.009736,-.022018,
-.011,-.021428,
-.012142,-.020628,
-.013128,-.019642,
-.013928,-.0185,
-.014518,-.017236,
-.014878,-.015889,
-.015,-.0145,
-.015,.0145,
-.014878,.015889,
-.014518,.017236,
-.013928,.0185,
-.013128,.019642,
-.012142,.020628,
-.011,.021428,
-.009736,.022018,
-.008389,.022378,
-.007,.0225,
.007,.0225,
0.0*
%
%ADD49MACRO49*%
%ADD78R,.272X.272*%
%ADD75R,.246X.246*%
%AMMACRO30*
4,1,40,-.007,-.011,
.007,-.011,
.007695,-.010939,
.008368,-.010759,
.009,-.010464,
.009571,-.010064,
.010064,-.009571,
.010464,-.009,
.010759,-.008368,
.010939,-.007695,
.011,-.007,
.011,.007,
.010939,.007695,
.010759,.008368,
.010464,.009,
.010064,.009571,
.009571,.010064,
.009,.010464,
.008368,.010759,
.007695,.010939,
.007,.011,
-.007,.011,
-.007695,.010939,
-.008368,.010759,
-.009,.010464,
-.009571,.010064,
-.010064,.009571,
-.010464,.009,
-.010759,.008368,
-.010939,.007695,
-.011,.007,
-.011,-.007,
-.010939,-.007695,
-.010759,-.008368,
-.010464,-.009,
-.010064,-.009571,
-.009571,-.010064,
-.009,-.010464,
-.008368,-.010759,
-.007695,-.010939,
-.007,-.011,
0.0*
%
%ADD30MACRO30*%
%AMMACRO22*
4,1,40,.012,-.008,
.012,.008,
.011939,.008695,
.011759,.009368,
.011464,.01,
.011064,.010571,
.010571,.011064,
.01,.011464,
.009368,.011759,
.008695,.011939,
.008,.012,
-.008,.012,
-.008695,.011939,
-.009368,.011759,
-.01,.011464,
-.010571,.011064,
-.011064,.010571,
-.011464,.01,
-.011759,.009368,
-.011939,.008695,
-.012,.008,
-.012,-.008,
-.011939,-.008695,
-.011759,-.009368,
-.011464,-.01,
-.011064,-.010571,
-.010571,-.011064,
-.01,-.011464,
-.009368,-.011759,
-.008695,-.011939,
-.008,-.012,
.008,-.012,
.008695,-.011939,
.009368,-.011759,
.01,-.011464,
.010571,-.011064,
.011064,-.010571,
.011464,-.01,
.011759,-.009368,
.011939,-.008695,
.012,-.008,
0.0*
%
%ADD22MACRO22*%
%AMMACRO20*
4,1,40,-.008,-.012,
.008,-.012,
.008695,-.011939,
.009368,-.011759,
.01,-.011464,
.010571,-.011064,
.011064,-.010571,
.011464,-.01,
.011759,-.009368,
.011939,-.008695,
.012,-.008,
.012,.008,
.011939,.008695,
.011759,.009368,
.011464,.01,
.011064,.010571,
.010571,.011064,
.01,.011464,
.009368,.011759,
.008695,.011939,
.008,.012,
-.008,.012,
-.008695,.011939,
-.009368,.011759,
-.01,.011464,
-.010571,.011064,
-.011064,.010571,
-.011464,.01,
-.011759,.009368,
-.011939,.008695,
-.012,.008,
-.012,-.008,
-.011939,-.008695,
-.011759,-.009368,
-.011464,-.01,
-.011064,-.010571,
-.010571,-.011064,
-.01,-.011464,
-.009368,-.011759,
-.008695,-.011939,
-.008,-.012,
0.0*
%
%ADD20MACRO20*%
%AMMACRO43*
4,1,40,-.011,.007,
-.011,-.007,
-.010939,-.007695,
-.010759,-.008368,
-.010464,-.009,
-.010064,-.009571,
-.009571,-.010064,
-.009,-.010464,
-.008368,-.010759,
-.007695,-.010939,
-.007,-.011,
.007,-.011,
.007695,-.010939,
.008368,-.010759,
.009,-.010464,
.009571,-.010064,
.010064,-.009571,
.010464,-.009,
.010759,-.008368,
.010939,-.007695,
.011,-.007,
.011,.007,
.010939,.007695,
.010759,.008368,
.010464,.009,
.010064,.009571,
.009571,.010064,
.009,.010464,
.008368,.010759,
.007695,.010939,
.007,.011,
-.007,.011,
-.007695,.010939,
-.008368,.010759,
-.009,.010464,
-.009571,.010064,
-.010064,.009571,
-.010464,.009,
-.010759,.008368,
-.010939,.007695,
-.011,.007,
0.0*
%
%ADD43MACRO43*%
%AMMACRO89*
4,1,6,.025,.0135,
.005,-.0065,
.005,-.0135,
-.005,-.0135,
-.005,-.0065,
-.025,.0135,
.025,.0135,
0.0*
%
%ADD89MACRO89*%
%AMMACRO61*
4,1,40,.013,.017,
-.013,.017,
-.013695,.016939,
-.014368,.016759,
-.015,.016464,
-.015571,.016064,
-.016064,.015571,
-.016464,.015,
-.016759,.014368,
-.016939,.013695,
-.017,.013,
-.017,-.013,
-.016939,-.013695,
-.016759,-.014368,
-.016464,-.015,
-.016064,-.015571,
-.015571,-.016064,
-.015,-.016464,
-.014368,-.016759,
-.013695,-.016939,
-.013,-.017,
.013,-.017,
.013695,-.016939,
.014368,-.016759,
.015,-.016464,
.015571,-.016064,
.016064,-.015571,
.016464,-.015,
.016759,-.014368,
.016939,-.013695,
.017,-.013,
.017,.013,
.016939,.013695,
.016759,.014368,
.016464,.015,
.016064,.015571,
.015571,.016064,
.015,.016464,
.014368,.016759,
.013695,.016939,
.013,.017,
0.0*
%
%ADD61MACRO61*%
%AMMACRO37*
4,1,40,.017,-.013,
.017,.013,
.016939,.013695,
.016759,.014368,
.016464,.015,
.016064,.015571,
.015571,.016064,
.015,.016464,
.014368,.016759,
.013695,.016939,
.013,.017,
-.013,.017,
-.013695,.016939,
-.014368,.016759,
-.015,.016464,
-.015571,.016064,
-.016064,.015571,
-.016464,.015,
-.016759,.014368,
-.016939,.013695,
-.017,.013,
-.017,-.013,
-.016939,-.013695,
-.016759,-.014368,
-.016464,-.015,
-.016064,-.015571,
-.015571,-.016064,
-.015,-.016464,
-.014368,-.016759,
-.013695,-.016939,
-.013,-.017,
.013,-.017,
.013695,-.016939,
.014368,-.016759,
.015,-.016464,
.015571,-.016064,
.016064,-.015571,
.016464,-.015,
.016759,-.014368,
.016939,-.013695,
.017,-.013,
0.0*
%
%ADD37MACRO37*%
%AMMACRO31*
4,1,40,-.007,-.011,
.007,-.011,
.007695,-.010939,
.008368,-.010759,
.009,-.010464,
.009571,-.010064,
.010064,-.009571,
.010464,-.009,
.010759,-.008368,
.010939,-.007695,
.011,-.007,
.011,.007,
.010939,.007695,
.010759,.008368,
.010464,.009,
.010064,.009571,
.009571,.010064,
.009,.010464,
.008368,.010759,
.007695,.010939,
.007,.011,
-.007,.011,
-.007695,.010939,
-.008368,.010759,
-.009,.010464,
-.009571,.010064,
-.010064,.009571,
-.010464,.009,
-.010759,.008368,
-.010939,.007695,
-.011,.007,
-.011,-.007,
-.010939,-.007695,
-.010759,-.008368,
-.010464,-.009,
-.010064,-.009571,
-.009571,-.010064,
-.009,-.010464,
-.008368,-.010759,
-.007695,-.010939,
-.007,-.011,
0.0*
%
%ADD31MACRO31*%
%AMMACRO21*
4,1,40,.012,-.008,
.012,.008,
.011939,.008695,
.011759,.009368,
.011464,.01,
.011064,.010571,
.010571,.011064,
.01,.011464,
.009368,.011759,
.008695,.011939,
.008,.012,
-.008,.012,
-.008695,.011939,
-.009368,.011759,
-.01,.011464,
-.010571,.011064,
-.011064,.010571,
-.011464,.01,
-.011759,.009368,
-.011939,.008695,
-.012,.008,
-.012,-.008,
-.011939,-.008695,
-.011759,-.009368,
-.011464,-.01,
-.011064,-.010571,
-.010571,-.011064,
-.01,-.011464,
-.009368,-.011759,
-.008695,-.011939,
-.008,-.012,
.008,-.012,
.008695,-.011939,
.009368,-.011759,
.01,-.011464,
.010571,-.011064,
.011064,-.010571,
.011464,-.01,
.011759,-.009368,
.011939,-.008695,
.012,-.008,
0.0*
%
%ADD21MACRO21*%
%AMMACRO19*
4,1,40,-.008,-.012,
.008,-.012,
.008695,-.011939,
.009368,-.011759,
.01,-.011464,
.010571,-.011064,
.011064,-.010571,
.011464,-.01,
.011759,-.009368,
.011939,-.008695,
.012,-.008,
.012,.008,
.011939,.008695,
.011759,.009368,
.011464,.01,
.011064,.010571,
.010571,.011064,
.01,.011464,
.009368,.011759,
.008695,.011939,
.008,.012,
-.008,.012,
-.008695,.011939,
-.009368,.011759,
-.01,.011464,
-.010571,.011064,
-.011064,.010571,
-.011464,.01,
-.011759,.009368,
-.011939,.008695,
-.012,.008,
-.012,-.008,
-.011939,-.008695,
-.011759,-.009368,
-.011464,-.01,
-.011064,-.010571,
-.010571,-.011064,
-.01,-.011464,
-.009368,-.011759,
-.008695,-.011939,
-.008,-.012,
0.0*
%
%ADD19MACRO19*%
%AMMACRO44*
4,1,40,-.011,.007,
-.011,-.007,
-.010939,-.007695,
-.010759,-.008368,
-.010464,-.009,
-.010064,-.009571,
-.009571,-.010064,
-.009,-.010464,
-.008368,-.010759,
-.007695,-.010939,
-.007,-.011,
.007,-.011,
.007695,-.010939,
.008368,-.010759,
.009,-.010464,
.009571,-.010064,
.010064,-.009571,
.010464,-.009,
.010759,-.008368,
.010939,-.007695,
.011,-.007,
.011,.007,
.010939,.007695,
.010759,.008368,
.010464,.009,
.010064,.009571,
.009571,.010064,
.009,.010464,
.008368,.010759,
.007695,.010939,
.007,.011,
-.007,.011,
-.007695,.010939,
-.008368,.010759,
-.009,.010464,
-.009571,.010064,
-.010064,.009571,
-.010464,.009,
-.010759,.008368,
-.010939,.007695,
-.011,.007,
0.0*
%
%ADD44MACRO44*%
%ADD93C,.012*%
%ADD94C,.03*%
%ADD95C,.014*%
%ADD96C,.015*%
%ADD97C,.016*%
%ADD98C,.006*%
%ADD99C,.00675*%
%ADD100C,.00688*%
%ADD112R,.019X.008*%
%ADD108O,.12702X.08402*%
%ADD101R,.008X.019*%
%ADD109C,.04404*%
%ADD106C,.09204*%
%ADD107C,.09704*%
%ADD105C,.11004*%
%ADD103C,.11104*%
%ADD104O,.315X.4528*%
%ADD102R,.008X.008*%
%ADD113C,.33904*%
%ADD110O,.315X.45279*%
%ADD111R,.29604X.29604*%
G75*
%LPD*%
G75*
G36*
G01X3937Y3004D02*
G02X3004Y3937I0J933D01*
G01Y555652D01*
X8000D01*
Y555500D01*
X27500D01*
X29000Y554000D01*
Y382000D01*
X54000Y357000D01*
Y293417D01*
X53985Y293381D01*
G03Y291717I2039J-832D01*
G01X54000Y291681D01*
Y262500D01*
X52945Y261445D01*
Y97055D01*
X54500Y95500D01*
Y76874D01*
X62023Y69351D01*
Y12977D01*
X62358Y12642D01*
Y12029D01*
X66289Y8098D01*
X66902D01*
X67000Y8000D01*
X119262D01*
Y3004D01*
X3937D01*
G37*
G36*
G01X8000Y965152D02*
X3004D01*
Y1051715D01*
X8000D01*
Y965152D01*
G37*
G36*
G01X35200Y1818500D02*
X35002Y1818698D01*
Y1824302D01*
X35400Y1824700D01*
Y1834100D01*
X37300Y1836000D01*
Y1885800D01*
X39000Y1887500D01*
X43100D01*
X44900Y1885700D01*
Y1875200D01*
X46200Y1873900D01*
Y1820200D01*
X44500Y1818500D01*
X35200D01*
G37*
G36*
G01X14809Y1816096D02*
X4038D01*
X4000Y1816133D01*
Y1817500D01*
X4500Y1818000D01*
X26000D01*
X29500Y1814500D01*
X40000D01*
X41900Y1812600D01*
Y1804500D01*
X40400Y1803000D01*
X25500D01*
X23000Y1800500D01*
X4500D01*
X4000Y1801000D01*
Y1802320D01*
X4025Y1802344D01*
X14797D01*
X15002Y1802549D01*
Y1803305D01*
X14809Y1803498D01*
X4038D01*
X4000Y1803535D01*
Y1805469D01*
X4025Y1805494D01*
X14797D01*
X15002Y1805698D01*
Y1806454D01*
X14809Y1806646D01*
X4038D01*
X4000Y1806684D01*
Y1808619D01*
X4025Y1808644D01*
X14797D01*
X15002Y1808848D01*
Y1809604D01*
X14809Y1809796D01*
X4038D01*
X4000Y1809834D01*
Y1811768D01*
X4025Y1811792D01*
X14797D01*
X15002Y1811997D01*
Y1812753D01*
X14809Y1812946D01*
X4038D01*
X4000Y1812983D01*
Y1814918D01*
X4025Y1814942D01*
X14797D01*
X15002Y1815147D01*
Y1815903D01*
X14809Y1816096D01*
G37*
G36*
G01X33798Y1822400D02*
G03X33800Y1822335I1601J17D01*
G01Y1820565D01*
G03X33798Y1820500I1599J-82D01*
G01Y1818900D01*
G03X33799Y1818883I1597J85D01*
G01Y1818799D01*
X33500Y1818500D01*
X31500D01*
X27700Y1822300D01*
X20217D01*
X17217Y1819300D01*
X4200D01*
X4000Y1819500D01*
Y1821217D01*
X4025Y1821242D01*
X14797D01*
X15002Y1821446D01*
Y1822202D01*
X14809Y1822394D01*
X4038D01*
X4000Y1822432D01*
Y1824367D01*
X4025Y1824392D01*
X14797D01*
X15002Y1824596D01*
Y1825352D01*
X14809Y1825544D01*
X4038D01*
X4000Y1825582D01*
Y1827517D01*
X4025Y1827542D01*
X14797D01*
X15002Y1827746D01*
Y1828502D01*
X14809Y1828694D01*
X4038D01*
X4000Y1828732D01*
Y1830666D01*
X4025Y1830690D01*
X14797D01*
X15002Y1830895D01*
Y1831651D01*
X14809Y1831844D01*
X4038D01*
X4000Y1831881D01*
Y1833816D01*
X4025Y1833840D01*
X14797D01*
X15002Y1834045D01*
Y1834801D01*
X14809Y1834994D01*
X4038D01*
X4000Y1835031D01*
Y1872000D01*
X12938Y1880938D01*
X32027D01*
X32100Y1880865D01*
Y1836200D01*
X33200Y1835100D01*
Y1825000D01*
X33800Y1824400D01*
Y1824065D01*
G03X33798Y1824000I1599J-82D01*
G01Y1822400D01*
G37*
G36*
G01X823705Y1867781D02*
X711752Y1755828D01*
X455028D01*
X445233Y1746033D01*
Y1741981D01*
X447480Y1739734D01*
X461824D01*
X465022Y1742932D01*
Y1747124D01*
X466965Y1749067D01*
X706339D01*
X708327Y1747079D01*
Y1743796D01*
X701346Y1736814D01*
X416086D01*
X386900Y1766000D01*
X367500D01*
X364500Y1769000D01*
Y1790000D01*
X287000Y1867500D01*
X190000D01*
X188000Y1869500D01*
Y1914000D01*
X178500Y1923500D01*
Y1939765D01*
X183266Y1944531D01*
Y1980823D01*
X179963Y1984126D01*
X145494D01*
X141005Y1979637D01*
Y1976594D01*
X139483Y1975072D01*
X128728D01*
X124000Y1979800D01*
X89000D01*
X82200Y1973000D01*
X31733D01*
X31063Y1972330D01*
X30944Y1972373D01*
G03X27999Y1970248I-744J-2073D01*
G02X27471Y1969860I-400J-9D01*
G03X30126Y1967537I-1471J-4360D01*
G02X30441Y1968111I359J176D01*
G03X30527Y1968122I-236J2190D01*
G01X30627Y1968137D01*
X34900Y1963864D01*
Y1956743D01*
X44776Y1946867D01*
Y1895276D01*
X34491Y1884991D01*
X11220D01*
X5890Y1879661D01*
X3004D01*
Y1988189D01*
G02X3937Y1989122I933J0D01*
G01X1033465D01*
G02X1034398Y1988189I0J-933D01*
G01Y1710976D01*
X1031976D01*
X1027500Y1706500D01*
X1015000D01*
X1006000Y1697500D01*
Y1690500D01*
X1001500Y1686000D01*
X936887D01*
X931000Y1691887D01*
Y1752500D01*
X934975Y1756475D01*
Y1785253D01*
X928228Y1792000D01*
X923000D01*
X916500Y1798500D01*
Y1809500D01*
X932000Y1825000D01*
Y1862000D01*
X918000Y1876000D01*
Y1913500D01*
X910500Y1921000D01*
Y1978500D01*
X906000Y1983000D01*
X872500D01*
X868800Y1979300D01*
X816400D01*
X810000Y1972900D01*
X756000D01*
X753700Y1970600D01*
Y1967300D01*
X761300Y1959700D01*
Y1938900D01*
X759400Y1937000D01*
X724900D01*
X722846Y1934946D01*
Y1927884D01*
X726130Y1924600D01*
X821702D01*
X823705Y1922597D01*
Y1867781D01*
G37*
G36*
G01X79000Y19000D02*
X68000Y30000D01*
Y43200D01*
X73300Y48500D01*
X82400D01*
X83300Y47600D01*
Y40700D01*
X87000Y37000D01*
X94700D01*
X99900Y42200D01*
Y43623D01*
X100238Y43960D01*
X107529D01*
X108167Y44598D01*
X108176D01*
X108177Y44600D01*
X112600D01*
X113100Y44100D01*
Y42200D01*
X114100Y41200D01*
X114835D01*
G03X114900Y41198I82J1599D01*
G01X116500D01*
G03X116565Y41200I-17J1601D01*
G01X117900D01*
X121650Y44950D01*
X127250D01*
X128100Y45800D01*
Y51800D01*
X129900Y53600D01*
X158200D01*
X160250Y55650D01*
Y59450D01*
X162200Y61400D01*
X169300D01*
X170000Y60700D01*
Y42293D01*
X169340Y41633D01*
X156833D01*
X155600Y40400D01*
Y33600D01*
X154971Y32971D01*
X146000D01*
X141971Y37000D01*
X126000D01*
X116300Y27300D01*
X112102D01*
Y27302D01*
X98698D01*
Y20498D01*
X97200Y19000D01*
X79000D01*
G37*
G36*
G01X128500Y187000D02*
X105306Y210194D01*
Y221765D01*
X103583Y223488D01*
X101595D01*
X99368Y225715D01*
Y229744D01*
X101325Y231701D01*
Y239820D01*
X101360Y239855D01*
Y246398D01*
X101333Y246425D01*
X95337D01*
X94878Y246884D01*
Y250843D01*
X89562Y256159D01*
X63458D01*
X61500Y258117D01*
Y290620D01*
X62374Y291494D01*
X76506D01*
X109255Y258745D01*
X109266Y258729D01*
G03X110017Y257983I2171J1434D01*
G01X117500Y250500D01*
X129500D01*
X135000Y245000D01*
Y228000D01*
X131500Y224500D01*
Y210000D01*
X137000Y204500D01*
Y190500D01*
X133500Y187000D01*
X128500D01*
G37*
G36*
G01X102000Y203500D02*
X96000D01*
X95145Y204355D01*
Y216145D01*
X95900Y216900D01*
X99800D01*
X102900Y213800D01*
Y204400D01*
X102000Y203500D01*
G37*
G36*
G01X116925Y262500D02*
X68562Y310864D01*
Y339494D01*
X75648D01*
X96642Y318500D01*
X132959D01*
X135780Y315679D01*
Y263595D01*
X134685Y262500D01*
X116925D01*
G37*
G36*
G01X96500Y405000D02*
X95000Y406500D01*
Y413500D01*
X95500Y414000D01*
X109500D01*
X110600Y412900D01*
Y407100D01*
X108500Y405000D01*
X96500D01*
G37*
G36*
G01X59807Y378600D02*
X44700Y393707D01*
Y645112D01*
X45369Y645781D01*
X51812D01*
X52800Y644793D01*
Y397300D01*
X64900Y385200D01*
Y380700D01*
X62800Y378600D01*
X59807D01*
G37*
G36*
G01X94700Y343600D02*
X94200Y344100D01*
Y346100D01*
X94700Y346600D01*
X97200D01*
X97530Y346930D01*
X97550Y346942D01*
G03X98058Y347450I-850J1358D01*
G01X98070Y347470D01*
X98300Y347700D01*
Y348235D01*
G03X98302Y348300I-1599J82D01*
G01Y349700D01*
G03X98300Y349765I-1601J-17D01*
G01Y350700D01*
X99700Y352100D01*
Y357600D01*
X104900Y362800D01*
Y365898D01*
X105540Y366537D01*
Y366539D01*
X110500Y371500D01*
X114800D01*
X115900Y370400D01*
Y368800D01*
X118200Y366500D01*
Y347100D01*
X117200Y346100D01*
X103700D01*
X101200Y343600D01*
X100565D01*
G03X100500Y343602I-82J-1599D01*
G01X98900D01*
G03X98835Y343600I17J-1601D01*
G01X96465D01*
G03X96400Y343602I-82J-1599D01*
G01X95000D01*
G03X94935Y343600I17J-1601D01*
G01X94700D01*
G37*
G36*
G01X79400Y396200D02*
X76004Y399596D01*
Y417504D01*
X79500Y421000D01*
Y424500D01*
X73000Y431000D01*
Y453565D01*
X73454Y454019D01*
X82898D01*
X83500Y453417D01*
Y446000D01*
X84500Y445000D01*
X88500D01*
X96700Y436800D01*
X96701D01*
X96702Y436798D01*
X112555D01*
G03X112645I45J2202D01*
G01X113698D01*
X113699Y436800D01*
X118500D01*
X120500Y434800D01*
Y416400D01*
X119600Y415500D01*
X94500D01*
X93380Y414380D01*
Y397180D01*
X92400Y396200D01*
X79400D01*
G37*
G36*
G01X167666Y415834D02*
X161702Y421799D01*
Y421802D01*
X161698D01*
X161670Y421830D01*
Y424398D01*
X161702D01*
Y430802D01*
X161670D01*
Y434730D01*
X159156Y437244D01*
X132902D01*
X130864Y439282D01*
Y447579D01*
X132676Y449391D01*
X206621D01*
X218661Y437351D01*
X218674Y437329D01*
G03X219506Y436506I1982J1171D01*
G01X221012Y435000D01*
X231000D01*
X233500Y437500D01*
Y443116D01*
X220616Y456000D01*
X123500D01*
X120956Y458544D01*
X111980D01*
X107566Y462958D01*
Y512000D01*
X108573Y513007D01*
X112064D01*
X151071Y474000D01*
X173000D01*
X181000Y482000D01*
X311500D01*
X326500Y467000D01*
Y447000D01*
X306052Y426552D01*
X304148D01*
Y425802D01*
X303200D01*
G03X301844Y425500I1J-3202D01*
G01X297500D01*
X287834Y415834D01*
X167666D01*
G37*
G36*
G01X97200Y438000D02*
X95000Y440200D01*
Y445900D01*
X95900Y446800D01*
X101800D01*
X104100Y444500D01*
X112200D01*
X114000Y442700D01*
Y438800D01*
X113200Y438000D01*
X99265D01*
G03X99200Y438002I-82J-1599D01*
G01X97600D01*
G03X97535Y438000I17J-1601D01*
G01X97200D01*
G37*
G36*
G01X50168Y807500D02*
X67107Y790560D01*
X67940D01*
X73807Y784693D01*
Y749252D01*
X99378Y723681D01*
X129915D01*
X136500Y717096D01*
Y613000D01*
X131000Y607500D01*
X122101D01*
X107196Y622405D01*
Y627704D01*
X103900Y631000D01*
X100381D01*
X99296Y632085D01*
Y636728D01*
X101659Y639091D01*
Y651625D01*
X101342Y651942D01*
X95262D01*
X94958Y652246D01*
Y656134D01*
X89252Y661840D01*
X67527D01*
X60500Y668867D01*
Y776500D01*
X44184Y792816D01*
Y805184D01*
X46500Y807500D01*
X50168D01*
G37*
G36*
G01X60620Y580393D02*
X59244Y581769D01*
Y603638D01*
X60731Y605125D01*
X64208D01*
X66041Y606958D01*
X76276D01*
X81254Y601980D01*
X87602D01*
G03X89400Y601048I1799J1270D01*
G01X91402D01*
X91425Y601043D01*
G03X91800Y600998I377J1557D01*
G01X93200D01*
G03X94626Y601871I0J1601D01*
G01X94682Y601980D01*
X114165D01*
X116810Y599335D01*
Y581663D01*
X115540Y580393D01*
X86264D01*
G02X85946Y581035I0J400D01*
G03X78228I-3859J2941D01*
G02X77910Y580393I-318J-242D01*
G01X60620D01*
G37*
G36*
G01X103500Y604400D02*
X95600D01*
X95116Y604884D01*
Y621301D01*
X95915Y622100D01*
X102200D01*
X105400Y618900D01*
Y606300D01*
X103500Y604400D01*
G37*
G36*
G01X94300Y749100D02*
X94200Y749200D01*
Y751200D01*
X95199Y752199D01*
X95283D01*
G03X95300Y752198I102J1596D01*
G01X96700D01*
G03X96765Y752200I-17J1601D01*
G01X97700D01*
X98300Y752800D01*
Y753735D01*
G03X98302Y753800I-1599J82D01*
G01Y755200D01*
G03X98300Y755265I-1601J-17D01*
G01Y755800D01*
X99700Y757200D01*
Y762700D01*
X102700Y765700D01*
Y766900D01*
X105600Y769800D01*
Y772300D01*
X110300Y777000D01*
X114600D01*
X114960Y776640D01*
Y775340D01*
X116799Y773501D01*
X116803Y773497D01*
G03X116976Y773324I1499J1326D01*
G01X118200Y772100D01*
Y752200D01*
X117200Y751200D01*
X103400D01*
X101300Y749100D01*
X100565D01*
G03X100500Y749102I-82J-1599D01*
G01X98900D01*
G03X98835Y749100I17J-1601D01*
G01X96465D01*
G03X96400Y749102I-82J-1599D01*
G01X95000D01*
G03X94935Y749100I17J-1601D01*
G01X94300D01*
G37*
G36*
G01X97000Y843500D02*
X95000Y845500D01*
Y851700D01*
X95900Y852600D01*
X100600D01*
X103300Y849900D01*
X113400D01*
X114000Y849300D01*
Y844300D01*
X113200Y843500D01*
X99265D01*
G03X99200Y843502I-82J-1599D01*
G01X97600D01*
G03X97535Y843500I17J-1601D01*
G01X97000D01*
G37*
G36*
G01X96100Y810000D02*
X95000Y811100D01*
Y819100D01*
X95600Y819700D01*
X110300D01*
X110900Y819100D01*
Y812200D01*
X108700Y810000D01*
X96100D01*
G37*
G36*
G01X77700Y801900D02*
X76508Y803092D01*
Y823508D01*
X79500Y826500D01*
Y830000D01*
X73000Y836500D01*
Y859155D01*
X73452Y859607D01*
X83072D01*
X83500Y859179D01*
Y851500D01*
X84500Y850500D01*
X87400D01*
X95600Y842300D01*
X96501D01*
X96502Y842298D01*
X113698D01*
X113699Y842300D01*
X118800D01*
X120700Y840400D01*
Y821700D01*
X120000Y821000D01*
X94500D01*
X93500Y820000D01*
Y803000D01*
X92400Y801900D01*
X77700D01*
G37*
G36*
G01X286500Y843000D02*
X143000D01*
X131000Y855000D01*
Y861500D01*
X126000Y866500D01*
X113500D01*
X108000Y872000D01*
Y920694D01*
X110788Y923482D01*
X140587D01*
X156569Y907500D01*
X193000D01*
X202400Y916900D01*
X312942D01*
X332401Y897441D01*
Y882601D01*
X307900Y858100D01*
X301600D01*
X286500Y843000D01*
G37*
G36*
G01X100042Y1067758D02*
X100030Y1067778D01*
G03X99153Y1068647I-2218J-1361D01*
G01X91700Y1076100D01*
X72243D01*
X61100Y1087243D01*
Y1196100D01*
X63500Y1198500D01*
X73100D01*
X76100Y1195500D01*
Y1150922D01*
X97522Y1129500D01*
X126000D01*
X136500Y1119000D01*
Y1038500D01*
X133968Y1035968D01*
X117132D01*
X111050Y1042050D01*
Y1056750D01*
X100042Y1067758D01*
G37*
G36*
G01X95100Y1013678D02*
Y1015735D01*
G03X95102Y1015800I-1599J82D01*
G01Y1017200D01*
G03X95100Y1017265I-1601J-17D01*
G01Y1020235D01*
G03X95102Y1020300I-1599J82D01*
G01Y1021700D01*
G03X95100Y1021765I-1601J-17D01*
G01Y1024723D01*
G03X95102Y1024788I-1599J82D01*
G01Y1026188D01*
G03X95100Y1026253I-1601J-17D01*
G01Y1027300D01*
X95900Y1028100D01*
X100600D01*
X102600Y1026100D01*
Y1012500D01*
X100500Y1010400D01*
X96500D01*
X95302Y1011598D01*
Y1012900D01*
G03X95100Y1013678I-1602J-1D01*
G37*
G36*
G01X94700Y1155000D02*
X94400Y1155300D01*
Y1157100D01*
X94800Y1157500D01*
X96800D01*
X98300Y1159000D01*
Y1159635D01*
G03X98302Y1159700I-1599J82D01*
G01Y1161100D01*
G03X98300Y1161165I-1601J-17D01*
G01Y1162100D01*
X101500Y1165300D01*
Y1168500D01*
X104500Y1171500D01*
Y1176600D01*
X110400Y1182500D01*
X115000D01*
X115800Y1181700D01*
Y1180000D01*
X116799Y1179001D01*
X116803Y1178997D01*
G03X116972Y1178828I1497J1328D01*
G01X116976Y1178824D01*
X118700Y1177100D01*
Y1159200D01*
X116500Y1157000D01*
X103300D01*
X101300Y1155000D01*
X100565D01*
G03X100500Y1155002I-82J-1599D01*
G01X98900D01*
G03X98835Y1155000I17J-1601D01*
G01X96465D01*
G03X96400Y1155002I-82J-1599D01*
G01X95000D01*
G03X94935Y1155000I17J-1601D01*
G01X94700D01*
G37*
G36*
G01X78700Y1207100D02*
X76500Y1209300D01*
Y1229000D01*
X79500Y1232000D01*
Y1235500D01*
X72700Y1242300D01*
Y1263967D01*
X73502Y1264769D01*
X83088D01*
X83500Y1264357D01*
Y1257000D01*
X84500Y1256000D01*
X88200D01*
X96400Y1247800D01*
X96701D01*
X96702Y1247798D01*
X113098D01*
X113099Y1247800D01*
X119600D01*
X120700Y1246700D01*
Y1227500D01*
X120400Y1227200D01*
X94500D01*
X93282Y1225982D01*
Y1208782D01*
X91600Y1207100D01*
X78700D01*
G37*
G36*
G01X278065Y1205365D02*
X174010D01*
X162869Y1216506D01*
Y1250734D01*
X168170Y1256035D01*
X246293D01*
X248500Y1258242D01*
Y1267500D01*
X246239Y1269761D01*
X112128D01*
X107581Y1274308D01*
Y1325659D01*
X109168Y1327246D01*
X115058D01*
X128304Y1314000D01*
X287500D01*
X332500Y1269000D01*
Y1253700D01*
X308000Y1229200D01*
X301900D01*
X278065Y1205365D01*
G37*
G36*
G01X113982Y1254318D02*
G03X114000Y1254283I2323J1172D01*
G01Y1250400D01*
X112600Y1249000D01*
X99265D01*
G03X99200Y1249002I-82J-1599D01*
G01X97600D01*
G03X97535Y1249000I17J-1601D01*
G01X97200D01*
X95000Y1251200D01*
Y1256500D01*
X96400Y1257900D01*
X100900D01*
X103500Y1255300D01*
X113000D01*
X113982Y1254318D01*
G37*
G36*
G01X109000Y1215800D02*
X96600D01*
X94700Y1217700D01*
Y1225200D01*
X95400Y1225900D01*
X110200D01*
X111300Y1224800D01*
Y1218100D01*
X109000Y1215800D01*
G37*
G36*
G01X125328Y1350553D02*
X123000Y1352881D01*
Y1382000D01*
X112500Y1392500D01*
X97100D01*
X93000Y1396600D01*
Y1409600D01*
X93900Y1410500D01*
X99199D01*
X104300Y1415601D01*
Y1433854D01*
X105272Y1434826D01*
Y1438214D01*
X103982Y1439504D01*
X101535D01*
X99299Y1441740D01*
Y1446134D01*
X101705Y1448540D01*
Y1462612D01*
X101358Y1462959D01*
X101133D01*
Y1462960D01*
X95603D01*
X95381Y1463182D01*
Y1467993D01*
X95791Y1468403D01*
X104675D01*
X111368Y1461710D01*
X125290D01*
X132500Y1454500D01*
Y1420500D01*
X157000Y1396000D01*
Y1384764D01*
X155911Y1383675D01*
X138186D01*
X133635Y1379124D01*
Y1361770D01*
X139932Y1355473D01*
Y1352617D01*
X137868Y1350553D01*
X125328D01*
G37*
G36*
G01X99000Y1418500D02*
X97700Y1419800D01*
X96965D01*
G03X96900Y1419802I-82J-1599D01*
G01X95599D01*
X95200Y1420200D01*
Y1433200D01*
X95600Y1433600D01*
X99300D01*
X101000Y1431900D01*
Y1419200D01*
X100300Y1418500D01*
X99000D01*
G37*
G36*
G01X93270Y1479185D02*
X70067D01*
X66650Y1475768D01*
X61796D01*
X59647Y1477917D01*
Y1582702D01*
X85356Y1608411D01*
X157022D01*
X164111Y1615500D01*
X171000D01*
X177000Y1609500D01*
Y1597500D01*
X173500Y1594000D01*
X77980D01*
X72822Y1588842D01*
Y1566274D01*
X78122Y1560974D01*
Y1497378D01*
X94027Y1481473D01*
Y1479942D01*
X93270Y1479185D01*
G37*
G36*
G01X116559Y1502012D02*
X91391D01*
X88500Y1504903D01*
Y1538500D01*
X93500Y1543500D01*
X99099D01*
X115215Y1527384D01*
X119927D01*
X124803Y1522508D01*
Y1510256D01*
X116559Y1502012D01*
G37*
G36*
G01X102000Y1553577D02*
X101360Y1552938D01*
Y1552460D01*
X100000Y1551100D01*
X99865D01*
G03X99800Y1551102I-82J-1599D01*
G01X98200D01*
G03X98135Y1551100I17J-1601D01*
G01X95765D01*
G03X95700Y1551102I-82J-1599D01*
G01X94300D01*
G03X94235Y1551100I17J-1601D01*
G01X93900D01*
X93500Y1551500D01*
Y1553000D01*
X94000Y1553500D01*
X96500D01*
X97600Y1554600D01*
Y1555735D01*
G03X97602Y1555800I-1599J82D01*
G01Y1557200D01*
G03X97600Y1557265I-1601J-17D01*
G01Y1560670D01*
X97609Y1560699D01*
G03X97702Y1561300I-1909J603D01*
G01Y1563202D01*
X102000Y1567500D01*
Y1574160D01*
X100414Y1575746D01*
Y1578406D01*
X100389Y1578431D01*
Y1581711D01*
X101103Y1582425D01*
X102260D01*
G03X102325Y1582424I57J1600D01*
G01X103725D01*
G03X103790Y1582425I8J1601D01*
G01X104714D01*
X105586Y1581553D01*
Y1579291D01*
X106789Y1578088D01*
X115712D01*
X116300Y1577500D01*
Y1558400D01*
X115100Y1557200D01*
X102900D01*
X102252Y1556552D01*
X102248D01*
Y1556548D01*
X102000Y1556300D01*
Y1553577D01*
G37*
G36*
G01X96700Y1621300D02*
X95000Y1623000D01*
Y1630000D01*
X95500Y1630500D01*
X109700D01*
X110700Y1629500D01*
Y1623200D01*
X108800Y1621300D01*
X96700D01*
G37*
G36*
G01X76000Y1613000D02*
X74000Y1615000D01*
Y1632000D01*
X79500Y1637500D01*
Y1641000D01*
X73000Y1647500D01*
Y1669573D01*
X73507Y1670080D01*
X83483D01*
X83900Y1669663D01*
Y1662100D01*
X84500Y1661500D01*
X89000D01*
X96800Y1653700D01*
X96901D01*
X96902Y1653698D01*
X113598D01*
X113599Y1653700D01*
X113800D01*
X115100Y1652400D01*
X116922D01*
G03X117078I78J2200D01*
G01X120900D01*
X121800Y1651500D01*
Y1632600D01*
X121200Y1632000D01*
X94500D01*
X93500Y1631000D01*
Y1616500D01*
X90000Y1613000D01*
X76000D01*
G37*
G36*
G01X98100Y1654902D02*
G03X98035Y1654900I17J-1601D01*
G01X97400D01*
X95000Y1657300D01*
Y1663100D01*
X95500Y1663600D01*
X101900D01*
X104600Y1660900D01*
X113700D01*
X114400Y1660200D01*
Y1656200D01*
X113100Y1654900D01*
X99765D01*
G03X99700Y1654902I-82J-1599D01*
G01X98100D01*
G37*
G36*
G01X109000Y1896700D02*
X107300Y1895000D01*
X59500D01*
X56000Y1898500D01*
Y1928000D01*
X57902Y1929902D01*
X108524D01*
X109000Y1929426D01*
Y1896700D01*
G37*
G36*
G01X68100Y1941269D02*
Y1944670D01*
X68109Y1944699D01*
G03X68202Y1945300I-1909J603D01*
G01Y1947202D01*
X72072Y1951072D01*
Y1952672D01*
G03X72076Y1952800I-1997J126D01*
G01Y1955700D01*
G03X72072Y1955828I-2001J2D01*
G01Y1958163D01*
X72909Y1959000D01*
X80900D01*
X83344Y1956556D01*
X86744D01*
X88700Y1954600D01*
Y1939700D01*
X85800Y1936800D01*
X74377D01*
X72677Y1935100D01*
X70365D01*
G03X70300Y1935102I-82J-1599D01*
G01X68700D01*
G03X68635Y1935100I17J-1601D01*
G01X66265D01*
G03X66200Y1935102I-82J-1599D01*
G01X64800D01*
G03X64735Y1935100I17J-1601D01*
G01X64400D01*
X64000Y1935500D01*
Y1937000D01*
X64500Y1937500D01*
X67000D01*
X68100Y1938600D01*
Y1939735D01*
G03X68102Y1939800I-1599J82D01*
G01Y1941200D01*
G03X68100Y1941265I-1601J-17D01*
G01Y1941269D01*
G37*
G36*
G01X111023Y1934595D02*
X109186Y1932758D01*
Y1932756D01*
X108230Y1931800D01*
X95900D01*
X94000Y1933700D01*
Y1954300D01*
X92700Y1955600D01*
Y1961700D01*
X94500Y1963500D01*
X121000D01*
X121600Y1964100D01*
Y1972500D01*
X122700Y1973600D01*
X137842D01*
X139607Y1971835D01*
Y1958793D01*
X140200Y1958200D01*
X146600D01*
X146898Y1958498D01*
X146902D01*
Y1958502D01*
X147400Y1959000D01*
Y1972061D01*
X147839Y1972500D01*
X165500D01*
X173500Y1964500D01*
Y1944089D01*
X173042Y1943631D01*
X160508D01*
X160000Y1944139D01*
Y1952400D01*
X159100Y1953300D01*
X149500D01*
X147200Y1951000D01*
X139500D01*
X137200Y1953300D01*
X136999D01*
X136998Y1953302D01*
X129002D01*
X129001Y1953300D01*
X121786D01*
X111023Y1942537D01*
Y1934595D01*
G37*
G36*
G01X92400Y1965200D02*
X91800Y1965800D01*
Y1973300D01*
X93698Y1975198D01*
X119102D01*
X120300Y1974000D01*
Y1965900D01*
X119600Y1965200D01*
X92400D01*
G37*
G36*
G01X148780Y6660D02*
X156620Y14500D01*
X210407D01*
X228000Y32093D01*
Y69500D01*
X224000Y73500D01*
X216000D01*
X205800Y63300D01*
X161600D01*
X158900Y60600D01*
Y57700D01*
X156200Y55000D01*
X128500D01*
X126200Y57300D01*
Y72700D01*
X145000Y91500D01*
X240000D01*
X331500Y183000D01*
X341000D01*
X345000Y179000D01*
Y82000D01*
X340500Y77500D01*
Y65201D01*
X355101Y50600D01*
X367583D01*
X393850Y76867D01*
Y114650D01*
X358000Y150500D01*
Y199500D01*
X445086Y286586D01*
Y301865D01*
X422067Y324884D01*
Y481866D01*
X351000Y552933D01*
Y724500D01*
X288000Y787500D01*
Y809500D01*
X292472Y813972D01*
X315028D01*
X325000Y804000D01*
X331000D01*
X331898Y803102D01*
Y802300D01*
G03X331900Y802235I1601J17D01*
G01Y801300D01*
X333700Y799500D01*
X359000D01*
X360900Y801400D01*
X361135D01*
G03X361200Y801398I82J1599D01*
G01X362800D01*
G03X362865Y801400I-17J1601D01*
G01X364635D01*
G03X364700Y801398I82J1599D01*
G01X366300D01*
G03X366365Y801400I-17J1601D01*
G01X366800D01*
X367200Y801000D01*
Y798465D01*
G03X367198Y798400I1599J-82D01*
G01Y797000D01*
G03X367200Y796935I1601J17D01*
G01Y795200D01*
X365500Y793500D01*
Y676441D01*
X832472Y209469D01*
Y204280D01*
X832464Y204253D01*
G03X832398Y203800I1536J-455D01*
G01Y202648D01*
X829826Y200075D01*
X817022D01*
X813847Y203250D01*
X792895D01*
X788000Y198355D01*
Y188464D01*
X790568Y185896D01*
X801467D01*
X810038Y177325D01*
Y172662D01*
X810100Y172600D01*
Y169100D01*
X813900Y165300D01*
X826100D01*
X847900Y143500D01*
X848000D01*
X860189Y131311D01*
X904250D01*
X905110Y130450D01*
X906296D01*
X909245Y127501D01*
X930197D01*
X935064Y132368D01*
Y168436D01*
X933500Y170000D01*
Y238000D01*
X917000Y254500D01*
Y324653D01*
X918102Y325754D01*
Y367213D01*
G03X917000Y370958I-2202J1387D01*
G01Y372500D01*
X908400Y381100D01*
X877200D01*
X871400Y386900D01*
X854500D01*
X850244Y382644D01*
X806731D01*
X803918Y379831D01*
Y329094D01*
X800950Y326126D01*
X770218D01*
X560997Y535347D01*
X550812D01*
X549670Y534205D01*
Y525110D01*
X554176Y520604D01*
X567728D01*
X767459Y320872D01*
X767628D01*
X773081Y315420D01*
X861996D01*
X864535Y312881D01*
Y212773D01*
X863160Y211398D01*
X860515D01*
X853032Y218880D01*
Y219063D01*
X850668Y221428D01*
X850484D01*
X849402Y222510D01*
Y222694D01*
X847037Y225058D01*
X846854D01*
X845772Y226140D01*
Y226324D01*
X843407Y228688D01*
X843224D01*
X836530Y235382D01*
Y235566D01*
X834165Y237930D01*
X833982D01*
X832900Y239014D01*
Y239196D01*
X830535Y241560D01*
X830352D01*
X493675Y578238D01*
Y586759D01*
X494950Y588034D01*
X873466D01*
X881600Y579900D01*
Y573200D01*
X880000Y571600D01*
X869500D01*
X865800Y567900D01*
Y561600D01*
X862900Y558700D01*
X854600D01*
X847500Y551600D01*
Y542500D01*
X844000Y539000D01*
X660180D01*
X659071Y537891D01*
Y532059D01*
X659867Y531263D01*
X930763D01*
X937659Y538159D01*
Y550740D01*
X931000Y557399D01*
Y572671D01*
X927441Y576230D01*
X922907D01*
X922514Y576624D01*
X916174D01*
X910394Y582404D01*
Y595490D01*
X931000Y616096D01*
Y647500D01*
X919000Y659500D01*
Y695559D01*
X918200Y696359D01*
Y773595D01*
G03X918214Y775570I-2400J1005D01*
G01X918200Y775606D01*
Y775928D01*
X906728Y787400D01*
X876500D01*
X871000Y792900D01*
X852926D01*
X848300Y788274D01*
X807980D01*
X806202Y790052D01*
Y800826D01*
X777226Y829802D01*
X662000D01*
G03Y823398I0J-3202D01*
G01X774574D01*
X799798Y798174D01*
Y781674D01*
X799800Y781672D01*
Y781323D01*
X806500Y774623D01*
Y718853D01*
X708889Y621242D01*
X522118D01*
G02X521828Y621917I0J400D01*
G03X518445Y625040I-1672J1583D01*
G01X517531D01*
X516406Y623915D01*
X515282Y625040D01*
X514367D01*
G03X513272Y621282I-1711J-1540D01*
G02X513780Y620897I108J-385D01*
G01Y619546D01*
X517337Y615988D01*
X711066D01*
X817277Y722200D01*
X848800D01*
X856500Y714500D01*
Y660500D01*
X855000Y659000D01*
Y651202D01*
X782500D01*
G03Y644798I0J-3202D01*
G01X855000D01*
Y632373D01*
X837332Y614704D01*
X497796D01*
X459500Y653000D01*
Y820500D01*
X448500Y831500D01*
X423000D01*
X415500Y839000D01*
Y858680D01*
X401000Y873180D01*
Y897000D01*
X336598Y961402D01*
X263598D01*
X204000Y1021000D01*
Y1050000D01*
X190500Y1063500D01*
Y1099591D01*
X176292Y1113799D01*
Y1126792D01*
X190700Y1141200D01*
Y1188100D01*
X194600Y1192000D01*
X254940D01*
X266322Y1180618D01*
X278818D01*
X280000Y1181800D01*
Y1185795D01*
X274133Y1191662D01*
Y1198985D01*
X275648Y1200500D01*
X295137D01*
X300472Y1195165D01*
X306364D01*
X306600Y1194929D01*
Y1192000D01*
X307900Y1190700D01*
X314518D01*
X315935Y1189283D01*
Y1185965D01*
X326287Y1175613D01*
X331009D01*
X331898Y1174724D01*
Y1173800D01*
G03X331900Y1173735I1601J17D01*
G01Y1172900D01*
X332600Y1172200D01*
X333435D01*
G03X333500Y1172198I82J1599D01*
G01X334900D01*
G03X334965Y1172200I-17J1601D01*
G01X372500D01*
X373000Y1171700D01*
Y1166500D01*
X371000Y1164500D01*
Y1115800D01*
X488500Y998300D01*
X868375D01*
X876282Y990393D01*
Y982194D01*
X852843Y958755D01*
Y946664D01*
X849996Y943817D01*
X662317D01*
X658377Y939877D01*
Y932005D01*
X660256Y930126D01*
X850119D01*
X858375Y938382D01*
X928583D01*
X935376Y945175D01*
Y973349D01*
X927323Y981402D01*
X913281D01*
X909656Y985027D01*
Y996935D01*
X930500Y1017779D01*
Y1057472D01*
X919052Y1068920D01*
Y1107041D01*
X916606Y1109487D01*
Y1140884D01*
X921733Y1146011D01*
Y1190622D01*
X918382Y1193973D01*
X869400D01*
X866073Y1197300D01*
X854427D01*
X851100Y1193973D01*
X660973D01*
X655500Y1188500D01*
Y1181000D01*
X658000Y1178500D01*
X800000D01*
X804000Y1174500D01*
Y1145000D01*
X801500Y1142500D01*
X407800D01*
X402200Y1148100D01*
Y1183700D01*
X419500Y1201000D01*
X511646D01*
X638830Y1328184D01*
X846634D01*
X860713Y1342263D01*
X928263D01*
X935495Y1349495D01*
Y1379998D01*
X928493Y1387000D01*
X919000D01*
X914500Y1391500D01*
Y1405500D01*
X926000Y1417000D01*
X986600D01*
X988000Y1418400D01*
X993300D01*
X993598Y1418698D01*
X996198D01*
X996199Y1418700D01*
X1003800D01*
X1023500Y1399000D01*
X1029402D01*
Y1399276D01*
X1034398D01*
Y3937D01*
G02X1033465Y3004I-933J0D01*
G01X148780D01*
Y6660D01*
G37*
G36*
G01X116141Y15355D02*
Y17685D01*
G02X151575I17717J46D01*
G01Y15355D01*
X141733D01*
Y17700D01*
G03X125983I-7875J32D01*
G01Y15355D01*
X116141D01*
G37*
G36*
G01X179538Y29900D02*
X178481Y30957D01*
Y32787D01*
X175900Y35368D01*
Y54600D01*
X176800Y55500D01*
X189000D01*
X191400Y57900D01*
X192135D01*
G03X192200Y57898I82J1599D01*
G01X193800D01*
G03X193865Y57900I-17J1601D01*
G01X196235D01*
G03X196300Y57898I82J1599D01*
G01X197700D01*
G03X197765Y57900I-17J1601D01*
G01X198100D01*
X198500Y57500D01*
Y55500D01*
X198000Y55000D01*
X195500D01*
X194400Y53900D01*
Y53265D01*
G03X194398Y53200I1599J-82D01*
G01Y51800D01*
G03X194400Y51735I1601J17D01*
G01Y50900D01*
X193000Y49500D01*
Y44000D01*
X188900Y39900D01*
Y34900D01*
X183900Y29900D01*
X181954D01*
X181930Y29906D01*
G03X181550Y29952I-381J-1556D01*
G01X180150D01*
G03X179770Y29906I1J-1602D01*
G01X179746Y29900D01*
X179538D01*
G37*
G36*
G01X188602Y324493D02*
Y366913D01*
G03X188274Y370105I-2202J1387D01*
G01X188138Y370246D01*
X189421Y371529D01*
X251796D01*
X258863Y378596D01*
X293866D01*
X297376Y382106D01*
Y393176D01*
X298415Y394215D01*
X306185D01*
X306700Y393700D01*
Y391100D01*
X307200Y390600D01*
X314667D01*
X315967Y389300D01*
Y384273D01*
X326030Y374210D01*
X331497D01*
X331863Y373844D01*
Y370207D01*
X335068Y367002D01*
Y289568D01*
X290000Y244500D01*
X203000D01*
X191000Y256500D01*
Y290187D01*
X178584Y302603D01*
Y314102D01*
X187899Y323417D01*
Y323791D01*
X188602Y324493D01*
G37*
G36*
G01X142500Y328400D02*
X139700Y331200D01*
X131100D01*
X130000Y332300D01*
Y336600D01*
X131200Y337800D01*
X144835D01*
G03X144900Y337798I82J1599D01*
G01X146500D01*
G03X146565Y337800I-17J1601D01*
G01X147200D01*
X149000Y336000D01*
Y329200D01*
X148200Y328400D01*
X142500D01*
G37*
G36*
G01X160808Y321705D02*
X160300Y322213D01*
Y329700D01*
X159500Y330500D01*
X159283D01*
Y330508D01*
X156392D01*
X147900Y339000D01*
X147699D01*
X147698Y339002D01*
X130702D01*
X130701Y339000D01*
X129500D01*
X127900Y340600D01*
X123600D01*
X123300Y340900D01*
Y358400D01*
X124500Y359600D01*
X149100D01*
X150500Y361000D01*
Y376600D01*
X153000Y379100D01*
X165300D01*
X170000Y374400D01*
Y360000D01*
X164500Y354500D01*
Y351000D01*
X171000Y344500D01*
Y322688D01*
X170017Y321705D01*
X160808D01*
G37*
G36*
G01X134100Y361000D02*
X133200Y361900D01*
Y370500D01*
X133900Y371200D01*
X148400D01*
X149000Y370600D01*
Y362000D01*
X148000Y361000D01*
X134100D01*
G37*
G36*
G01X128400Y403600D02*
X127700Y404300D01*
Y406600D01*
X125700Y408600D01*
Y428800D01*
X126600Y429700D01*
X140700D01*
X143000Y432000D01*
X143535D01*
G03X143600Y431998I82J1599D01*
G01X145200D01*
G03X145265Y432000I-17J1601D01*
G01X147635D01*
G03X147700Y431998I82J1599D01*
G01X149100D01*
G03X149165Y432000I-17J1601D01*
G01X149900D01*
X150200Y431700D01*
Y429700D01*
X149700Y429200D01*
X147000D01*
X145800Y428000D01*
Y427365D01*
G03X145798Y427300I1599J-82D01*
G01Y425900D01*
G03X145800Y425835I1601J17D01*
G01Y424800D01*
X144700Y423700D01*
Y418200D01*
X138100Y411600D01*
Y410402D01*
X138086Y410388D01*
Y408586D01*
X133100Y403600D01*
X128400D01*
G37*
G36*
G01X271134Y502344D02*
X168583D01*
X146167Y524760D01*
Y531060D01*
X147846Y532739D01*
X164949D01*
X173688Y524000D01*
X206000D01*
X209178Y527178D01*
Y549482D01*
X220091Y560395D01*
X224761D01*
X273281Y511875D01*
Y504491D01*
X271134Y502344D01*
G37*
G36*
G01X148300Y766100D02*
X134900D01*
X133300Y767700D01*
Y774800D01*
X135100Y776600D01*
X148000D01*
X149600Y775000D01*
Y767400D01*
X148300Y766100D01*
G37*
G36*
G01X143000Y734000D02*
X140300Y736700D01*
X131200D01*
X130000Y737900D01*
Y742300D01*
X131200Y743500D01*
X144935D01*
G03X145000Y743498I82J1599D01*
G01X146600D01*
G03X146665Y743500I-17J1601D01*
G01X147400D01*
X149100Y741800D01*
Y734400D01*
X148700Y734000D01*
X143000D01*
G37*
G36*
G01X160912Y727271D02*
X160500Y727683D01*
Y735000D01*
X159500Y736000D01*
X159283D01*
Y736020D01*
X156780D01*
X148100Y744700D01*
X147899D01*
X147898Y744702D01*
X130702D01*
X130701Y744700D01*
X125400D01*
X123700Y746400D01*
Y764300D01*
X124200Y764800D01*
X148800D01*
X150900Y766900D01*
Y784400D01*
X151600Y785100D01*
X168500D01*
X170000Y783600D01*
Y765500D01*
X164500Y760000D01*
Y756500D01*
X171000Y750000D01*
Y727714D01*
X170557Y727271D01*
X160912D01*
G37*
G36*
G01X129200Y809500D02*
X128000Y810700D01*
Y812400D01*
X126000Y814400D01*
Y834500D01*
X127000Y835500D01*
X140900D01*
X142900Y837500D01*
X143535D01*
G03X143600Y837498I82J1599D01*
G01X145200D01*
G03X145265Y837500I-17J1601D01*
G01X147635D01*
G03X147700Y837498I82J1599D01*
G01X149100D01*
G03X149165Y837500I-17J1601D01*
G01X149500D01*
X150000Y837000D01*
Y835500D01*
X149000Y834500D01*
X146500D01*
X145800Y833800D01*
Y832865D01*
G03X145798Y832800I1599J-82D01*
G01Y831400D01*
G03X145800Y831335I1601J17D01*
G01Y830800D01*
X144500Y829500D01*
Y824000D01*
X138400Y817900D01*
Y814300D01*
X133600Y809500D01*
X129200D01*
G37*
G36*
G01X160537Y1133152D02*
X160300Y1133389D01*
Y1140700D01*
X159482Y1141518D01*
Y1141532D01*
X159468D01*
X159400Y1141600D01*
X157200D01*
X149600Y1149200D01*
X148499D01*
X148498Y1149202D01*
X130602D01*
X130601Y1149200D01*
X125500D01*
X124094Y1150606D01*
X124089Y1150612D01*
G03X123812Y1150889I-1689J-1412D01*
G01X123806Y1150894D01*
X122400Y1152300D01*
Y1168900D01*
X124500Y1171000D01*
X150800D01*
X151800Y1172000D01*
Y1172201D01*
X151802Y1172202D01*
Y1180598D01*
X151800Y1180599D01*
Y1190700D01*
X152400Y1191300D01*
X168200D01*
X170000Y1189500D01*
Y1171000D01*
X164500Y1165500D01*
Y1162000D01*
X171000Y1155500D01*
Y1133755D01*
X170397Y1133152D01*
X160537D01*
G37*
G36*
G01X130760Y1142240D02*
X130066Y1142934D01*
X130055Y1142994D01*
G03X130007Y1143196I-2554J-500D01*
G01X130000Y1143222D01*
Y1146900D01*
X131100Y1148000D01*
X144935D01*
G03X145000Y1147998I82J1599D01*
G01X146600D01*
G03X146665Y1148000I-17J1601D01*
G01X148000D01*
X149000Y1147000D01*
Y1140400D01*
X148200Y1139600D01*
X141900D01*
X139300Y1142200D01*
X138477D01*
X138438Y1142240D01*
X130760D01*
G37*
G36*
G01X134700Y1172300D02*
X134000Y1173000D01*
Y1180000D01*
X135500Y1181500D01*
X149200D01*
X150600Y1180100D01*
Y1172700D01*
X150200Y1172300D01*
X134700D01*
G37*
G36*
G01X128900Y1215000D02*
X127950Y1215950D01*
Y1217950D01*
X125600Y1220300D01*
Y1239200D01*
X127400Y1241000D01*
X140900D01*
X141548Y1241648D01*
X141652D01*
Y1241752D01*
X142900Y1243000D01*
X143835D01*
G03X143900Y1242998I82J1599D01*
G01X145500D01*
G03X145565Y1243000I-17J1601D01*
G01X147935D01*
G03X148000Y1242998I82J1599D01*
G01X149400D01*
G03X149465Y1243000I-17J1601D01*
G01X149900D01*
X150400Y1242500D01*
Y1241000D01*
X149400Y1240000D01*
X146900D01*
X146100Y1239200D01*
Y1238365D01*
G03X146098Y1238300I1599J-82D01*
G01Y1236900D01*
G03X146100Y1236835I1601J17D01*
G01Y1236200D01*
X144900Y1235000D01*
Y1229500D01*
X138400Y1223000D01*
Y1219900D01*
X133500Y1215000D01*
X128900D01*
G37*
G36*
G01X192452Y1385859D02*
X189245Y1389066D01*
X178717D01*
Y1408792D01*
X180530Y1410605D01*
X189205D01*
X252533Y1347277D01*
X283925D01*
X288987Y1342215D01*
Y1337114D01*
X286538Y1334665D01*
X160135D01*
X157200Y1337600D01*
Y1349395D01*
X159705Y1351900D01*
X165199D01*
X165522Y1351577D01*
Y1349478D01*
X167567Y1347433D01*
X175167D01*
X179676Y1342924D01*
X202457D01*
X204946Y1345413D01*
Y1358658D01*
X195899Y1367705D01*
Y1382618D01*
X192946Y1385571D01*
X192452D01*
Y1385859D01*
G37*
G36*
G01X431500Y1238000D02*
X303000Y1366500D01*
X265000D01*
X206000Y1425500D01*
Y1452000D01*
X189000Y1469000D01*
Y1509500D01*
X185500Y1513000D01*
Y1513322D01*
X173764Y1525058D01*
X173777Y1525157D01*
G03X172298Y1527540I-2182J296D01*
G01X172162Y1527586D01*
Y1531263D01*
X174892Y1533993D01*
X174893D01*
X188800Y1547900D01*
Y1548087D01*
X188902Y1548188D01*
Y1584313D01*
G03X188836Y1587186I-2202J1387D01*
G01X188800Y1587238D01*
Y1588300D01*
X192150Y1591650D01*
X196350D01*
X210000Y1578000D01*
Y1456000D01*
X212000Y1454000D01*
X217100D01*
X218879Y1455779D01*
Y1581621D01*
X163700Y1636800D01*
Y1650800D01*
X159500Y1655000D01*
X141000D01*
X134500Y1661500D01*
Y1672500D01*
X131000Y1676000D01*
X120000D01*
X113000Y1683000D01*
Y1702000D01*
X115500Y1704500D01*
X121500D01*
X203200Y1622800D01*
X356800D01*
X366500Y1632500D01*
Y1669000D01*
X368700Y1671200D01*
X377800D01*
X378400Y1670600D01*
X392600D01*
X395500Y1673500D01*
Y1683500D01*
X413000Y1701000D01*
X445676D01*
X452796Y1708120D01*
X707120D01*
X757500Y1758500D01*
X795500D01*
X801500Y1752500D01*
Y1736000D01*
X797500Y1732000D01*
X778500D01*
X741500Y1695000D01*
Y1659500D01*
X732500Y1650500D01*
X455000D01*
X444000Y1661500D01*
Y1669000D01*
X441000Y1672000D01*
X429500D01*
X427000Y1669500D01*
Y1662000D01*
X448000Y1641000D01*
X959000D01*
X991500Y1608500D01*
X1018000D01*
X1020000Y1606500D01*
Y1514500D01*
X1019200Y1513700D01*
X980700D01*
X980000Y1514400D01*
X922100D01*
X916226Y1520274D01*
Y1539426D01*
X922000Y1545200D01*
Y1585700D01*
X914200Y1593500D01*
X883312D01*
X877695Y1599117D01*
X877683D01*
X872800Y1604000D01*
X854800D01*
X849917Y1599117D01*
X809080D01*
X804101Y1594138D01*
Y1552275D01*
X799826Y1548000D01*
X456300D01*
X364800Y1456500D01*
X282000D01*
X267500Y1442000D01*
Y1396300D01*
X286100Y1377700D01*
X304300D01*
X313192Y1386592D01*
X320769D01*
X322346Y1388169D01*
Y1395746D01*
X334800Y1408200D01*
X361500D01*
X364500Y1411200D01*
Y1438500D01*
X459000Y1533000D01*
X857500D01*
X864500Y1526000D01*
Y1473500D01*
X856379Y1465379D01*
X661061D01*
X657500Y1461818D01*
Y1456000D01*
X662000Y1451500D01*
X853000D01*
X856500Y1448000D01*
Y1434500D01*
X850500Y1428500D01*
X695000D01*
X504500Y1238000D01*
X431500D01*
G37*
G36*
G01X146600Y1551698D02*
G03X146665Y1551700I-17J1601D01*
G01X147000D01*
X149000Y1549700D01*
Y1546100D01*
X148000Y1545100D01*
X142300D01*
X139800Y1547600D01*
X130100D01*
X129500Y1548200D01*
Y1549900D01*
X133600Y1554000D01*
X141900D01*
X144200Y1551700D01*
X144935D01*
G03X145000Y1551698I82J1599D01*
G01X146600D01*
G37*
G36*
G01X160607Y1538148D02*
X160100Y1538655D01*
Y1546400D01*
X159482Y1547018D01*
Y1547044D01*
X159456D01*
X158100Y1548400D01*
X152000D01*
X147500Y1552900D01*
X147499D01*
X147498Y1552902D01*
X144798D01*
X143300Y1554400D01*
Y1554900D01*
X142900Y1555300D01*
X132500D01*
X129300Y1552100D01*
X123500D01*
X122500Y1553100D01*
Y1572500D01*
X126500Y1576500D01*
X134301D01*
X134302Y1576498D01*
X149498D01*
X149499Y1576500D01*
X149500D01*
X151300Y1578300D01*
Y1578301D01*
X151302Y1578302D01*
Y1586898D01*
X151300Y1586899D01*
Y1591500D01*
X152200Y1592400D01*
X169100D01*
X170000Y1591500D01*
Y1576500D01*
X164500Y1571000D01*
Y1567500D01*
X171000Y1561000D01*
Y1538655D01*
X170493Y1538148D01*
X160607D01*
G37*
G36*
G01X149000Y1577700D02*
X134800D01*
X134000Y1578500D01*
Y1585500D01*
X136500Y1588000D01*
X148487D01*
X148888Y1587598D01*
X148902D01*
X150100Y1586400D01*
Y1578800D01*
X149000Y1577700D01*
G37*
G36*
G01X129000Y1621500D02*
X128200Y1622300D01*
Y1623100D01*
X125800Y1625500D01*
Y1643300D01*
X128600Y1646100D01*
X141900D01*
X144300Y1648500D01*
X145035D01*
G03X145100Y1648498I82J1599D01*
G01X146700D01*
G03X146765Y1648500I-17J1601D01*
G01X149135D01*
G03X149200Y1648498I82J1599D01*
G01X150600D01*
G03X150665Y1648500I-17J1601D01*
G01X151000D01*
X151400Y1648100D01*
Y1646100D01*
X150900Y1645600D01*
X148400D01*
X147300Y1644500D01*
Y1643865D01*
G03X147298Y1643800I1599J-82D01*
G01Y1642400D01*
G03X147300Y1642335I1601J17D01*
G01Y1641500D01*
X145900Y1640100D01*
Y1634700D01*
X142090Y1630890D01*
X142087D01*
X138460Y1627263D01*
Y1627260D01*
X138300Y1627100D01*
Y1625500D01*
X135400Y1622600D01*
X133800D01*
X132700Y1621500D01*
X129000D01*
G37*
G36*
G01X210000Y1645500D02*
X148000Y1707500D01*
Y1721711D01*
X157789Y1731500D01*
X164000D01*
X202500Y1693000D01*
X290423D01*
X290464Y1692854D01*
G03X292399Y1691388I1936J546D01*
G01X295600D01*
G03X297536Y1692854I0J2011D01*
G01X297577Y1693000D01*
X301700D01*
X302365Y1693665D01*
X307135D01*
X307400Y1693400D01*
Y1687300D01*
X327200Y1667500D01*
X334000D01*
X336000Y1665500D01*
Y1649500D01*
X332000Y1645500D01*
X210000D01*
G37*
G36*
G01X218700Y1778502D02*
G03X217970Y1778326I0J-1602D01*
G01X217841Y1778259D01*
X200400Y1795700D01*
X181300D01*
X179000Y1798000D01*
Y1807500D01*
X186000Y1814500D01*
X301500D01*
X333500Y1782500D01*
Y1753100D01*
X314200Y1733800D01*
X307700D01*
X306000Y1735500D01*
Y1789500D01*
X294500Y1801000D01*
X271000D01*
X266763Y1796763D01*
Y1784038D01*
X273809Y1776992D01*
Y1760309D01*
X257000Y1743500D01*
X232559D01*
X220806Y1731747D01*
X202453D01*
X189712Y1744488D01*
Y1746212D01*
X190960Y1747460D01*
X232577D01*
X254132Y1769015D01*
Y1772097D01*
X251029Y1775200D01*
X225031D01*
G02X224642Y1775692I0J400D01*
G03X222500Y1778402I-2142J508D01*
G01X220658D01*
X220626Y1778413D01*
G03X220100Y1778502I-527J-1513D01*
G01X218700D01*
G37*
G36*
G01X290194Y1824500D02*
X181500D01*
X178000Y1828000D01*
Y1847150D01*
X182464Y1851614D01*
X276829D01*
X292409Y1836034D01*
Y1826715D01*
X290194Y1824500D01*
G37*
G36*
G01X135884Y1810640D02*
X127242Y1819282D01*
Y1868334D01*
X127200Y1868375D01*
Y1868600D01*
X121224Y1874576D01*
Y1927724D01*
X122800Y1929300D01*
X132000D01*
X136000Y1925300D01*
Y1829000D01*
X141000Y1824000D01*
Y1814000D01*
X137640Y1810640D01*
X135884D01*
G37*
G36*
G01X134000Y1952098D02*
G03X134065Y1952100I-17J1601D01*
G01X136500D01*
X137100Y1951500D01*
Y1948700D01*
X133700Y1945300D01*
X129500D01*
X128800Y1946000D01*
Y1951400D01*
X129500Y1952100D01*
X132335D01*
G03X132400Y1952098I82J1599D01*
G01X134000D01*
G37*
G36*
G01X239000Y137000D02*
X220500D01*
X211000Y146500D01*
Y211000D01*
X216500Y216500D01*
X290500D01*
X358000Y284000D01*
X366500D01*
X370000Y280500D01*
Y268000D01*
X239000Y137000D01*
G37*
G36*
G01X260500Y558000D02*
X205000Y613500D01*
Y643000D01*
X189500Y658500D01*
Y700000D01*
X187500Y702000D01*
Y728041D01*
X190002Y730542D01*
Y770502D01*
X192500Y773000D01*
X244500D01*
X287000Y730500D01*
X317183D01*
X324020Y723663D01*
Y626076D01*
X322444Y624500D01*
X288500D01*
X265500Y601500D01*
Y561500D01*
X262000Y558000D01*
X260500D01*
G37*
G36*
G01X312900Y401500D02*
X311503Y402897D01*
X308303D01*
X308100Y403100D01*
Y408900D01*
X311900Y412700D01*
Y427600D01*
X312800Y428500D01*
X324800D01*
X325900Y427400D01*
Y425765D01*
G03X325898Y425700I1599J-82D01*
G01Y424300D01*
G03X325900Y424235I1601J17D01*
G01Y421765D01*
G03X325898Y421700I1599J-82D01*
G01Y420300D01*
G03X325900Y420235I1601J17D01*
G01Y417765D01*
G03X325898Y417700I1599J-82D01*
G01Y416300D01*
G03X325900Y416235I1601J17D01*
G01Y415900D01*
X325400Y415400D01*
X320700D01*
X319200Y413900D01*
Y412000D01*
X320900Y410300D01*
X325600D01*
X325900Y410000D01*
Y409265D01*
G03X325898Y409200I1599J-82D01*
G01Y407800D01*
G03X325900Y407735I1601J17D01*
G01Y405165D01*
G03X325898Y405100I1599J-82D01*
G01Y403700D01*
G03X325900Y403635I1601J17D01*
G01Y402800D01*
X324600Y401500D01*
X312900D01*
G37*
G36*
G01X407446Y427975D02*
G02X407170Y428665I0J400D01*
G03X399905Y434099I-3170J3335D01*
G02X399149Y434281I-356J182D01*
G01Y468254D01*
X342757Y524646D01*
X294924D01*
X289051Y530519D01*
Y538561D01*
X291857Y541367D01*
X351728D01*
X414416Y478679D01*
Y429920D01*
X412471Y427975D01*
X407446D01*
G37*
G36*
G01X324564Y580997D02*
X324044Y581517D01*
Y584964D01*
X324868Y585788D01*
X327552D01*
X328088Y586324D01*
Y588092D01*
X328089Y588104D01*
G03X328102Y588300I-1588J204D01*
G01Y589700D01*
G03X328100Y589765I-1601J-17D01*
G01X328097Y589853D01*
X328470Y590226D01*
X335438D01*
X336114Y590902D01*
Y595152D01*
X335833Y595433D01*
X328546D01*
X328113Y595866D01*
Y597704D01*
X328700Y598291D01*
X335348D01*
X336114Y599057D01*
Y611115D01*
X335744Y611485D01*
X327571D01*
X327290Y611766D01*
Y731286D01*
X327905Y731901D01*
X333810D01*
X343331Y722380D01*
Y583563D01*
X340765Y580997D01*
X324564D01*
G37*
G36*
G01X314100Y830300D02*
X312006Y832394D01*
X307606D01*
X307100Y832900D01*
Y838400D01*
X312200Y843500D01*
Y858400D01*
X312900Y859100D01*
X324200D01*
X325900Y857400D01*
Y855765D01*
G03X325898Y855700I1599J-82D01*
G01Y854300D01*
G03X325900Y854235I1601J17D01*
G01Y851765D01*
G03X325898Y851700I1599J-82D01*
G01Y850300D01*
G03X325900Y850235I1601J17D01*
G01Y847765D01*
G03X325898Y847700I1599J-82D01*
G01Y846300D01*
G03X325900Y846235I1601J17D01*
G01Y845900D01*
X325400Y845400D01*
X320700D01*
X319200Y843900D01*
Y842000D01*
X320900Y840300D01*
X325600D01*
X325900Y840000D01*
Y839265D01*
G03X325898Y839200I1599J-82D01*
G01Y837800D01*
G03X325900Y837735I1601J17D01*
G01Y835165D01*
G03X325898Y835100I1599J-82D01*
G01Y833700D01*
G03X325900Y833635I1601J17D01*
G01Y831700D01*
X324500Y830300D01*
X314100D01*
G37*
G36*
G01Y1201800D02*
X312053Y1203847D01*
X308409D01*
X308100Y1204156D01*
Y1210500D01*
X312200Y1214600D01*
Y1229400D01*
X312800Y1230000D01*
X324800D01*
X325900Y1228900D01*
Y1227265D01*
G03X325898Y1227200I1599J-82D01*
G01Y1225800D01*
G03X325900Y1225735I1601J17D01*
G01Y1223265D01*
G03X325898Y1223200I1599J-82D01*
G01Y1221800D01*
G03X325900Y1221735I1601J17D01*
G01Y1219265D01*
G03X325898Y1219200I1599J-82D01*
G01Y1217800D01*
G03X325900Y1217735I1601J17D01*
G01Y1217400D01*
X325400Y1216900D01*
X320700D01*
X319200Y1215400D01*
Y1213500D01*
X320900Y1211800D01*
X325600D01*
X325900Y1211500D01*
Y1210765D01*
G03X325898Y1210700I1599J-82D01*
G01Y1209300D01*
G03X325900Y1209235I1601J17D01*
G01Y1206565D01*
G03X325898Y1206500I1599J-82D01*
G01Y1205100D01*
G03X325900Y1205035I1601J17D01*
G01Y1203200D01*
X324500Y1201800D01*
X314100D01*
G37*
G36*
G01Y1700300D02*
X312051Y1702349D01*
X309406D01*
X309100Y1702655D01*
Y1709100D01*
X312200Y1712200D01*
Y1727900D01*
X312800Y1728500D01*
X324800D01*
X325900Y1727400D01*
Y1725765D01*
G03X325898Y1725700I1599J-82D01*
G01Y1724300D01*
G03X325900Y1724235I1601J17D01*
G01Y1721765D01*
G03X325898Y1721700I1599J-82D01*
G01Y1720300D01*
G03X325900Y1720235I1601J17D01*
G01Y1717765D01*
G03X325898Y1717700I1599J-82D01*
G01Y1716300D01*
G03X325900Y1716235I1601J17D01*
G01Y1715900D01*
X325400Y1715400D01*
X320700D01*
X319200Y1713900D01*
Y1712000D01*
X320900Y1710300D01*
X325600D01*
X325900Y1710000D01*
Y1709265D01*
G03X325898Y1709200I1599J-82D01*
G01Y1707800D01*
G03X325900Y1707735I1601J17D01*
G01Y1705065D01*
G03X325898Y1705000I1599J-82D01*
G01Y1703600D01*
G03X325900Y1703535I1601J17D01*
G01Y1701700D01*
X324500Y1700300D01*
X314100D01*
G37*
G36*
G01X366965Y359500D02*
X365866Y360599D01*
Y367866D01*
X366900Y368900D01*
X367635D01*
G03X367700Y368898I82J1599D01*
G01X369300D01*
G03X369365Y368900I-17J1601D01*
G01X371135D01*
G03X371200Y368898I82J1599D01*
G01X372800D01*
G03X372865Y368900I-17J1601D01*
G01X373100D01*
X373500Y368500D01*
Y360716D01*
X372284Y359500D01*
X366965D01*
G37*
G36*
G01X373156Y431656D02*
X366186D01*
X365666Y432176D01*
Y439190D01*
X366958Y440482D01*
X372075D01*
X373602Y438955D01*
Y432102D01*
X373156Y431656D01*
G37*
G36*
G01X426500Y658500D02*
X417000D01*
X396000Y679500D01*
Y790500D01*
X402000Y796500D01*
X426500D01*
X431000Y792000D01*
Y663000D01*
X426500Y658500D01*
G37*
G36*
G01X366900Y1232100D02*
X365000Y1234000D01*
Y1239900D01*
X366200Y1241100D01*
X372100D01*
X373500Y1239700D01*
Y1232500D01*
X373100Y1232100D01*
X372865D01*
G03X372800Y1232102I-82J-1599D01*
G01X371200D01*
G03X371135Y1232100I17J-1601D01*
G01X369365D01*
G03X369300Y1232102I-82J-1599D01*
G01X367700D01*
G03X367635Y1232100I17J-1601D01*
G01X366900D01*
G37*
G36*
G01X365500Y1730100D02*
X363900Y1731700D01*
Y1735900D01*
X365800Y1737800D01*
X371700D01*
X374000Y1735500D01*
Y1730500D01*
X373600Y1730100D01*
X373365D01*
G03X373300Y1730102I-82J-1599D01*
G01X371700D01*
G03X371635Y1730100I17J-1601D01*
G01X369865D01*
G03X369800Y1730102I-82J-1599D01*
G01X368200D01*
G03X368135Y1730100I17J-1601D01*
G01X365500D01*
G37*
G36*
G01X849000Y1025000D02*
X491721D01*
X412268Y1104453D01*
Y1119323D01*
X419945Y1127000D01*
X858500D01*
X864500Y1121000D01*
Y1068500D01*
X854000Y1058000D01*
X659500D01*
X654500Y1053000D01*
Y1050000D01*
X656500Y1048000D01*
X850500D01*
X855000Y1043500D01*
Y1031000D01*
X849000Y1025000D01*
G37*
G36*
G01X843078Y1336238D02*
X660726D01*
X657905Y1339059D01*
Y1348317D01*
X707974Y1398386D01*
X863145D01*
X867000Y1394531D01*
Y1372900D01*
X864300Y1370200D01*
X856900D01*
X850800Y1364100D01*
Y1343960D01*
X843078Y1336238D01*
G37*
G36*
G01X812000Y1690000D02*
X777000Y1655000D01*
X753000D01*
X746500Y1661500D01*
Y1692000D01*
X782000Y1727500D01*
X811500D01*
X812000Y1727000D01*
Y1690000D01*
G37*
G36*
G01X822900Y343600D02*
X822500Y344000D01*
Y346000D01*
X823000Y346500D01*
X825500D01*
X826600Y347600D01*
Y348235D01*
G03X826602Y348300I-1599J82D01*
G01Y349700D01*
G03X826600Y349765I-1601J-17D01*
G01Y350600D01*
X828000Y352000D01*
Y357500D01*
X831000Y360500D01*
Y365700D01*
X836900Y371600D01*
X839046D01*
X839070Y371594D01*
G03X839450Y371548I381J1556D01*
G01X840850D01*
G03X841230Y371594I-1J1602D01*
G01X841254Y371600D01*
X841984D01*
X842700Y370884D01*
Y368565D01*
X845300Y365965D01*
Y348000D01*
X843300Y346000D01*
X832000D01*
X829600Y343600D01*
X828865D01*
G03X828800Y343602I-82J-1599D01*
G01X827200D01*
G03X827135Y343600I17J-1601D01*
G01X824765D01*
G03X824700Y343602I-82J-1599D01*
G01X823300D01*
G03X823235Y343600I17J-1601D01*
G01X822900D01*
G37*
G36*
G01Y749100D02*
X822500Y749500D01*
Y751500D01*
X823000Y752000D01*
X825500D01*
X826600Y753100D01*
Y753735D01*
G03X826602Y753800I-1599J82D01*
G01Y755200D01*
G03X826600Y755265I-1601J-17D01*
G01Y756100D01*
X828000Y757500D01*
Y763000D01*
X831000Y766000D01*
Y771400D01*
X836186Y776586D01*
X842128D01*
X842798Y775916D01*
Y774825D01*
G03X842800Y774751I2002J17D01*
G01Y773959D01*
X846500Y770259D01*
Y752500D01*
X845500Y751500D01*
X832000D01*
X829600Y749100D01*
X828865D01*
G03X828800Y749102I-82J-1599D01*
G01X827200D01*
G03X827135Y749100I17J-1601D01*
G01X824765D01*
G03X824700Y749102I-82J-1599D01*
G01X823300D01*
G03X823235Y749100I17J-1601D01*
G01X822900D01*
G37*
G36*
G01Y1154600D02*
X822500Y1155000D01*
Y1157000D01*
X823000Y1157500D01*
X825500D01*
X826600Y1158600D01*
Y1159235D01*
G03X826602Y1159300I-1599J82D01*
G01Y1160700D01*
G03X826600Y1160765I-1601J-17D01*
G01Y1161600D01*
X828000Y1163000D01*
Y1168500D01*
X831700Y1172200D01*
Y1177300D01*
X837000Y1182600D01*
X839046D01*
X839070Y1182594D01*
G03X839450Y1182548I381J1556D01*
G01X840850D01*
G03X841230Y1182594I-1J1602D01*
G01X841254Y1182600D01*
X842170D01*
X842700Y1182070D01*
Y1179538D01*
X845000Y1177238D01*
Y1157900D01*
X844100Y1157000D01*
X832000D01*
X829600Y1154600D01*
X828865D01*
G03X828800Y1154602I-82J-1599D01*
G01X827200D01*
G03X827135Y1154600I17J-1601D01*
G01X824765D01*
G03X824700Y1154602I-82J-1599D01*
G01X823300D01*
G03X823235Y1154600I17J-1601D01*
G01X822900D01*
G37*
G36*
G01Y1560100D02*
X822500Y1560500D01*
Y1562500D01*
X823000Y1563000D01*
X825500D01*
X826600Y1564100D01*
Y1564735D01*
G03X826602Y1564800I-1599J82D01*
G01Y1566200D01*
G03X826600Y1566265I-1601J-17D01*
G01Y1567100D01*
X828000Y1568500D01*
Y1574000D01*
X831000Y1577000D01*
Y1582500D01*
X836169Y1587669D01*
X841669D01*
X842222Y1587116D01*
Y1585567D01*
X846500Y1581289D01*
Y1563500D01*
X845500Y1562500D01*
X832000D01*
X829600Y1560100D01*
X828865D01*
G03X828800Y1560102I-82J-1599D01*
G01X827200D01*
G03X827135Y1560100I17J-1601D01*
G01X824765D01*
G03X824700Y1560102I-82J-1599D01*
G01X823300D01*
G03X823235Y1560100I17J-1601D01*
G01X822900D01*
G37*
G36*
G01X842300Y1699898D02*
G03X842365Y1699900I-17J1601D01*
G01X843000D01*
X843600Y1699300D01*
Y1694000D01*
X842600Y1693000D01*
X824888D01*
X823888Y1694000D01*
Y1702000D01*
X824888Y1703000D01*
X837888D01*
X838888Y1702000D01*
Y1700500D01*
X839488Y1699900D01*
X840635D01*
G03X840700Y1699898I82J1599D01*
G01X842300D01*
G37*
G36*
G01X869823Y1648495D02*
X788161D01*
X784562Y1652094D01*
Y1656488D01*
X813152Y1685078D01*
X868897D01*
X871582Y1682393D01*
Y1650254D01*
X869823Y1648495D01*
G37*
G36*
G01X852500Y1727500D02*
Y1708500D01*
X845200Y1701200D01*
X840400D01*
X840200Y1701400D01*
Y1703688D01*
X838888Y1705000D01*
X818888D01*
X816888Y1707000D01*
Y1727388D01*
X817500Y1728000D01*
X824000D01*
X824500Y1728500D01*
Y1729500D01*
X825000Y1730000D01*
X850000D01*
X852500Y1727500D01*
G37*
G36*
G01X837888Y1732000D02*
X824862D01*
X824326Y1732536D01*
Y1740420D01*
X824906Y1741000D01*
X837888D01*
X838888Y1740000D01*
Y1733000D01*
X837888Y1732000D01*
G37*
G36*
G01X787569Y1816006D02*
X785582Y1817993D01*
Y1822137D01*
X828998Y1865553D01*
Y1918703D01*
X841751Y1931456D01*
X863529D01*
X865127Y1929858D01*
Y1873687D01*
X859121Y1867681D01*
X842748D01*
X815777Y1840710D01*
Y1837208D01*
X817418Y1835567D01*
X821220D01*
X846452Y1860798D01*
X863048D01*
X864946Y1858900D01*
Y1832715D01*
X858293Y1826062D01*
X833651D01*
X832506Y1824917D01*
Y1818378D01*
X832494Y1818345D01*
G03X832398Y1817800I1506J-546D01*
G01Y1816266D01*
X832138Y1816006D01*
X811201D01*
X811175Y1816013D01*
G03X809825I-675J-2513D01*
G01X809799Y1816006D01*
X787569D01*
G37*
G36*
G01X787739Y1934107D02*
X787339Y1934507D01*
Y1936007D01*
X787839Y1936507D01*
X790339D01*
X791439Y1937607D01*
Y1938742D01*
G03X791440Y1938807I-1600J57D01*
G01Y1940207D01*
G03X791439Y1940272I-1601J8D01*
G01Y1943307D01*
X795439Y1947307D01*
Y1957339D01*
X795929Y1957829D01*
X796008Y1957832D01*
G03X796438Y1957894I-69J2000D01*
G01X796462Y1957900D01*
X808600D01*
X813839Y1952661D01*
Y1940707D01*
X810339Y1937207D01*
X798539D01*
X795439Y1934107D01*
X793704D01*
G03X793639Y1934108I-57J-1600D01*
G01X792039D01*
G03X791974Y1934107I-8J-1601D01*
G01X789604D01*
G03X789539Y1934108I-57J-1600D01*
G01X788139D01*
G03X788074Y1934107I-8J-1601D01*
G01X787739D01*
G37*
G36*
G01X819900Y1931800D02*
X818700Y1933000D01*
Y1954700D01*
X819650Y1955650D01*
Y1961950D01*
X821200Y1963500D01*
X848900D01*
X849900Y1964500D01*
Y1972500D01*
X851700Y1974300D01*
X863500D01*
X865000Y1972800D01*
Y1960600D01*
X866900Y1958700D01*
X875100D01*
X875198Y1958798D01*
X875202D01*
Y1958802D01*
X876018Y1959618D01*
Y1971738D01*
X876780Y1972500D01*
X894000D01*
X902000Y1964500D01*
Y1944000D01*
X901500Y1943500D01*
X889000D01*
X888500Y1944000D01*
Y1952000D01*
X886600Y1953900D01*
X878400D01*
X876000Y1951500D01*
X866900D01*
X864500Y1953900D01*
X863999D01*
X863998Y1953902D01*
X857202D01*
X857201Y1953900D01*
X843400D01*
X838400Y1948900D01*
Y1938400D01*
X831800Y1931800D01*
X819900D01*
G37*
G36*
G01X820600Y1965100D02*
X819600Y1966100D01*
Y1972700D01*
X821698Y1974798D01*
X847702D01*
X848700Y1973800D01*
Y1972999D01*
X848698Y1972998D01*
Y1966143D01*
X847655Y1965100D01*
X820600D01*
G37*
G36*
G01X859650Y331050D02*
X858800Y331900D01*
Y337400D01*
X859300Y337900D01*
X873335D01*
G03X873400Y337898I82J1599D01*
G01X875000D01*
G03X875065Y337900I-17J1601D01*
G01X876100D01*
X876900Y337100D01*
Y331800D01*
X876150Y331050D01*
X859650D01*
G37*
G36*
G01X885700Y330700D02*
X877300Y339100D01*
X876599D01*
X876598Y339102D01*
X858998D01*
X858250Y339850D01*
X852450D01*
X851000Y341300D01*
Y358800D01*
X852000Y359800D01*
X877800D01*
X880100Y362100D01*
Y377800D01*
X881300Y379000D01*
X896700D01*
X898500Y377200D01*
Y360000D01*
X894717Y356217D01*
G03X894270Y355770I2739J-3186D01*
G01X893000Y354500D01*
Y351000D01*
X899500Y344500D01*
Y322172D01*
X899087Y321759D01*
X889444D01*
X889000Y322203D01*
Y329500D01*
X887800Y330700D01*
X885700D01*
G37*
G36*
G01X877200Y361100D02*
X862100D01*
X861200Y362000D01*
Y371200D01*
X862100Y372100D01*
X877000D01*
X878800Y370300D01*
Y362700D01*
X877200Y361100D01*
G37*
G36*
G01X859500Y736800D02*
X858500Y737800D01*
Y743400D01*
X859500Y744400D01*
X873235D01*
G03X873300Y744398I82J1599D01*
G01X874900D01*
G03X874965Y744400I-17J1601D01*
G01X876000D01*
X877000Y743400D01*
Y737500D01*
X876300Y736800D01*
X859500D01*
G37*
G36*
G01X863354Y766402D02*
X862541Y767214D01*
Y776541D01*
X863500Y777500D01*
X877400D01*
X878900Y776000D01*
Y767400D01*
X877902Y766402D01*
X863354D01*
G37*
G36*
G01X889412Y727359D02*
X889000Y727771D01*
Y735000D01*
X888000Y736000D01*
X887828D01*
Y736020D01*
X886280D01*
X876700Y745600D01*
X876499D01*
X876498Y745602D01*
X859002D01*
X859001Y745600D01*
X852400D01*
X851400Y746600D01*
Y764300D01*
X852300Y765200D01*
X878800D01*
X880300Y766700D01*
Y783700D01*
X882200Y785600D01*
X896200D01*
X898500Y783300D01*
Y765500D01*
X894792Y761792D01*
G03X894207Y761207I2664J-3249D01*
G01X893000Y760000D01*
Y756500D01*
X899500Y750000D01*
Y727851D01*
X899008Y727359D01*
X889412D01*
G37*
G36*
G01X889444Y1132735D02*
X889000Y1133179D01*
Y1140500D01*
X887900Y1141600D01*
X885400D01*
X876900Y1150100D01*
X876099D01*
X876098Y1150102D01*
X860898D01*
X859850Y1151150D01*
X852550D01*
X850900Y1152800D01*
Y1169800D01*
X852100Y1171000D01*
X878000D01*
X879000Y1172000D01*
Y1186200D01*
X879900Y1187100D01*
X896800D01*
X898500Y1185400D01*
Y1171000D01*
X894853Y1167353D01*
X894844Y1167346D01*
G03X894165Y1166667I2612J-3291D01*
G01X894158Y1166658D01*
X893000Y1165500D01*
Y1162000D01*
X899500Y1155500D01*
Y1133131D01*
X899104Y1132735D01*
X889444D01*
G37*
G36*
G01X859300Y1142500D02*
X858100Y1143700D01*
Y1147900D01*
X859100Y1148900D01*
X873235D01*
G03X873300Y1148898I82J1599D01*
G01X874900D01*
G03X874965Y1148900I-17J1601D01*
G01X875600D01*
X876300Y1148200D01*
Y1143000D01*
X875800Y1142500D01*
X859300D01*
G37*
G36*
G01X877000Y1172500D02*
X861100D01*
X860000Y1173600D01*
Y1182300D01*
X860700Y1183000D01*
X876500D01*
X877500Y1182000D01*
Y1173000D01*
X877000Y1172500D01*
G37*
G36*
G01X859400Y1547600D02*
X858500Y1548500D01*
Y1553700D01*
X859900Y1555100D01*
X873335D01*
G03X873400Y1555098I82J1599D01*
G01X875000D01*
G03X875065Y1555100I-17J1601D01*
G01X875700D01*
X876100Y1554700D01*
Y1548400D01*
X875300Y1547600D01*
X859400D01*
G37*
G36*
G01X889428Y1538078D02*
X889000Y1538506D01*
Y1546000D01*
X887800Y1547200D01*
X885400D01*
X876300Y1556300D01*
X876199D01*
X876198Y1556302D01*
X859402D01*
X859401Y1556300D01*
X857400D01*
X857100Y1556600D01*
X852500D01*
X851600Y1557500D01*
Y1575300D01*
X852800Y1576500D01*
X879400D01*
X880900Y1578000D01*
Y1590300D01*
X882600Y1592000D01*
X895700D01*
X898500Y1589200D01*
Y1576500D01*
X894907Y1572907D01*
X894897Y1572899D01*
G03X894124Y1572126I2559J-3332D01*
G01X894116Y1572116D01*
X893000Y1571000D01*
Y1567500D01*
X899500Y1561000D01*
Y1538477D01*
X899101Y1538078D01*
X889428D01*
G37*
G36*
G01X879300Y1579700D02*
X877600Y1578000D01*
X863000D01*
X862500Y1578500D01*
Y1588000D01*
X864500Y1590000D01*
X877300D01*
X879300Y1588000D01*
Y1579700D01*
G37*
G36*
G01X881799Y1666007D02*
X873541D01*
X872837Y1666711D01*
Y1686727D01*
X874740Y1688630D01*
X882122D01*
X882500Y1688252D01*
Y1666708D01*
X881799Y1666007D01*
G37*
G36*
G01X896200Y1706500D02*
X890800D01*
X890550Y1706750D01*
Y1713750D01*
X890502Y1713799D01*
Y1717698D01*
X890000Y1718199D01*
Y1720500D01*
X890500Y1721000D01*
X891500D01*
X892782Y1719718D01*
Y1719108D01*
X892682D01*
Y1713004D01*
X893696D01*
X893700Y1713000D01*
X896100D01*
X896500Y1712600D01*
Y1706800D01*
X896200Y1706500D01*
G37*
G36*
G01X883353Y1649769D02*
X882427Y1648843D01*
X874969D01*
X874132Y1649680D01*
Y1663511D01*
X874972Y1664351D01*
X882105D01*
X883353Y1663103D01*
Y1649769D01*
G37*
G36*
G01X889300Y1708600D02*
X888900Y1708200D01*
X879800D01*
X875000Y1713000D01*
X862700D01*
X862500Y1713200D01*
Y1726800D01*
X862700Y1727000D01*
X874500D01*
X876500Y1725000D01*
X879500D01*
X880000Y1724500D01*
Y1720000D01*
X880500Y1719500D01*
X887000D01*
X889300Y1717200D01*
Y1712086D01*
G03Y1711914I2200J-86D01*
G01Y1708600D01*
G37*
G36*
G01X887013Y1656150D02*
X886000Y1657163D01*
Y1694400D01*
X888100Y1696500D01*
Y1697135D01*
G03X888102Y1697200I-1599J82D01*
G01Y1698800D01*
G03X888100Y1698865I-1601J-17D01*
G01Y1704100D01*
X889300Y1705300D01*
X890301D01*
X890302Y1705298D01*
X892702D01*
X893100Y1704900D01*
Y1680900D01*
X895000Y1679000D01*
Y1657058D01*
X894092Y1656150D01*
X887013D01*
G37*
G36*
G01X857300Y1950400D02*
Y1952300D01*
X857700Y1952700D01*
X861635D01*
G03X861700Y1952698I82J1599D01*
G01X863300D01*
G03X863365Y1952700I-17J1601D01*
G01X863500D01*
X863700Y1952500D01*
Y1950300D01*
X863500Y1950100D01*
X857621D01*
G03X857592Y1950108I-706J-2504D01*
G01X857300Y1950400D01*
G37*
G36*
G01X993500Y1419900D02*
X992800Y1420600D01*
X988700D01*
X986800Y1422500D01*
X934500D01*
X932000Y1425000D01*
Y1509500D01*
X932700Y1510200D01*
X981000D01*
X981800Y1511000D01*
X1019500D01*
X1020000Y1510500D01*
Y1434000D01*
X1009100Y1423100D01*
X998900D01*
X995700Y1419900D01*
X995465D01*
G03X995400Y1419902I-82J-1599D01*
G01X993800D01*
G03X993735Y1419900I17J-1601D01*
G01X993500D01*
G37*
%LPC*%
G75*
G36*
G01X49214Y281496D02*
Y267716D01*
G02X17716I-15749J1D01*
G01Y281496D01*
G02X49214I15749J0D01*
G37*
G36*
G01X259842Y1889754D02*
Y1903534D01*
G02X291340I15749J0D01*
G01Y1889754D01*
G02X259842I-15749J0D01*
G37*
G36*
G01X5904Y1909055D02*
Y1922835D01*
G02X37404I15750J0D01*
G01Y1909055D01*
G02X5904I-15750J0D01*
G37*
G36*
G01X259842Y1074793D02*
Y1088573D01*
G02X291340I15749J0D01*
G01Y1074793D01*
G02X259842I-15749J0D01*
G37*
G36*
G01Y265748D02*
Y279528D01*
G02X291340I15749J0D01*
G01Y265748D01*
G02X259842I-15749J0D01*
G37*
G36*
G01X961902Y1625900D02*
G02X960300Y1624298I-1602J0D01*
G01X957700D01*
G02X956098Y1625900I0J1602D01*
G01Y1628500D01*
G02X956798Y1629824I1602J0D01*
G01Y1631000D01*
G02X961202I2202J0D01*
G01Y1629824D01*
G02X961902Y1628500I-902J-1324D01*
G01Y1625900D01*
G37*
G36*
G01X815106Y1623404D02*
G02X812894I-1106J-1904D01*
G03Y1624096I-201J346D01*
G02Y1627904I1106J1904D01*
G03Y1628596I-201J346D01*
G02X815106I1106J1904D01*
G03Y1627904I201J-346D01*
G02Y1624096I-1106J-1904D01*
G03Y1623404I201J-346D01*
G37*
G36*
G01X809606D02*
G02X807394I-1106J-1904D01*
G03Y1624096I-201J346D01*
G02Y1627904I1106J1904D01*
G03Y1628596I-201J346D01*
G02X809606I1106J1904D01*
G03Y1627904I201J-346D01*
G02Y1624096I-1106J-1904D01*
G03Y1623404I201J-346D01*
G37*
G36*
G01X652806Y1563104D02*
G02X650594I-1106J-1904D01*
G03Y1563796I-201J346D01*
G02X652806I1106J1904D01*
G03Y1563104I201J-346D01*
G37*
G36*
G01X647306D02*
G02X645094I-1106J-1904D01*
G03Y1563796I-201J346D01*
G02X647306I1106J1904D01*
G03Y1563104I201J-346D01*
G37*
G36*
G01X640806D02*
G02X638594I-1106J-1904D01*
G03Y1563796I-201J346D01*
G02X640806I1106J1904D01*
G03Y1563104I201J-346D01*
G37*
G36*
G01X635306D02*
G02X633094I-1106J-1904D01*
G03Y1563796I-201J346D01*
G02X635306I1106J1904D01*
G03Y1563104I201J-346D01*
G37*
G36*
G01X259842Y671250D02*
Y685030D01*
G02X291340I15749J0D01*
G01Y671250D01*
G02X259842I-15749J0D01*
G37*
G54D112*
X363750Y799000D03*
X369250Y1170000D03*
X374250Y1669000D03*
X370250Y366500D03*
Y434000D03*
Y1234500D03*
X370750Y1732500D03*
G54D108*
X72835Y595787D03*
G54D101*
X37400Y1821450D03*
X31400D03*
G54D109*
X295200Y913000D03*
X305200D03*
Y903000D03*
X295200D03*
X81500Y1213000D03*
X294500Y1254000D03*
X295000Y1245000D03*
X196000Y1070300D03*
X292500Y965500D03*
X294000Y1111500D03*
X661500Y650500D03*
X327500Y1368500D03*
X328000Y1374000D03*
Y1381500D03*
X547659Y1560537D03*
X542159D03*
Y1566037D03*
X547659D03*
G54D106*
X1010500Y1966000D03*
X340500Y793500D03*
X343000Y1166000D03*
X1009500Y27500D03*
X329500Y363500D03*
X327500Y1662000D03*
G54D107*
X82087Y28858D03*
Y434370D03*
Y839882D03*
Y1245394D03*
Y1650906D03*
X162008Y1963268D03*
Y341220D03*
Y746732D03*
Y1152244D03*
Y1557756D03*
X890354Y1963268D03*
Y341220D03*
Y746732D03*
Y1152244D03*
Y1557756D03*
G54D105*
X25499Y1950499D03*
X1010499D03*
X1010999Y43999D03*
G54D103*
X11811Y1862763D03*
G54D104*
X998032Y1896644D03*
G54D102*
X37400Y1824400D03*
X38800Y1825600D03*
Y1829000D03*
Y1830400D03*
Y1833800D03*
X29800D03*
Y1830400D03*
Y1829000D03*
Y1825600D03*
X31400Y1824400D03*
X114500Y38800D03*
X116900D03*
X99900Y40100D03*
X110900D03*
X129300Y49300D03*
X132700D03*
Y52700D03*
X97300Y215565D03*
Y213365D03*
Y211100D03*
Y208900D03*
Y206600D03*
Y204400D03*
X106700Y410300D03*
X98500Y346000D03*
X100900D03*
X100500Y347900D03*
Y350100D03*
X112550Y369350D03*
X114750D03*
X83800Y401700D03*
X88300D03*
X83800Y412700D03*
X88300D03*
X106700Y419300D03*
X110100D03*
X97200Y434400D03*
X99600D03*
X97200Y440400D03*
X99600D03*
X97300Y621077D03*
Y618877D03*
Y616600D03*
Y614400D03*
Y612100D03*
Y609900D03*
X98500Y751500D03*
X96800Y751300D03*
X100900Y751500D03*
X100500Y753400D03*
Y755600D03*
X112550Y774850D03*
X97200Y845900D03*
X99600D03*
X107000Y815800D03*
X86400Y807700D03*
X90900D03*
X86400Y818700D03*
X90900D03*
X107000Y824800D03*
X110400D03*
X97200Y839900D03*
X99600D03*
X97300Y1015400D03*
Y1017600D03*
Y1019900D03*
Y1022100D03*
Y1024388D03*
Y1026588D03*
X98500Y1157400D03*
X100900D03*
X100500Y1159300D03*
Y1161500D03*
X112550Y1180350D03*
X114750D03*
X88900Y1213200D03*
X84400Y1224200D03*
X88900D03*
X95900Y1230900D03*
X99300D03*
X97200Y1245400D03*
X99600D03*
X97200Y1251400D03*
X99600D03*
X99300Y1221900D03*
X95900D03*
X97300Y1420900D03*
Y1423100D03*
Y1425400D03*
Y1427600D03*
Y1429900D03*
Y1432100D03*
X100200Y1553500D03*
X99800Y1555400D03*
Y1557600D03*
X101925Y1580225D03*
X104125D03*
X106900Y1626500D03*
X82700Y1618500D03*
X87200D03*
X82700Y1629500D03*
X87200D03*
X106900Y1635500D03*
X110300D03*
X97700Y1651300D03*
X100100D03*
Y1657300D03*
X97700D03*
X70700Y1937500D03*
X70300Y1939400D03*
Y1941600D03*
X132000Y1955700D03*
X134400D03*
X122700Y1959700D03*
X127200D03*
X116800Y1960100D03*
X120200D03*
X122700Y1970700D03*
X127200D03*
X116800Y1969100D03*
X830000Y201800D03*
X129300Y58300D03*
X132700D03*
X830000Y204200D03*
X360800Y799000D03*
X329700Y801900D03*
X366300Y1170000D03*
X329700Y1173400D03*
X304100Y1192950D03*
X988800Y1415000D03*
X992200D03*
X993400Y1416300D03*
X995800D03*
X179750Y32150D03*
X181950D03*
X192200Y51400D03*
Y53600D03*
X191800Y55500D03*
X194200D03*
X329700Y371900D03*
X304000Y392000D03*
X144500Y335400D03*
X146900D03*
X144500Y341400D03*
X146900D03*
X144900Y355800D03*
X148300D03*
X158100Y362800D03*
X162600D03*
X158100Y373800D03*
X162600D03*
X144900Y364800D03*
X128875Y405775D03*
X131075D03*
X143600Y425500D03*
Y427700D03*
X143200Y429600D03*
X145600D03*
X148200Y769600D03*
X144800D03*
X144600Y741100D03*
X147000D03*
X144600Y747100D03*
X147000D03*
X144800Y760600D03*
X148200D03*
X158300Y769900D03*
X162800D03*
X158300Y780900D03*
X162800D03*
X145600Y835100D03*
X129250Y811650D03*
X131450D03*
X143600Y831000D03*
Y833200D03*
X143200Y835100D03*
X144600Y1151600D03*
X147000D03*
X146800Y1167000D03*
X150200D03*
X157800Y1174000D03*
X162300D03*
X157800Y1185000D03*
X162300D03*
X144600Y1145600D03*
X147000D03*
X146800Y1176000D03*
X129250Y1217150D03*
X131450D03*
X143900Y1236500D03*
Y1238700D03*
X143500Y1240600D03*
X145900D03*
X957300Y1619900D03*
X960700D03*
X957300Y1623300D03*
X960700D03*
X371300Y1669000D03*
X377200D03*
X147000Y1549300D03*
X144600D03*
Y1555300D03*
X147000D03*
X135000Y1572500D03*
X138400D03*
X158900Y1580200D03*
X163400D03*
X158900Y1591200D03*
X163400D03*
X138400Y1581500D03*
X135000D03*
X129250Y1623650D03*
X131450D03*
X145100Y1642000D03*
Y1644200D03*
X144700Y1646100D03*
X147100D03*
X305100Y1691450D03*
X134400Y1949700D03*
X132000D03*
X323700Y403300D03*
X310400Y405100D03*
X323700Y405500D03*
Y407400D03*
X315400Y414500D03*
Y417900D03*
X323700Y418100D03*
Y419900D03*
Y422100D03*
Y423900D03*
Y426100D03*
X330300Y587900D03*
X323700Y833300D03*
X309700Y834600D03*
X323700Y835500D03*
Y837400D03*
X315400Y845000D03*
X323700Y848100D03*
X315400Y848400D03*
X323700Y849900D03*
Y852100D03*
Y853900D03*
Y856100D03*
Y1204700D03*
X310400Y1206050D03*
X323700Y1206900D03*
Y1208900D03*
X315500Y1215800D03*
Y1219200D03*
X323700Y1219600D03*
Y1221400D03*
Y1223600D03*
Y1225400D03*
Y1227600D03*
Y1703200D03*
X311400Y1704550D03*
X323700Y1705400D03*
Y1707400D03*
X313100Y1714000D03*
X316500D03*
X313100Y1717400D03*
X316500D03*
X323700Y1718100D03*
Y1719900D03*
Y1722100D03*
Y1723900D03*
Y1726100D03*
X367300Y366500D03*
Y434000D03*
Y1234500D03*
X367800Y1732500D03*
X826800Y346000D03*
X829200D03*
X828800Y347900D03*
Y350100D03*
X839050Y369350D03*
X841250D03*
X826800Y751500D03*
X829200D03*
X828800Y753400D03*
Y755600D03*
X839050Y774850D03*
X841250D03*
X826800Y1157000D03*
X829200D03*
X828800Y1158900D03*
Y1161100D03*
X839050Y1180350D03*
X841250D03*
X826800Y1562500D03*
X829200D03*
X828800Y1564400D03*
Y1566600D03*
X839050Y1585850D03*
X841250D03*
X842700Y1697500D03*
X840300D03*
X842700Y1703500D03*
X830000Y1818200D03*
X794039Y1936507D03*
X793639Y1938407D03*
Y1940607D03*
X861300Y1956300D03*
X863700D03*
X844800Y1960000D03*
X848200D03*
X851000D03*
X855500D03*
X851000Y1971000D03*
X855500D03*
X844800Y1969000D03*
X873000Y335500D03*
X875400D03*
X873000Y341500D03*
X875400D03*
X863800Y355500D03*
X867200D03*
X863800Y358900D03*
X867200D03*
X887500Y363100D03*
X892000D03*
X887500Y374100D03*
X892000D03*
X867200Y364500D03*
X863800D03*
X872900Y742000D03*
X875300D03*
X866700Y770400D03*
X872900Y748000D03*
X875300D03*
X863300Y761400D03*
X866700D03*
X887200Y769100D03*
X891700D03*
X887200Y780100D03*
X891700D03*
X872900Y1152500D03*
X875300D03*
X872800Y1167500D03*
X876200D03*
X891300Y1175100D03*
X895800D03*
X891300Y1186100D03*
X895800D03*
X872900Y1146500D03*
X875300D03*
X876200Y1176500D03*
X872800D03*
X873000Y1552700D03*
Y1558700D03*
X875400D03*
X864300Y1573000D03*
X867700D03*
X889800Y1579100D03*
X894300D03*
X889800Y1590100D03*
X894300D03*
X864300Y1582000D03*
X867700D03*
X876300Y1721500D03*
X890500Y1696800D03*
Y1699200D03*
X993400Y1422300D03*
X995800D03*
X988800Y1424000D03*
X992200D03*
G54D113*
X269690Y1490152D03*
G54D110*
X998032Y1075778D03*
Y680108D03*
Y156486D03*
G54D111*
X710500Y41500D03*
%LPD*%
G75*
G36*
G01X15748Y279134D02*
Y281464D01*
G02X51182I17717J46D01*
G01Y279134D01*
X41340D01*
Y281479D01*
G03X25590I-7875J32D01*
G01Y279134D01*
X15748D01*
G37*
G36*
G01X3937Y1920473D02*
Y1922803D01*
G02X39371I17717J46D01*
G01Y1920473D01*
X29529D01*
Y1922818D01*
G03X13779I-7875J32D01*
G01Y1920473D01*
X3937D01*
G37*
G36*
G01X257874Y277166D02*
Y279496D01*
G02X293308I17717J46D01*
G01Y277166D01*
X283466D01*
Y279511D01*
G03X267716I-7875J32D01*
G01Y277166D01*
X257874D01*
G37*
G36*
G01Y682668D02*
Y684998D01*
G02X293308I17717J46D01*
G01Y682668D01*
X283466D01*
Y685013D01*
G03X267716I-7875J32D01*
G01Y682668D01*
X257874D01*
G37*
G36*
G01Y1086211D02*
Y1088541D01*
G02X293308I17717J46D01*
G01Y1086211D01*
X283466D01*
Y1088556D01*
G03X267716I-7875J32D01*
G01Y1086211D01*
X257874D01*
G37*
G36*
G01Y1901172D02*
Y1903502D01*
G02X293308I17717J46D01*
G01Y1901172D01*
X283466D01*
Y1903517D01*
G03X267716I-7875J32D01*
G01Y1901172D01*
X257874D01*
G37*
G36*
G01X980314Y161014D02*
Y163344D01*
G02X1015748I17717J46D01*
G01Y161014D01*
X1005906D01*
Y163359D01*
G03X990156I-7875J32D01*
G01Y161014D01*
X980314D01*
G37*
G36*
G01Y684636D02*
Y686966D01*
G02X1015748I17717J46D01*
G01Y684636D01*
X1005906D01*
Y686981D01*
G03X990156I-7875J32D01*
G01Y684636D01*
X980314D01*
G37*
G36*
G01Y1080305D02*
Y1082635D01*
G02X1015748I17717J46D01*
G01Y1080305D01*
X1005906D01*
Y1082650D01*
G03X990156I-7875J32D01*
G01Y1080305D01*
X980314D01*
G37*
G36*
G01Y1901172D02*
Y1903502D01*
G02X1015748I17717J46D01*
G01Y1901172D01*
X1005906D01*
Y1903517D01*
G03X990156I-7875J32D01*
G01Y1901172D01*
X980314D01*
G37*
G54D100*
G01X8858Y601347D02*
X14401D01*
X15575Y602521D01*
X26530D01*
X27529Y601522D01*
G01X8858Y604496D02*
X14401D01*
X15175Y603722D01*
X26529D01*
X27529Y604722D01*
G01X8858Y613945D02*
X14252D01*
X15376Y615069D01*
X26531D01*
X27529Y614071D01*
G01X8858Y617095D02*
X14551D01*
X15376Y616270D01*
X26528D01*
X27529Y617271D01*
G01X8858Y626544D02*
X14401D01*
X15575Y627718D01*
X26530D01*
X27529Y626719D01*
G01X8858Y629693D02*
X14401D01*
X15175Y628919D01*
X26529D01*
X27529Y629919D01*
G01X8858Y664339D02*
X14401D01*
X15575Y665513D01*
X26531D01*
X27529Y664515D01*
G01X8858Y667489D02*
X14400D01*
X15175Y666714D01*
X26528D01*
X27529Y667715D01*
G01X8858Y676937D02*
X14401D01*
X15575Y678111D01*
X26531D01*
X27529Y677113D01*
G01X8858Y680087D02*
X14400D01*
X15175Y679312D01*
X26528D01*
X27529Y680313D01*
G01X8858Y689536D02*
X14401D01*
X15575Y690710D01*
X26530D01*
X27529Y689711D01*
G01X8858Y692685D02*
X14401D01*
X15175Y691911D01*
X26529D01*
X27529Y692911D01*
G01X8858Y702134D02*
X14401D01*
X15575Y703308D01*
X26531D01*
X27529Y702310D01*
G01X8858Y639142D02*
X14401D01*
X15575Y640316D01*
X26531D01*
X27529Y639318D01*
G01X8858Y642292D02*
X14400D01*
X15175Y641517D01*
X26528D01*
X27529Y642518D01*
G01X8858Y714733D02*
X14403D01*
X15376Y715706D01*
X26531D01*
X27529Y714708D01*
G01X8858Y717882D02*
X14401D01*
X15376Y716907D01*
X26528D01*
X27529Y717908D01*
G01X8858Y727331D02*
X14402D01*
X15376Y728305D01*
X26531D01*
X27529Y727307D01*
G01X8858Y730481D02*
X14401D01*
X15376Y729506D01*
X26528D01*
X27529Y730507D01*
G01X8858Y758827D02*
X14402D01*
X15376Y759801D01*
X26531D01*
X27529Y758803D01*
G01X8858Y761977D02*
X14401D01*
X15376Y761002D01*
X26528D01*
X27529Y762003D01*
G01X8858Y705284D02*
X14400D01*
X15175Y704509D01*
X26528D01*
X27529Y705510D01*
G01X8858Y771426D02*
X14403D01*
X15376Y772399D01*
X26531D01*
X27529Y771401D01*
G01X8858Y774575D02*
X14401D01*
X15376Y773600D01*
X26528D01*
X27529Y774601D01*
G01X8858Y843867D02*
X14603D01*
X15376Y844640D01*
X26531D01*
X27529Y843642D01*
G01X8858Y847016D02*
X14201D01*
X15376Y845841D01*
X26528D01*
X27529Y846842D01*
G01X8858Y793473D02*
X14403D01*
X15376Y794446D01*
X26531D01*
X27529Y793448D01*
G01X8858Y796622D02*
X14401D01*
X15376Y795647D01*
X26528D01*
X27529Y796648D01*
G01X8858Y806071D02*
X14402D01*
X15376Y807045D01*
X26531D01*
X27529Y806047D01*
G01X8858Y809221D02*
X14401D01*
X15376Y808246D01*
X26528D01*
X27529Y809247D01*
G01X8858Y818670D02*
X14403D01*
X15376Y819643D01*
X26531D01*
X27529Y818645D01*
G01X8858Y821819D02*
X14401D01*
X15376Y820844D01*
X26528D01*
X27529Y821845D01*
G01X8858Y831268D02*
X14402D01*
X15376Y832242D01*
X26531D01*
X27529Y831244D01*
G01X8858Y834418D02*
X14401D01*
X15376Y833443D01*
X26528D01*
X27529Y834444D01*
G01X8858Y894260D02*
X14402D01*
X15376Y895234D01*
X26531D01*
X27529Y894236D01*
G01X8858Y897410D02*
X14401D01*
X15376Y896435D01*
X26528D01*
X27529Y897436D01*
G01X8858Y856465D02*
X14602D01*
X15376Y857239D01*
X26531D01*
X27529Y856241D01*
G01X8858Y859615D02*
X14201D01*
X15376Y858440D01*
X26528D01*
X27529Y859441D01*
G01X8858Y906859D02*
X14403D01*
X15376Y907832D01*
X26531D01*
X27529Y906834D01*
G01X8858Y910008D02*
X14401D01*
X15376Y909033D01*
X26528D01*
X27529Y910034D01*
G01X8858Y869063D02*
X14602D01*
X15376Y869837D01*
X26531D01*
X27529Y868839D01*
G01X8858Y872213D02*
X14201D01*
X15376Y871038D01*
X26528D01*
X27529Y872039D01*
G01X8858Y881662D02*
X14553D01*
X15376Y882485D01*
X26531D01*
X27529Y881487D01*
G01X8858Y884811D02*
X14251D01*
X15376Y883686D01*
X26528D01*
X27529Y884687D01*
G01X26600Y1488350D02*
X27834Y1487116D01*
Y1480467D01*
X43310Y1464991D01*
Y1288491D01*
X47877Y1283924D01*
Y1186395D01*
X52810Y1181462D01*
Y1058009D01*
X47002Y1052201D01*
X25002D01*
X11799Y1038998D01*
Y1018201D01*
X41438Y988562D01*
Y791638D01*
X54842Y778234D01*
Y397959D01*
X62001Y390800D01*
X182300D01*
X189500Y398000D01*
X303650D01*
X305100Y396550D01*
G01X30200Y1488350D02*
X29035Y1487185D01*
Y1480965D01*
X44511Y1465489D01*
Y1288989D01*
X49078Y1284422D01*
Y1186893D01*
X54011Y1181960D01*
Y1057511D01*
X47500Y1051000D01*
X25500D01*
X13000Y1038500D01*
Y1018699D01*
X42639Y989060D01*
Y792136D01*
X56043Y778732D01*
Y398457D01*
X62499Y392001D01*
X181802D01*
X189002Y399201D01*
X226358D01*
X226861Y399704D01*
X228925D01*
X229428Y399201D01*
X231492D01*
X231995Y399704D01*
X234059D01*
X234562Y399201D01*
X253181D01*
X253684Y399704D01*
X255748D01*
X256251Y399201D01*
X258315D01*
X258818Y399704D01*
X260882D01*
X261385Y399201D01*
X283402D01*
X283905Y399704D01*
X285969D01*
X286472Y399201D01*
X288536D01*
X289039Y399704D01*
X291103D01*
X291606Y399201D01*
X303751D01*
X305100Y400550D01*
G01X8858Y1135205D02*
X14402D01*
X15376Y1136179D01*
X26531D01*
X27529Y1135181D01*
G01X8858Y1138355D02*
X14401D01*
X15376Y1137380D01*
X26528D01*
X27529Y1138381D01*
G01X8858Y1097410D02*
X14110D01*
X15234Y1098534D01*
X26580D01*
X27529Y1097585D01*
G01X8858Y1100559D02*
X14401D01*
X15225Y1099735D01*
X26479D01*
X27529Y1100785D01*
G01Y1110184D02*
X26614Y1111099D01*
X15492D01*
X14401Y1110008D01*
X8858D01*
G01X27529Y1113384D02*
X26445Y1112300D01*
X15258D01*
X14400Y1113158D01*
X8858D01*
G01Y1185599D02*
X14403D01*
X15376Y1186572D01*
X26531D01*
X27529Y1185574D01*
G01X8858Y1188748D02*
X14401D01*
X15376Y1187773D01*
X26528D01*
X27529Y1188774D01*
G01X8858Y1147804D02*
X14403D01*
X15376Y1148777D01*
X26531D01*
X27529Y1147779D01*
G01X8858Y1150953D02*
X14401D01*
X15376Y1149978D01*
X26528D01*
X27529Y1150979D01*
G01X8858Y1198197D02*
X14402D01*
X15376Y1199171D01*
X26531D01*
X27529Y1198173D01*
G01X8858Y1201347D02*
X14401D01*
X15376Y1200372D01*
X26528D01*
X27529Y1201373D01*
G01X8858Y1160402D02*
X14402D01*
X15376Y1161376D01*
X26531D01*
X27529Y1160378D01*
G01X8858Y1163552D02*
X14401D01*
X15376Y1162577D01*
X26528D01*
X27529Y1163578D01*
G01X8858Y1210796D02*
X14403D01*
X15376Y1211769D01*
X26531D01*
X27529Y1210771D01*
G01X8858Y1173000D02*
X14402D01*
X15376Y1173974D01*
X26531D01*
X27529Y1172976D01*
G01X8858Y1176150D02*
X14401D01*
X15376Y1175175D01*
X26528D01*
X27529Y1176176D01*
G01X8858Y1254890D02*
X14402D01*
X15376Y1255864D01*
X26531D01*
X27529Y1254866D01*
G01X8858Y1258040D02*
X14401D01*
X15376Y1257065D01*
X26528D01*
X27529Y1258066D01*
G01X8858Y1267489D02*
X14403D01*
X15376Y1268462D01*
X26531D01*
X27529Y1267464D01*
G01X8858Y1270638D02*
X14401D01*
X15376Y1269663D01*
X26528D01*
X27529Y1270664D01*
G01X8858Y1280087D02*
X14402D01*
X15376Y1281061D01*
X26531D01*
X27529Y1280063D01*
G01X8858Y1283237D02*
X14401D01*
X15376Y1282262D01*
X26528D01*
X27529Y1283263D01*
G01X8858Y1213945D02*
X14401D01*
X15376Y1212970D01*
X26528D01*
X27529Y1213971D01*
G01X8858Y1223394D02*
X14402D01*
X15376Y1224368D01*
X26531D01*
X27529Y1223370D01*
G01X8858Y1226544D02*
X14401D01*
X15376Y1225569D01*
X26528D01*
X27529Y1226570D01*
G01X8858Y1314733D02*
X14401D01*
X15575Y1315907D01*
X26530D01*
X27529Y1314908D01*
G01X8858Y1317882D02*
X14401D01*
X15175Y1317108D01*
X26529D01*
X27529Y1318108D01*
G01X8858Y1327331D02*
X14401D01*
X15575Y1328505D01*
X26531D01*
X27529Y1327507D01*
G01X8858Y1330481D02*
X14400D01*
X15175Y1329706D01*
X26528D01*
X27529Y1330707D01*
G01X8858Y1339930D02*
X14401D01*
X15575Y1341104D01*
X26530D01*
X27529Y1340105D01*
G01X8858Y1343079D02*
X14401D01*
X15175Y1342305D01*
X26529D01*
X27529Y1343305D01*
G01X8858Y1352528D02*
X14401D01*
X15575Y1353702D01*
X26531D01*
X27529Y1352704D01*
G01X8858Y1355678D02*
X14400D01*
X15175Y1354903D01*
X26528D01*
X27529Y1355904D01*
G01X8858Y1292685D02*
X14402D01*
X15376Y1293659D01*
X26531D01*
X27529Y1292661D01*
G01X8858Y1295835D02*
X14401D01*
X15376Y1294860D01*
X26528D01*
X27529Y1295861D01*
G01X8858Y1365126D02*
X14402D01*
X15376Y1366100D01*
X26531D01*
X27529Y1365102D01*
G01X8858Y1368276D02*
X14401D01*
X15376Y1367301D01*
X26528D01*
X27529Y1368302D01*
G01X8858Y1377725D02*
X14403D01*
X15376Y1378698D01*
X26531D01*
X27529Y1377700D01*
G01X8858Y1380874D02*
X14401D01*
X15376Y1379899D01*
X26528D01*
X27529Y1380900D01*
G01X8858Y1390323D02*
X14402D01*
X15376Y1391297D01*
X26531D01*
X27529Y1390299D01*
G01X8858Y1393473D02*
X14401D01*
X15376Y1392498D01*
X26528D01*
X27529Y1393499D01*
G01X8858Y1402922D02*
X14401D01*
X15375Y1403896D01*
X26530D01*
X27529Y1402897D01*
G01X8858Y1406071D02*
X14401D01*
X15375Y1405097D01*
X26529D01*
X27529Y1406097D01*
G01X304500Y826050D02*
X303121Y827429D01*
X190628D01*
X159599Y796400D01*
X69501D01*
X55499Y810402D01*
Y1052934D01*
X58299Y1055734D01*
Y1185503D01*
X53366Y1190436D01*
Y1286312D01*
X48799Y1290879D01*
Y1470201D01*
X35199Y1483801D01*
Y1503002D01*
X33999Y1504202D01*
Y1509301D01*
X32850Y1510450D01*
G01X304500Y830050D02*
X303080Y828630D01*
X280823D01*
X280250Y829203D01*
X278326D01*
X277753Y828630D01*
X275689D01*
X275186Y829133D01*
X273122D01*
X272619Y828630D01*
X190130D01*
X159101Y797601D01*
X69999D01*
X56700Y810900D01*
Y1052436D01*
X59500Y1055236D01*
Y1186001D01*
X54567Y1190934D01*
Y1286810D01*
X50000Y1291377D01*
Y1470699D01*
X36400Y1484299D01*
Y1491295D01*
X37039Y1491934D01*
Y1493726D01*
X36400Y1494365D01*
Y1496429D01*
X36986Y1497015D01*
Y1498913D01*
X36400Y1499499D01*
Y1503500D01*
X35200Y1504700D01*
Y1509300D01*
X36350Y1510450D01*
G01X26600Y1491850D02*
X27799Y1493049D01*
Y1497899D01*
X27296Y1498402D01*
Y1500466D01*
X27799Y1500969D01*
Y1503033D01*
X27214Y1503618D01*
Y1505518D01*
X27799Y1506103D01*
Y1508167D01*
X27196Y1508770D01*
Y1510634D01*
X27799Y1511237D01*
Y1513301D01*
X25201Y1515899D01*
X20702D01*
X20199Y1515396D01*
X18135D01*
X17632Y1515899D01*
X15568D01*
X14401Y1514732D01*
X8858D01*
G01X30200Y1491850D02*
X29000Y1493050D01*
Y1513799D01*
X25699Y1517100D01*
X15182D01*
X14401Y1517881D01*
X8858D01*
G01Y1524181D02*
X14401D01*
X15375Y1525155D01*
X26530D01*
X27529Y1524156D01*
G01X8858Y1527330D02*
X14401D01*
X15375Y1526356D01*
X26529D01*
X27529Y1527356D01*
G01X8858Y1536779D02*
X14402D01*
X15376Y1537753D01*
X26531D01*
X27529Y1536755D01*
G01X8858Y1539929D02*
X14401D01*
X15376Y1538954D01*
X26528D01*
X27529Y1539955D01*
G01X8858Y1549378D02*
X14401D01*
X15375Y1550352D01*
X26530D01*
X27529Y1549353D01*
G01X8858Y1552527D02*
X14401D01*
X15375Y1551553D01*
X26529D01*
X27529Y1552553D01*
G01X8858Y1561976D02*
X14402D01*
X15376Y1562950D01*
X26531D01*
X27529Y1561952D01*
G01X8858Y1565126D02*
X14401D01*
X15376Y1564151D01*
X26528D01*
X27529Y1565152D01*
G01X32850Y1513950D02*
X33999Y1515099D01*
Y1517125D01*
X33001Y1518123D01*
G01X36201D02*
X35200Y1517122D01*
Y1515100D01*
X36350Y1513950D01*
G01X8858Y1634417D02*
X14402D01*
X15376Y1635391D01*
X26531D01*
X27529Y1634393D01*
G01X8858Y1637567D02*
X14401D01*
X15376Y1636592D01*
X26528D01*
X27529Y1637593D01*
G01X8858Y1587173D02*
X14401D01*
X15376Y1586198D01*
X26528D01*
X27529Y1587199D01*
G01X8858Y1584023D02*
X14402D01*
X15376Y1584997D01*
X26531D01*
X27529Y1583999D01*
G01X8858Y1599771D02*
X14401D01*
X15375Y1598797D01*
X26529D01*
X27529Y1599797D01*
G01X8858Y1596622D02*
X14401D01*
X15375Y1597596D01*
X26530D01*
X27529Y1596597D01*
G01X8858Y1612370D02*
X14401D01*
X15376Y1611395D01*
X26528D01*
X27529Y1612396D01*
G01X8858Y1609220D02*
X14402D01*
X15376Y1610194D01*
X26531D01*
X27529Y1609196D01*
G01X8858Y1624968D02*
X14401D01*
X15376Y1623993D01*
X26528D01*
X27529Y1624994D01*
G01X8858Y1621818D02*
X14402D01*
X15376Y1622792D01*
X26531D01*
X27529Y1621794D01*
G01X8858Y1719456D02*
X14056D01*
X15222Y1720622D01*
X26530D01*
X27529Y1719623D01*
G01Y1672379D02*
X26609Y1673299D01*
X15488D01*
X14401Y1672212D01*
X8858D01*
G01X27529Y1675579D02*
X26450Y1674500D01*
X15264D01*
X14402Y1675362D01*
X8858D01*
G01X27529Y1684977D02*
X26607Y1685899D01*
X15489D01*
X14401Y1684811D01*
X8858D01*
G01X27529Y1688177D02*
X26452Y1687100D01*
X15261D01*
X14401Y1687960D01*
X8858D01*
G01X27529Y1697576D02*
X26606Y1698499D01*
X15491D01*
X14401Y1697409D01*
X8858D01*
G01X27529Y1700776D02*
X26453Y1699700D01*
X15261D01*
X14402Y1700559D01*
X8858D01*
G01X32950Y1778850D02*
X34100Y1777700D01*
X43900D01*
X72311Y1806111D01*
X76747D01*
X81136Y1810500D01*
X105249D01*
X127839Y1787910D01*
Y1773636D01*
X201845Y1699630D01*
X284030D01*
X285000Y1700600D01*
G01X32950Y1775350D02*
X34099Y1776499D01*
X44398D01*
X72809Y1804910D01*
X77245D01*
X81634Y1809299D01*
X104751D01*
X126638Y1787412D01*
Y1773138D01*
X201347Y1698429D01*
X283971D01*
X285000Y1697400D01*
G01X8858Y1722606D02*
X14402D01*
X15185Y1721823D01*
X26529D01*
X27529Y1722823D01*
G01X8858Y1735204D02*
X14401D01*
X15184Y1734421D01*
X26529D01*
X27529Y1735421D01*
G01X8858Y1732055D02*
X14401D01*
X15566Y1733220D01*
X26530D01*
X27529Y1732221D01*
G01X8858Y1747803D02*
X14402D01*
X15185Y1747020D01*
X26529D01*
X27529Y1748020D01*
G01X8858Y1744653D02*
X14401D01*
X15567Y1745819D01*
X26530D01*
X27529Y1744820D01*
G01X8858Y1760401D02*
X14401D01*
X15184Y1759618D01*
X26529D01*
X27529Y1760618D01*
G01X8858Y1757252D02*
X14401D01*
X15566Y1758417D01*
X26530D01*
X27529Y1757418D01*
G01X54872Y1678298D02*
X56000Y1679426D01*
Y1696954D01*
X46299Y1706655D01*
Y1715321D01*
X45796Y1715824D01*
Y1717888D01*
X46299Y1718391D01*
Y1720455D01*
X45796Y1720958D01*
Y1723022D01*
X46299Y1723525D01*
Y1747002D01*
X42453Y1750848D01*
X41728D01*
X40268Y1752307D01*
Y1753033D01*
X38809Y1754492D01*
X38083D01*
X36624Y1755952D01*
Y1756677D01*
X35164Y1758137D01*
X34506D01*
X32979Y1759664D01*
Y1760322D01*
X26499Y1766802D01*
Y1768559D01*
X25500Y1769558D01*
G01X58372Y1678298D02*
X57201Y1679469D01*
Y1697452D01*
X47500Y1707153D01*
Y1747500D01*
X27700Y1767300D01*
Y1768558D01*
X28700Y1769558D01*
G01X29450Y1778850D02*
X28301Y1777701D01*
X25002D01*
X16188Y1768887D01*
X15365D01*
X14402Y1769850D01*
X8858D01*
G01X29450Y1775350D02*
X28300Y1776500D01*
X25500D01*
X16686Y1767686D01*
X15387D01*
X14401Y1766700D01*
X8858D01*
G01X395000Y364250D02*
X393500Y362750D01*
Y361199D01*
X400201Y354498D01*
Y266701D01*
X243200Y109700D01*
X118300D01*
X109096Y118904D01*
Y142594D01*
X111299Y144797D01*
Y159701D01*
X108569Y162431D01*
X95000D01*
X94025Y161456D01*
X89764D01*
G01X391000Y364250D02*
X392299Y362951D01*
Y360701D01*
X399000Y354000D01*
Y267199D01*
X242702Y110901D01*
X189836D01*
X189333Y111404D01*
X187269D01*
X186766Y110901D01*
X184702D01*
X184199Y111404D01*
X182135D01*
X181632Y110901D01*
X136777D01*
X136274Y111404D01*
X134210D01*
X133707Y110901D01*
X131643D01*
X131140Y111404D01*
X129076D01*
X128573Y110901D01*
X126509D01*
X126006Y111404D01*
X123942D01*
X123439Y110901D01*
X118798D01*
X110297Y119402D01*
Y142096D01*
X112500Y144299D01*
Y160199D01*
X109067Y163632D01*
X95000D01*
X94026Y164606D01*
X89764D01*
G01Y95315D02*
X94615D01*
X95590Y94340D01*
X97900D01*
X99500Y95940D01*
G01X89764Y92165D02*
X94000D01*
X95590Y93139D01*
X97901D01*
X99500Y91540D01*
G01X89764Y76417D02*
X94000D01*
X94975Y75442D01*
X97900D01*
X99500Y77042D01*
G01X89764Y73267D02*
X94000D01*
X94974Y74241D01*
X97901D01*
X99500Y72642D01*
G01Y58244D02*
X97900Y56644D01*
X95308D01*
X94433Y57519D01*
X89764D01*
G01X99500Y53844D02*
X97901Y55443D01*
X95543D01*
X94470Y54370D01*
X89764D01*
G01Y104763D02*
X94026D01*
X95000Y103789D01*
X104001D01*
X105000Y104788D01*
G01X89764Y101614D02*
X94000D01*
X94974Y102588D01*
X104000D01*
X105000Y101588D01*
G01X89764Y85866D02*
X94025D01*
X95000Y84891D01*
X104000D01*
X105000Y85891D01*
G01X89764Y82716D02*
X94000D01*
X94974Y83690D01*
X104001D01*
X105000Y82691D01*
G01X89764Y66968D02*
X94025D01*
X95000Y65993D01*
X104000D01*
X105000Y66993D01*
G01X89764Y63818D02*
X94000D01*
X94974Y64792D01*
X104001D01*
X105000Y63793D01*
G01X77205Y128385D02*
X72973D01*
X72000Y129358D01*
X68999D01*
X68000Y128359D01*
G01X77205Y131535D02*
X72976D01*
X72000Y130559D01*
X69000D01*
X68000Y131559D01*
G01X89764Y145708D02*
X94402D01*
X95376Y144734D01*
X97901D01*
X99500Y146333D01*
G01X89764Y142559D02*
X94000D01*
X95440Y143533D01*
X97900D01*
X99500Y141933D01*
G01X89764Y155157D02*
X94025D01*
X95000Y154182D01*
X104000D01*
X105000Y155182D01*
G01X89764Y152007D02*
X94000D01*
X94974Y152981D01*
X104001D01*
X105000Y151982D01*
G01X89764Y481929D02*
X94611D01*
X95586Y480954D01*
X97900D01*
X99500Y482554D01*
G01X89764Y478779D02*
X94258D01*
X95738Y479753D01*
X97901D01*
X99500Y478154D01*
G01X89764Y463031D02*
X94519D01*
X95493Y462057D01*
X97901D01*
X99500Y463656D01*
G01X89764Y459882D02*
X94026D01*
X95540Y460856D01*
X97900D01*
X99500Y459256D01*
G01X89764Y472480D02*
X94025D01*
X95000Y471505D01*
X104000D01*
X105000Y472505D01*
G01X89764Y469330D02*
X94000D01*
X94974Y470304D01*
X104001D01*
X105000Y469305D01*
G01X340500Y435750D02*
X341850Y437100D01*
Y438951D01*
X337299Y443502D01*
Y468002D01*
X318502Y486799D01*
X152502D01*
X118560Y520741D01*
X117848D01*
X116389Y522201D01*
Y522912D01*
X114929Y524372D01*
X114218D01*
X112758Y525831D01*
Y526543D01*
X111299Y528002D01*
Y540474D01*
X110796Y540977D01*
Y543041D01*
X111299Y543544D01*
Y545608D01*
X110796Y546111D01*
Y548175D01*
X111299Y548678D01*
Y550742D01*
X110796Y551245D01*
Y553309D01*
X111299Y553812D01*
Y565002D01*
X108358Y567943D01*
X94975D01*
X94000Y566968D01*
X89764D01*
G01X77205Y533897D02*
X72973D01*
X72000Y534870D01*
X68999D01*
X68000Y533871D01*
G01X77205Y537047D02*
X72976D01*
X72000Y536071D01*
X69000D01*
X68000Y537071D01*
G01X99500Y551845D02*
X97755Y550100D01*
X95146D01*
X94026Y551220D01*
X89764D01*
G01X99500Y547445D02*
X98046Y548899D01*
X94899D01*
X94071Y548071D01*
X89764D01*
G01Y500827D02*
X94373D01*
X95348Y499852D01*
X97900D01*
X99500Y501452D01*
G01X89764Y497677D02*
X94000D01*
X95390Y498651D01*
X97901D01*
X99500Y497052D01*
G01X89764Y510275D02*
X94026D01*
X95000Y509301D01*
X104001D01*
X105000Y510300D01*
G01X89764Y507126D02*
X94000D01*
X94974Y508100D01*
X104000D01*
X105000Y507100D01*
G01X89764Y491378D02*
X94122D01*
X95097Y490403D01*
X104000D01*
X105000Y491403D01*
G01X89764Y488228D02*
X94026D01*
X95000Y489202D01*
X104001D01*
X105000Y488203D01*
G01X344500Y435750D02*
X344400D01*
X343051Y437099D01*
Y439449D01*
X338500Y444000D01*
Y468500D01*
X319000Y488000D01*
X153000D01*
X112500Y528500D01*
Y565500D01*
X108856Y569144D01*
X94974D01*
X94000Y570118D01*
X89764D01*
G01Y560669D02*
X94671D01*
X95646Y559694D01*
X104000D01*
X105000Y560694D01*
G01X89764Y557519D02*
X94617D01*
X95591Y558493D01*
X104001D01*
X105000Y557494D01*
G01X89764Y906339D02*
X94025D01*
X95000Y905364D01*
X97900D01*
X99500Y906964D01*
G01X89764Y903189D02*
X94000D01*
X94974Y904163D01*
X97901D01*
X99500Y902564D01*
G01X89764Y887441D02*
X94059D01*
X95034Y886466D01*
X97900D01*
X99500Y888066D01*
G01X89764Y884291D02*
X94000D01*
X94974Y885265D01*
X97901D01*
X99500Y883666D01*
G01X89764Y868543D02*
X94026D01*
X95000Y867569D01*
X97901D01*
X99500Y869168D01*
G01X89764Y865394D02*
X94000D01*
X94974Y866368D01*
X97900D01*
X99500Y864768D01*
G01X89764Y915787D02*
X94026D01*
X95000Y914813D01*
X104001D01*
X105000Y915812D01*
G01X89764Y912638D02*
X94000D01*
X94974Y913612D01*
X104000D01*
X105000Y912612D01*
G01X89764Y896890D02*
X94000D01*
X94975Y895915D01*
X104000D01*
X105000Y896915D01*
G01X89764Y893740D02*
X94000D01*
X94974Y894714D01*
X104001D01*
X105000Y893715D01*
G01X89764Y877992D02*
X94000D01*
X94975Y877017D01*
X104000D01*
X105000Y878017D01*
G01X89764Y874842D02*
X93842D01*
X94816Y875816D01*
X104001D01*
X105000Y874817D01*
G01X340500Y865750D02*
X341799Y867049D01*
Y869302D01*
X337299Y873802D01*
Y898362D01*
X315362Y920299D01*
X161502D01*
X137228Y944573D01*
X136517D01*
X135058Y946032D01*
Y946743D01*
X133598Y948203D01*
X132887D01*
X131427Y949662D01*
Y950374D01*
X124356Y957445D01*
X123645D01*
X122185Y958904D01*
Y959616D01*
X120726Y961075D01*
X120015D01*
X118555Y962535D01*
Y963246D01*
X117096Y964705D01*
X116384D01*
X114925Y966165D01*
Y966876D01*
X108346Y973455D01*
X95000D01*
X94025Y972480D01*
X89764D01*
G01X344500Y865750D02*
X343000Y867250D01*
Y869800D01*
X338500Y874300D01*
Y898860D01*
X315860Y921500D01*
X162000D01*
X108844Y974656D01*
X95000D01*
X94026Y975630D01*
X89764D01*
G01X77205Y939409D02*
X73000D01*
X72027Y940382D01*
X68999D01*
X68000Y939383D01*
G01X77205Y942559D02*
X72976D01*
X72000Y941583D01*
X69000D01*
X68000Y942583D01*
G01X89764Y956732D02*
X94268D01*
X95242Y955758D01*
X97901D01*
X99500Y957357D01*
G01X89764Y953583D02*
X94000D01*
X94974Y954557D01*
X97900D01*
X99500Y952957D01*
G01X89764Y966181D02*
X94025D01*
X95000Y965206D01*
X104000D01*
X105000Y966206D01*
G01X89764Y963031D02*
X94000D01*
X94974Y964005D01*
X104001D01*
X105000Y963006D01*
G01X54872Y1674798D02*
X56000Y1673670D01*
Y1475200D01*
X54342Y1473542D01*
Y1293100D01*
X58855Y1288587D01*
Y1207046D01*
X63701Y1202200D01*
X296701D01*
X299972Y1198929D01*
X303771D01*
X305200Y1197500D01*
G01X58372Y1674798D02*
X57201Y1673627D01*
Y1607658D01*
X57657Y1607202D01*
Y1605044D01*
X57201Y1604588D01*
Y1602524D01*
X57639Y1602086D01*
Y1599892D01*
X57201Y1599454D01*
Y1597390D01*
X57704Y1596887D01*
Y1594823D01*
X57201Y1594320D01*
Y1507644D01*
X57704Y1507141D01*
Y1505077D01*
X57201Y1504574D01*
Y1502510D01*
X57704Y1502007D01*
Y1499943D01*
X57201Y1499440D01*
Y1474702D01*
X55543Y1473044D01*
Y1293598D01*
X60056Y1289085D01*
Y1207544D01*
X64199Y1203401D01*
X297199D01*
X300470Y1200130D01*
X303830D01*
X305200Y1201500D01*
G01X99500Y1274680D02*
X97863Y1273043D01*
X95038D01*
X94026Y1274055D01*
X89764D01*
G01X99500Y1270280D02*
X97938Y1271842D01*
X94936D01*
X94000Y1270906D01*
X89764D01*
G01Y1283504D02*
X94025D01*
X95000Y1282529D01*
X104000D01*
X105000Y1283529D01*
G01X89764Y1280354D02*
X94000D01*
X94974Y1281328D01*
X104001D01*
X105000Y1280329D01*
G01X77205Y1344921D02*
X73000D01*
X72027Y1345894D01*
X68999D01*
X68000Y1344895D01*
G01X77205Y1348071D02*
X72976D01*
X72000Y1347095D01*
X69000D01*
X68000Y1348095D01*
G01X89764Y1311851D02*
X94479D01*
X95454Y1310876D01*
X97900D01*
X99500Y1312476D01*
G01X89764Y1308701D02*
X94000D01*
X95450Y1309675D01*
X97901D01*
X99500Y1308076D01*
G01Y1293578D02*
X97852Y1291930D01*
X95070D01*
X94047Y1292953D01*
X89764D01*
G01X99500Y1289178D02*
X97949Y1290729D01*
X94926D01*
X94000Y1289803D01*
X89764D01*
G01Y1321299D02*
X94026D01*
X95000Y1320325D01*
X104001D01*
X105000Y1321324D01*
G01X89764Y1318150D02*
X94000D01*
X94974Y1319124D01*
X104000D01*
X105000Y1318124D01*
G01X89764Y1302402D02*
X94025D01*
X95000Y1301427D01*
X104000D01*
X105000Y1302427D01*
G01X89764Y1299252D02*
X94000D01*
X94974Y1300226D01*
X104001D01*
X105000Y1299227D01*
G01X340500Y1237250D02*
X341900Y1238650D01*
Y1240401D01*
X337299Y1245002D01*
Y1269502D01*
X288502Y1318299D01*
X130202D01*
X126500Y1322000D01*
X119761Y1328739D01*
X119049D01*
X117590Y1330199D01*
Y1330910D01*
X116130Y1332370D01*
X115419D01*
X113959Y1333829D01*
Y1334541D01*
X112500Y1336000D01*
Y1351437D01*
X111997Y1351940D01*
Y1354004D01*
X112500Y1354507D01*
Y1356571D01*
X111997Y1357074D01*
Y1359138D01*
X112500Y1359641D01*
Y1361705D01*
X111997Y1362208D01*
Y1364272D01*
X112500Y1364775D01*
Y1374500D01*
X108033Y1378967D01*
X95332D01*
X94357Y1377992D01*
X89764D01*
G01X344500Y1237250D02*
X343101Y1238649D01*
Y1240899D01*
X338500Y1245500D01*
Y1270000D01*
X289000Y1319500D01*
X130700D01*
X121340Y1328860D01*
X113701Y1336498D01*
Y1374998D01*
X108531Y1380168D01*
X95332D01*
X94358Y1381142D01*
X89764D01*
G01X99500Y1362869D02*
X97931Y1361300D01*
X94944D01*
X94000Y1362244D01*
X89764D01*
G01X99500Y1358469D02*
X97870Y1360099D01*
X95004D01*
X94000Y1359095D01*
X89764D01*
G01Y1371693D02*
X94025D01*
X95000Y1370718D01*
X104000D01*
X105000Y1371718D01*
G01X89764Y1368543D02*
X94000D01*
X94974Y1369517D01*
X104001D01*
X105000Y1368518D01*
G01X89764Y1714213D02*
X94000D01*
X94974Y1715187D01*
X97901D01*
X99500Y1713588D01*
G01X89764Y1717363D02*
X94000D01*
X94975Y1716388D01*
X97900D01*
X99500Y1717988D01*
G01Y1694690D02*
X97801Y1696389D01*
X95074D01*
X94000Y1695315D01*
X89764D01*
G01X99500Y1699090D02*
X98000Y1697590D01*
X94900D01*
X94025Y1698465D01*
X89764D01*
G01Y1676418D02*
X94026D01*
X95000Y1677392D01*
X97900D01*
X99500Y1675792D01*
G01X89764Y1679567D02*
X93933D01*
X94907Y1678593D01*
X97901D01*
X99500Y1680192D01*
G01X105000Y1704739D02*
X103901Y1705838D01*
X95074D01*
X94000Y1704764D01*
X89764D01*
G01X105000Y1707939D02*
X104100Y1707039D01*
X94875D01*
X94000Y1707914D01*
X89764D01*
G01X105000Y1685841D02*
X103901Y1686940D01*
X95074D01*
X94000Y1685866D01*
X89764D01*
G01X105000Y1689041D02*
X104100Y1688141D01*
X94900D01*
X94025Y1689016D01*
X89764D01*
G01X359500Y1664250D02*
X358100Y1662850D01*
Y1661099D01*
X362701Y1656498D01*
Y1637201D01*
X351799Y1626299D01*
X205201D01*
X112000Y1719500D01*
Y1782000D01*
X109521Y1784479D01*
X94975D01*
X94000Y1783504D01*
X89764D01*
G01X355500Y1664250D02*
X356899Y1662851D01*
Y1660601D01*
X361500Y1656000D01*
Y1637699D01*
X351301Y1627500D01*
X205699D01*
X113201Y1719998D01*
Y1748892D01*
X113704Y1749395D01*
Y1751459D01*
X113201Y1751962D01*
Y1754026D01*
X113704Y1754529D01*
Y1756593D01*
X113201Y1757096D01*
Y1767096D01*
X113704Y1767599D01*
Y1769663D01*
X113201Y1770166D01*
Y1772230D01*
X113704Y1772733D01*
Y1774797D01*
X113201Y1775300D01*
Y1777364D01*
X113704Y1777867D01*
Y1779931D01*
X113201Y1780434D01*
Y1782498D01*
X110019Y1785680D01*
X95000D01*
X94026Y1786654D01*
X89764D01*
G01X77205Y1750433D02*
X72473D01*
X71500Y1751406D01*
X68999D01*
X68000Y1750407D01*
G01X77205Y1753583D02*
X72583D01*
X71607Y1752607D01*
X69000D01*
X68000Y1753607D01*
G01X99500Y1763981D02*
X97800Y1765681D01*
X95181D01*
X94107Y1764607D01*
X89764D01*
G01X99500Y1768381D02*
X98001Y1766882D01*
X94900D01*
X94026Y1767756D01*
X89764D01*
G01X105000Y1774030D02*
X103901Y1775129D01*
X95129D01*
X94055Y1774055D01*
X89764D01*
G01X105000Y1777230D02*
X104100Y1776330D01*
X95170D01*
X94295Y1777205D01*
X89764D01*
G01X105000Y1723636D02*
X103900Y1724736D01*
X95574D01*
X94500Y1723662D01*
X89764D01*
G01X105000Y1726836D02*
X104101Y1725937D01*
X95374D01*
X94500Y1726811D01*
X89764D01*
G01X380000Y364250D02*
X378500Y362750D01*
Y361000D01*
X375500Y358000D01*
Y265301D01*
X239559Y129360D01*
X125001D01*
X124000Y128359D01*
G01X376000Y364250D02*
X377299Y362951D01*
Y361498D01*
X374299Y358498D01*
Y265799D01*
X239061Y130561D01*
X162062D01*
X161559Y131064D01*
X159495D01*
X158992Y130561D01*
X156928D01*
X156425Y131064D01*
X154361D01*
X153858Y130561D01*
X143858D01*
X143355Y131064D01*
X141291D01*
X140788Y130561D01*
X138724D01*
X138221Y131064D01*
X136157D01*
X135654Y130561D01*
X133590D01*
X133087Y131064D01*
X131023D01*
X130520Y130561D01*
X124998D01*
X124000Y131559D01*
G01X359500Y364250D02*
X358300Y363050D01*
Y360700D01*
X363000Y356000D01*
Y294414D01*
X292337Y223751D01*
X205450D01*
X179699Y198000D01*
X147500D01*
X144299Y201201D01*
Y204998D01*
X146948Y207647D01*
X149000D01*
X149975Y208622D01*
X154331D01*
G01X355500Y364250D02*
X357099Y362651D01*
Y360202D01*
X361799Y355502D01*
Y294912D01*
X291839Y224952D01*
X289775D01*
X289272Y225455D01*
X287208D01*
X286705Y224952D01*
X266437D01*
X265934Y225455D01*
X263870D01*
X263367Y224952D01*
X261303D01*
X260800Y225455D01*
X258736D01*
X258233Y224952D01*
X256169D01*
X255666Y225455D01*
X253602D01*
X253099Y224952D01*
X243692D01*
X243189Y225455D01*
X241125D01*
X240622Y224952D01*
X238558D01*
X238055Y225455D01*
X235991D01*
X235488Y224952D01*
X233424D01*
X232921Y225455D01*
X230857D01*
X230354Y224952D01*
X220354D01*
X219851Y225455D01*
X217787D01*
X217284Y224952D01*
X215220D01*
X214717Y225455D01*
X212653D01*
X212150Y224952D01*
X210086D01*
X209583Y225455D01*
X207519D01*
X207016Y224952D01*
X204952D01*
X199334Y219334D01*
X198622D01*
X197163Y217874D01*
Y217163D01*
X190092Y210092D01*
X189381D01*
X187921Y208632D01*
Y207921D01*
X186462Y206462D01*
X185750D01*
X184291Y205002D01*
Y204291D01*
X182831Y202831D01*
X182120D01*
X180660Y201372D01*
Y200660D01*
X179201Y199201D01*
X147998D01*
X145500Y201699D01*
Y204500D01*
X147446Y206446D01*
X149000D01*
X149974Y205472D01*
X154331D01*
G01X166890Y241693D02*
X171026D01*
X172000Y240719D01*
X177281D01*
X179000Y239000D01*
Y236394D01*
X180000Y235394D01*
G01X166890Y238543D02*
X171000D01*
X171975Y239518D01*
X176783D01*
X177799Y238502D01*
Y236393D01*
X176800Y235394D01*
G01X154331Y224370D02*
X149974D01*
X149000Y225344D01*
X146194D01*
X144595Y223745D01*
G01X154331Y227519D02*
X149974D01*
X149000Y226545D01*
X146195D01*
X144595Y228145D01*
G01X154331Y214921D02*
X149975D01*
X149000Y215896D01*
X140095D01*
X139095Y214896D01*
G01X154331Y218071D02*
X149974D01*
X149000Y217097D01*
X140094D01*
X139095Y218096D01*
G01X154331Y265315D02*
X149974D01*
X149000Y266289D01*
X140094D01*
X139095Y265290D01*
G01X154331Y274763D02*
X149975D01*
X149000Y275738D01*
X146195D01*
X144595Y274138D01*
G01X154331Y277913D02*
X150000D01*
X149026Y276939D01*
X146194D01*
X144595Y278538D01*
G01X154331Y293661D02*
X149975D01*
X149000Y294636D01*
X146195D01*
X144595Y293036D01*
G01X154331Y296811D02*
X150000D01*
X149026Y295837D01*
X146194D01*
X144595Y297436D01*
G01X154331Y312559D02*
X150000D01*
X149026Y313533D01*
X146194D01*
X144595Y311934D01*
G01X154331Y315708D02*
X150000D01*
X149026Y314734D01*
X146195D01*
X144595Y316334D01*
G01X154331Y268464D02*
X149964D01*
X148990Y267490D01*
X140095D01*
X139095Y268490D01*
G01X154331Y284212D02*
X150000D01*
X149025Y285187D01*
X140095D01*
X139095Y284187D01*
G01X154331Y287362D02*
X150000D01*
X149026Y286388D01*
X140094D01*
X139095Y287387D01*
G01X154331Y303110D02*
X149975D01*
X149000Y304085D01*
X140095D01*
X139095Y303085D01*
G01X154331Y306260D02*
X149974D01*
X149000Y305286D01*
X140094D01*
X139095Y306285D01*
G01X355500Y435750D02*
X356800Y437050D01*
Y438800D01*
X360000Y442000D01*
Y465000D01*
X325718Y499282D01*
X165218D01*
X154976Y509524D01*
X154264D01*
X152805Y510984D01*
Y511695D01*
X151345Y513155D01*
X150634D01*
X149174Y514614D01*
Y515326D01*
X142103Y522397D01*
X141392D01*
X139933Y523856D01*
Y524567D01*
X138473Y526027D01*
X137762D01*
X136302Y527486D01*
Y528198D01*
X134843Y529657D01*
X134131D01*
X132672Y531117D01*
Y531828D01*
X129628Y534872D01*
X124999D01*
X124000Y533873D01*
G01X359500Y435750D02*
X358001Y437249D01*
Y438302D01*
X361201Y441502D01*
Y465498D01*
X326216Y500483D01*
X165716D01*
X130126Y536073D01*
X125000D01*
X124000Y537073D01*
G01X376000Y435750D02*
X377500Y437250D01*
Y438801D01*
X372799Y443502D01*
Y461502D01*
X325002Y509299D01*
X285002D01*
X190502Y603799D01*
X141502D01*
X138799Y606502D01*
Y610498D01*
X141460Y613159D01*
X149000D01*
X149975Y614134D01*
X154331D01*
G01X380000Y435750D02*
X378701Y437049D01*
Y439299D01*
X374000Y444000D01*
Y462000D01*
X325500Y510500D01*
X285500D01*
X214763Y581237D01*
Y581948D01*
X213304Y583408D01*
X212592D01*
X211133Y584867D01*
Y585579D01*
X209673Y587038D01*
X208962D01*
X201891Y594109D01*
Y594820D01*
X200431Y596280D01*
X199720D01*
X198261Y597739D01*
Y598451D01*
X196801Y599910D01*
X196090D01*
X194630Y601370D01*
Y602081D01*
X193171Y603541D01*
X192459D01*
X191000Y605000D01*
X142000D01*
X140000Y607000D01*
Y610000D01*
X141958Y611958D01*
X149042D01*
X150016Y610984D01*
X154331D01*
G01Y629882D02*
X149974D01*
X149000Y630856D01*
X146194D01*
X144595Y629257D01*
G01X154331Y620433D02*
X149975D01*
X149000Y621408D01*
X140095D01*
X139095Y620408D01*
G01X154331Y623583D02*
X149974D01*
X149000Y622609D01*
X140094D01*
X139095Y623608D01*
G01X166890Y647205D02*
X171026D01*
X172000Y646231D01*
X177281D01*
X179000Y644512D01*
Y641906D01*
X180000Y640906D01*
G01X166890Y644055D02*
X171000D01*
X171975Y645030D01*
X176783D01*
X177799Y644014D01*
Y641905D01*
X176800Y640906D01*
G01X154331Y633031D02*
X149974D01*
X149000Y632057D01*
X146195D01*
X144595Y633657D01*
G01X154331Y680275D02*
X149975D01*
X149000Y681250D01*
X146195D01*
X144595Y679650D01*
G01X154331Y683425D02*
X150000D01*
X149026Y682451D01*
X146194D01*
X144595Y684050D01*
G01X154331Y699173D02*
X150000D01*
X149025Y700148D01*
X146195D01*
X144595Y698548D01*
G01X154331Y702323D02*
X150000D01*
X149026Y701349D01*
X146194D01*
X144595Y702948D01*
G01X154331Y670827D02*
X149974D01*
X149000Y671801D01*
X140094D01*
X139095Y670802D01*
G01X154331Y673976D02*
X150000D01*
X149026Y673002D01*
X140095D01*
X139095Y674002D01*
G01X154331Y689724D02*
X149975D01*
X149000Y690699D01*
X140095D01*
X139095Y689699D01*
G01X154331Y692874D02*
X150000D01*
X149026Y691900D01*
X140094D01*
X139095Y692899D01*
G01X154331Y718071D02*
X150000D01*
X149026Y719045D01*
X146194D01*
X144595Y717446D01*
G01X154331Y721220D02*
X149974D01*
X149000Y720246D01*
X146195D01*
X144595Y721846D01*
G01X154331Y708622D02*
X150000D01*
X149025Y709597D01*
X140095D01*
X139095Y708597D01*
G01X154331Y711772D02*
X150000D01*
X149026Y710798D01*
X140094D01*
X139095Y711797D01*
G01X167000Y939309D02*
X167998Y940307D01*
X174494D01*
X180301Y934500D01*
X320801D01*
X360000Y895301D01*
Y872000D01*
X356900Y868900D01*
Y867150D01*
X355500Y865750D01*
G01X167000Y942509D02*
X168001Y941508D01*
X174992D01*
X180799Y935701D01*
X321299D01*
X361201Y895799D01*
Y871502D01*
X358101Y868402D01*
Y867149D01*
X359500Y865750D01*
G01X376000D02*
X377499Y867249D01*
Y868802D01*
X372799Y873502D01*
Y891502D01*
X319502Y944799D01*
X249802D01*
X185802Y1008799D01*
X145502D01*
X142799Y1011502D01*
Y1015998D01*
X145472Y1018671D01*
X149000D01*
X149975Y1019646D01*
X154331D01*
G01X380000Y865750D02*
X378700Y867050D01*
Y869300D01*
X374000Y874000D01*
Y892000D01*
X320000Y946000D01*
X250300D01*
X210063Y986237D01*
Y986948D01*
X208604Y988408D01*
X207892D01*
X206433Y989867D01*
Y990579D01*
X204973Y992038D01*
X204262D01*
X197191Y999109D01*
Y999820D01*
X195731Y1001280D01*
X195020D01*
X193561Y1002739D01*
Y1003451D01*
X192101Y1004910D01*
X191390D01*
X189930Y1006370D01*
Y1007081D01*
X188471Y1008541D01*
X187759D01*
X186300Y1010000D01*
X146000D01*
X144000Y1012000D01*
Y1015500D01*
X145970Y1017470D01*
X149000D01*
X149974Y1016496D01*
X154331D01*
G01X166890Y1052717D02*
X171000D01*
X171974Y1051743D01*
X177281D01*
X179000Y1050024D01*
Y1047418D01*
X180000Y1046418D01*
G01X166890Y1049567D02*
X171000D01*
X171975Y1050542D01*
X176783D01*
X177799Y1049526D01*
Y1047417D01*
X176800Y1046418D01*
G01X154331Y1035394D02*
X150106D01*
X149132Y1036368D01*
X146194D01*
X144595Y1034769D01*
G01X154331Y1038543D02*
X149974D01*
X149000Y1037569D01*
X146195D01*
X144595Y1039169D01*
G01X154331Y1025945D02*
X149975D01*
X149000Y1026920D01*
X140095D01*
X139095Y1025920D01*
G01X154331Y1029095D02*
X149974D01*
X149000Y1028121D01*
X140094D01*
X139095Y1029120D01*
G01X154331Y1085787D02*
X149975D01*
X149000Y1086762D01*
X146195D01*
X144595Y1085162D01*
G01X154331Y1088937D02*
X150000D01*
X149026Y1087963D01*
X146194D01*
X144595Y1089562D01*
G01X154331Y1104685D02*
X150000D01*
X149025Y1105660D01*
X146195D01*
X144595Y1104060D01*
G01X154331Y1107835D02*
X150000D01*
X149026Y1106861D01*
X146194D01*
X144595Y1108460D01*
G01X154331Y1123583D02*
X150000D01*
X149026Y1124557D01*
X146194D01*
X144595Y1122958D01*
G01X154331Y1126732D02*
X150000D01*
X149026Y1125758D01*
X146195D01*
X144595Y1127358D01*
G01X154331Y1076339D02*
X149974D01*
X149000Y1077313D01*
X140094D01*
X139095Y1076314D01*
G01X154331Y1079488D02*
X150000D01*
X149026Y1078514D01*
X140095D01*
X139095Y1079514D01*
G01X154331Y1095236D02*
X149975D01*
X149000Y1096211D01*
X140095D01*
X139095Y1095211D01*
G01X154331Y1098386D02*
X150000D01*
X149026Y1097412D01*
X140094D01*
X139095Y1098411D01*
G01X154331Y1114134D02*
X150000D01*
X149025Y1115109D01*
X140095D01*
X139095Y1114109D01*
G01X154331Y1117284D02*
X150000D01*
X149026Y1116310D01*
X140094D01*
X139095Y1117309D01*
G01X355500Y1237250D02*
X356900Y1238650D01*
Y1240400D01*
X360000Y1243500D01*
Y1266500D01*
X294795Y1331705D01*
X193704D01*
X193201Y1331202D01*
X191137D01*
X190634Y1331705D01*
X188570D01*
X188067Y1331202D01*
X186003D01*
X185500Y1331705D01*
X172995D01*
X172492Y1331202D01*
X170428D01*
X169925Y1331705D01*
X167861D01*
X167358Y1331202D01*
X165294D01*
X164791Y1331705D01*
X162727D01*
X162224Y1331202D01*
X160160D01*
X159657Y1331705D01*
X153096D01*
X138982Y1345819D01*
X130498D01*
X129500Y1344821D01*
G01X359500Y1237250D02*
X358101Y1238649D01*
Y1239902D01*
X361201Y1243002D01*
Y1266998D01*
X295293Y1332906D01*
X153594D01*
X139480Y1347020D01*
X130501D01*
X129500Y1348021D01*
G01X376000Y1237250D02*
X377499Y1238749D01*
Y1240302D01*
X372799Y1245002D01*
Y1263201D01*
X286701Y1349299D01*
X253299D01*
X188299Y1414299D01*
X145002D01*
X142799Y1416502D01*
Y1421998D01*
X144984Y1424183D01*
X149000D01*
X149975Y1425158D01*
X154331D01*
G01X380000Y1237250D02*
X378700Y1238550D01*
Y1240800D01*
X374000Y1245500D01*
Y1263699D01*
X287199Y1350500D01*
X253797D01*
X216805Y1387492D01*
Y1388203D01*
X215346Y1389663D01*
X214634D01*
X213175Y1391122D01*
Y1391834D01*
X211715Y1393293D01*
X211004D01*
X200063Y1404234D01*
Y1404945D01*
X198604Y1406405D01*
X197892D01*
X196433Y1407864D01*
Y1408575D01*
X194974Y1410035D01*
X194262D01*
X192803Y1411494D01*
Y1412206D01*
X191343Y1413665D01*
X190632D01*
X188797Y1415500D01*
X145500D01*
X144000Y1417000D01*
Y1421500D01*
X145482Y1422982D01*
X149026D01*
X150000Y1422008D01*
X154331D01*
G01X166890Y1458229D02*
X171026D01*
X172000Y1457255D01*
X177281D01*
X179000Y1455536D01*
Y1452930D01*
X180000Y1451930D01*
G01X166890Y1455079D02*
X171000D01*
X171975Y1456054D01*
X176783D01*
X177799Y1455038D01*
Y1452929D01*
X176800Y1451930D01*
G01X154331Y1440906D02*
X149974D01*
X149000Y1441880D01*
X146194D01*
X144595Y1440281D01*
G01X154331Y1444055D02*
X150055D01*
X149081Y1443081D01*
X146195D01*
X144595Y1444681D01*
G01X154331Y1491299D02*
X150000D01*
X149025Y1492274D01*
X146195D01*
X144595Y1490674D01*
G01X154331Y1494449D02*
X150000D01*
X149026Y1493475D01*
X146194D01*
X144595Y1495074D01*
G01X154331Y1431457D02*
X149975D01*
X149000Y1432432D01*
X140095D01*
X139095Y1431432D01*
G01X154331Y1434607D02*
X149974D01*
X149000Y1433633D01*
X140094D01*
X139095Y1434632D01*
G01X154331Y1481851D02*
X150000D01*
X149026Y1482825D01*
X140094D01*
X139095Y1481826D01*
G01X154331Y1485000D02*
X149974D01*
X149000Y1484026D01*
X140095D01*
X139095Y1485026D01*
G01X154331Y1500748D02*
X150000D01*
X149025Y1501723D01*
X140095D01*
X139095Y1500723D01*
G01X154331Y1510197D02*
X150000D01*
X149025Y1511172D01*
X146195D01*
X144595Y1509572D01*
G01X154331Y1513347D02*
X150000D01*
X149026Y1512373D01*
X146194D01*
X144595Y1513972D01*
G01X154331Y1529095D02*
X150000D01*
X149026Y1530069D01*
X146194D01*
X144595Y1528470D01*
G01X154331Y1532244D02*
X150000D01*
X149026Y1531270D01*
X146195D01*
X144595Y1532870D01*
G01X154331Y1503898D02*
X150000D01*
X149026Y1502924D01*
X140094D01*
X139095Y1503923D01*
G01X154331Y1519646D02*
X150000D01*
X149025Y1520621D01*
X140095D01*
X139095Y1519621D01*
G01X154331Y1522796D02*
X150000D01*
X149026Y1521822D01*
X140094D01*
X139095Y1522821D01*
G01X344500Y1664250D02*
X342900Y1662650D01*
Y1660900D01*
X340000Y1658000D01*
Y1648000D01*
X333299Y1641299D01*
X207258D01*
X206906Y1641651D01*
Y1641650D01*
X130799Y1717757D01*
Y1748502D01*
X127970Y1751331D01*
X125997D01*
X125000Y1750334D01*
G01X340500Y1664250D02*
X341699Y1663051D01*
Y1661398D01*
X338799Y1658498D01*
Y1648498D01*
X332801Y1642500D01*
X207756D01*
X141419Y1708837D01*
Y1709549D01*
X139959Y1711008D01*
X139248D01*
X137788Y1712468D01*
Y1713179D01*
X136329Y1714639D01*
X135617D01*
X134158Y1716098D01*
X132000Y1718255D01*
Y1733598D01*
X132503Y1734101D01*
Y1736165D01*
X132000Y1736668D01*
Y1738732D01*
X132503Y1739235D01*
Y1741299D01*
X132000Y1741802D01*
Y1743866D01*
X132503Y1744369D01*
Y1746433D01*
X132000Y1746936D01*
Y1749000D01*
X128468Y1752532D01*
X126002D01*
X125000Y1753534D01*
G01X154331Y1830670D02*
X149500D01*
X148525Y1829695D01*
X145996D01*
X143799Y1827498D01*
Y1823002D01*
X147002Y1819799D01*
X303002D01*
X337299Y1785502D01*
Y1743502D01*
X341900Y1738901D01*
Y1737150D01*
X340500Y1735750D01*
G01X344500D02*
X343101Y1737149D01*
Y1739399D01*
X338500Y1744000D01*
Y1786000D01*
X303500Y1821000D01*
X215666D01*
X215163Y1821503D01*
X213099D01*
X212596Y1821000D01*
X210532D01*
X210029Y1821503D01*
X207965D01*
X207462Y1821000D01*
X186216D01*
X185713Y1821503D01*
X183649D01*
X183146Y1821000D01*
X181082D01*
X180579Y1821503D01*
X178515D01*
X178012Y1821000D01*
X175948D01*
X175445Y1821503D01*
X173381D01*
X172878Y1821000D01*
X147500D01*
X145000Y1823500D01*
Y1827000D01*
X146494Y1828494D01*
X148506D01*
X149480Y1827520D01*
X154331D01*
G01X166890Y1863741D02*
X171526D01*
X172500Y1862767D01*
X177281D01*
X179000Y1861048D01*
Y1858442D01*
X180000Y1857442D01*
G01X166890Y1860591D02*
X171500D01*
X172475Y1861566D01*
X176783D01*
X177799Y1860550D01*
Y1858441D01*
X176800Y1857442D01*
G01X154331Y1849567D02*
X149500D01*
X148526Y1848593D01*
X146195D01*
X144595Y1850193D01*
G01X154331Y1846418D02*
X149474D01*
X148500Y1847392D01*
X146194D01*
X144595Y1845793D01*
G01X154331Y1840119D02*
X149474D01*
X148450Y1839095D01*
X140144D01*
X139095Y1840144D01*
G01X154331Y1836969D02*
X149475D01*
X148550Y1837894D01*
X140045D01*
X139095Y1836944D01*
G01X154331Y1899961D02*
X149500D01*
X148526Y1898987D01*
X146194D01*
X144595Y1900586D01*
G01X154331Y1896811D02*
X149500D01*
X148525Y1897786D01*
X146195D01*
X144595Y1896186D01*
G01X154331Y1918859D02*
X149500D01*
X148526Y1917885D01*
X146194D01*
X144595Y1919484D01*
G01X154331Y1915709D02*
X149500D01*
X148525Y1916684D01*
X146195D01*
X144595Y1915084D01*
G01X154331Y1937756D02*
X149500D01*
X148526Y1936782D01*
X146195D01*
X144595Y1938382D01*
G01X154331Y1934607D02*
X149500D01*
X148526Y1935581D01*
X146194D01*
X144595Y1933982D01*
G01X154331Y1890512D02*
X149474D01*
X148450Y1889488D01*
X140145D01*
X139095Y1890538D01*
G01X154331Y1887363D02*
X149474D01*
X148550Y1888287D01*
X140044D01*
X139095Y1887338D01*
G01X154331Y1909410D02*
X149000D01*
X147976Y1908386D01*
X140144D01*
X139095Y1909435D01*
G01X154331Y1906260D02*
X148975D01*
X148050Y1907185D01*
X140045D01*
X139095Y1906235D01*
G01X154331Y1928308D02*
X149474D01*
X148450Y1927284D01*
X140144D01*
X139095Y1928333D01*
G01X154331Y1925158D02*
X149500D01*
X148575Y1926083D01*
X140045D01*
X139095Y1925133D01*
G01X344500Y364250D02*
X343100Y362850D01*
Y360800D01*
X340000Y357700D01*
Y288301D01*
X291199Y239500D01*
X191499D01*
X190500Y238501D01*
G01X340500Y364250D02*
X341899Y362851D01*
Y361298D01*
X338799Y358198D01*
Y288799D01*
X290701Y240701D01*
X230461D01*
X229958Y241204D01*
X227894D01*
X227391Y240701D01*
X225327D01*
X224824Y241204D01*
X222760D01*
X222257Y240701D01*
X212257D01*
X211754Y241204D01*
X209690D01*
X209187Y240701D01*
X207123D01*
X206620Y241204D01*
X204556D01*
X204053Y240701D01*
X201989D01*
X201486Y241204D01*
X199422D01*
X198919Y240701D01*
X191500D01*
X190500Y241701D01*
G01X391000Y435750D02*
X392300Y437050D01*
Y439000D01*
X395500Y442200D01*
Y465000D01*
X339261Y521239D01*
X292080D01*
X206761Y606559D01*
X206049D01*
X204590Y608019D01*
Y608730D01*
X203130Y610190D01*
X202419D01*
X200959Y611649D01*
Y612361D01*
X199500Y613820D01*
Y625098D01*
X198997Y625601D01*
Y627665D01*
X199500Y628168D01*
Y630232D01*
X198997Y630735D01*
Y632799D01*
X199500Y633302D01*
Y635366D01*
X198997Y635869D01*
Y637933D01*
X199500Y638436D01*
Y640500D01*
X194988Y645012D01*
X191499D01*
X190500Y644013D01*
G01X395000Y435750D02*
X393501Y437249D01*
Y438502D01*
X396701Y441702D01*
Y465498D01*
X339759Y522440D01*
X292578D01*
X200701Y614318D01*
Y640998D01*
X195486Y646213D01*
X191500D01*
X190500Y647213D01*
G01X391000Y865750D02*
X392299Y867049D01*
Y868799D01*
X395500Y872000D01*
Y895301D01*
X333486Y957315D01*
X260886D01*
X223454Y994747D01*
X222743D01*
X221284Y996206D01*
Y996917D01*
X219824Y998377D01*
X219113D01*
X217653Y999836D01*
Y1000548D01*
X210582Y1007619D01*
X209871D01*
X208411Y1009078D01*
Y1009790D01*
X206952Y1011249D01*
X206241D01*
X204781Y1012709D01*
Y1013420D01*
X203322Y1014879D01*
X202610D01*
X201151Y1016339D01*
Y1017050D01*
X198799Y1019402D01*
Y1046713D01*
X194988Y1050524D01*
X191499D01*
X190500Y1049525D01*
G01X395000Y865750D02*
X393500Y867250D01*
Y868301D01*
X396701Y871502D01*
Y895799D01*
X333984Y958516D01*
X261384D01*
X200000Y1019900D01*
Y1047211D01*
X195486Y1051725D01*
X191500D01*
X190500Y1052725D01*
G01X391000Y1237250D02*
X392299Y1238549D01*
Y1240299D01*
X395500Y1243500D01*
Y1267000D01*
X301000Y1361500D01*
X263400D01*
X240493Y1384408D01*
X239782D01*
X238322Y1385867D01*
Y1386579D01*
X236863Y1388038D01*
X236152D01*
X234692Y1389498D01*
Y1390209D01*
X213490Y1411413D01*
X212779D01*
X211319Y1412872D01*
Y1413583D01*
X209860Y1415043D01*
X209149D01*
X207689Y1416502D01*
Y1417213D01*
X206230Y1418673D01*
X205519D01*
X204059Y1420132D01*
Y1420844D01*
X196568Y1428335D01*
Y1454254D01*
X194786Y1456036D01*
X191499D01*
X190500Y1455037D01*
G01Y1458237D02*
X191500Y1457237D01*
X195284D01*
X197769Y1454752D01*
Y1428833D01*
X205260Y1421342D01*
X263898Y1362701D01*
X301498D01*
X396701Y1267498D01*
Y1243002D01*
X393500Y1239801D01*
Y1238750D01*
X395000Y1237250D01*
G01X355500Y1735750D02*
X356900Y1737150D01*
Y1738900D01*
X360000Y1742000D01*
Y1786500D01*
X284952Y1861548D01*
X243743D01*
X243240Y1861045D01*
X241176D01*
X240673Y1861548D01*
X238609D01*
X238106Y1861045D01*
X236042D01*
X235539Y1861548D01*
X211082D01*
X210579Y1861045D01*
X208515D01*
X208012Y1861548D01*
X205948D01*
X205445Y1861045D01*
X203381D01*
X202878Y1861548D01*
X200814D01*
X200311Y1861045D01*
X198247D01*
X197744Y1861548D01*
X191499D01*
X190500Y1860549D01*
G01X359500Y1735750D02*
X358101Y1737149D01*
Y1738402D01*
X361201Y1741502D01*
Y1786998D01*
X285450Y1862749D01*
X191500D01*
X190500Y1863749D01*
G01X309300Y396550D02*
X307900Y397950D01*
X306500D01*
X305100Y396550D01*
G01X309300D02*
X310750Y398000D01*
X337300D01*
X337800Y397500D01*
G01X309300Y400550D02*
X307901Y399151D01*
X306499D01*
X305100Y400550D01*
G01X309300D02*
X310649Y399201D01*
X337301D01*
X337800Y399700D01*
G01X308600Y826050D02*
X307200Y827450D01*
X305900D01*
X304500Y826050D01*
G01X308600D02*
X309979Y827429D01*
X336321D01*
X336800Y826950D01*
G01X308600Y830050D02*
X307201Y828651D01*
X305899D01*
X304500Y830050D01*
G01X308600D02*
X310020Y828630D01*
X336280D01*
X336800Y829150D01*
G01X309300Y1197500D02*
X307900Y1198900D01*
X306600D01*
X305200Y1197500D01*
G01X309300D02*
X310729Y1198929D01*
X337021D01*
X337500Y1198450D01*
G01X309300Y1201500D02*
X307901Y1200101D01*
X306599D01*
X305200Y1201500D01*
G01X309300D02*
X310670Y1200130D01*
X336980D01*
X337500Y1200650D01*
G01X328600Y1696950D02*
X329079Y1697429D01*
X348954D01*
X349338Y1697045D01*
X352585D01*
G01X310300Y1696000D02*
X311729Y1697429D01*
X328121D01*
X328600Y1696950D01*
G01X295600Y1693400D02*
X294650Y1694350D01*
Y1696550D01*
X295529Y1697429D01*
X304771D01*
X306200Y1696000D01*
G01X310300D02*
X308900Y1697400D01*
X307600D01*
X306200Y1696000D01*
G01X328600Y1699150D02*
X329120Y1698630D01*
X348954D01*
X349339Y1699015D01*
X352585D01*
G01X310300Y1700000D02*
X311670Y1698630D01*
X328080D01*
X328600Y1699150D01*
G01X292400Y1693400D02*
X293449Y1694449D01*
Y1697048D01*
X295031Y1698630D01*
X304830D01*
X306200Y1700000D01*
G01X310300D02*
X308901Y1698601D01*
X307599D01*
X306200Y1700000D01*
G01X337800Y397500D02*
X338300Y398000D01*
X348383D01*
X349338Y397045D01*
X352585D01*
G01X337800Y399700D02*
X338299Y399201D01*
X348881D01*
X349067Y399015D01*
X352585D01*
G01X382795Y382585D02*
Y379338D01*
X382411Y378954D01*
Y377790D01*
X387301Y372900D01*
X391929D01*
X393600Y371229D01*
Y369150D01*
X395000Y367750D01*
G01X391000D02*
X392399Y369149D01*
Y370731D01*
X391431Y371699D01*
X386803D01*
X382900Y375601D01*
X381210Y377292D01*
Y378954D01*
X380825Y379339D01*
Y382585D01*
G01X374920D02*
Y380000D01*
X374536Y379616D01*
Y377964D01*
X378600Y373900D01*
Y369150D01*
X380000Y367750D01*
G01X372955Y382585D02*
Y380000D01*
X373335Y379620D01*
Y377466D01*
X377399Y373402D01*
Y369149D01*
X376000Y367750D01*
G01X365080Y382585D02*
Y379887D01*
X364693Y379500D01*
Y378494D01*
X358100Y371901D01*
Y369150D01*
X359500Y367750D01*
G01X357205Y382585D02*
Y379600D01*
X356801Y379196D01*
Y378002D01*
X349798Y370999D01*
X343999D01*
X343100Y370100D01*
Y369150D01*
X344500Y367750D01*
G01X340500D02*
X340650D01*
X341899Y368999D01*
Y370598D01*
X343501Y372200D01*
X349300D01*
X350759Y373659D01*
Y374371D01*
X352219Y375830D01*
X352930D01*
X355600Y378500D01*
Y379300D01*
X355235Y379665D01*
Y382083D01*
G01X363110Y382585D02*
Y380000D01*
X363492Y379618D01*
Y378992D01*
X356899Y372399D01*
Y369149D01*
X355500Y367750D01*
G01X340500Y432250D02*
X340650D01*
X341899Y431001D01*
Y429101D01*
X344601Y426399D01*
X350401D01*
X351860Y424940D01*
Y424228D01*
X353320Y422769D01*
X354031D01*
X355600Y421200D01*
Y420600D01*
X355235Y420235D01*
Y417917D01*
G01X357205Y417415D02*
Y420095D01*
X356801Y420499D01*
Y421698D01*
X350899Y427600D01*
X345099D01*
X343100Y429599D01*
Y430850D01*
X344500Y432250D01*
G01X363110Y417415D02*
Y420116D01*
X363494Y420500D01*
Y421307D01*
X356899Y427902D01*
Y430851D01*
X355500Y432250D01*
G01X365080Y417415D02*
Y420115D01*
X364695Y420500D01*
Y421805D01*
X358100Y428400D01*
Y430850D01*
X359500Y432250D01*
G01X372955Y417415D02*
Y420500D01*
X373337Y420882D01*
Y424036D01*
X377399Y428098D01*
Y430851D01*
X376000Y432250D01*
G01X374920Y417415D02*
Y420500D01*
X374538Y420882D01*
Y423538D01*
X378600Y427600D01*
Y430850D01*
X380000Y432250D01*
G01X380825Y417415D02*
Y420116D01*
X381209Y420500D01*
Y421408D01*
X386502Y426701D01*
X390201D01*
X392399Y428899D01*
Y430851D01*
X391000Y432250D01*
G01X382795Y417415D02*
Y420000D01*
X382410Y420385D01*
Y420910D01*
X387000Y425500D01*
X390699D01*
X393600Y428401D01*
Y430850D01*
X395000Y432250D01*
G01X388500Y794250D02*
X387100Y792850D01*
Y791099D01*
X391701Y786498D01*
Y677498D01*
X829184Y240015D01*
X829895D01*
X831354Y238556D01*
Y237845D01*
X832814Y236385D01*
X833525D01*
X834985Y234926D01*
Y234214D01*
X842056Y227143D01*
X842767D01*
X844227Y225684D01*
Y224972D01*
X845686Y223513D01*
X846397D01*
X847857Y222054D01*
Y221342D01*
X849316Y219883D01*
X850028D01*
X851487Y218423D01*
Y217712D01*
X861499Y207700D01*
X877553D01*
X878475Y208622D01*
X882677D01*
G01X384500Y794250D02*
X385899Y792851D01*
Y790601D01*
X390500Y786000D01*
Y677000D01*
X861001Y206499D01*
X877447D01*
X878474Y205472D01*
X882677D01*
G01X373500Y794250D02*
X372100Y792850D01*
Y791100D01*
X369000Y788000D01*
Y680900D01*
X840137Y209763D01*
X840848D01*
X842308Y208304D01*
Y207592D01*
X843767Y206133D01*
X844479D01*
X845938Y204673D01*
Y203962D01*
X853009Y196891D01*
X853720D01*
X855180Y195431D01*
Y194720D01*
X856639Y193261D01*
X857351D01*
X858810Y191801D01*
Y191090D01*
X860270Y189630D01*
X860981D01*
X862441Y188171D01*
Y187459D01*
X863900Y186000D01*
X875728D01*
X876231Y186503D01*
X878295D01*
X878798Y186000D01*
X880862D01*
X881365Y186503D01*
X883429D01*
X883932Y186000D01*
X903001D01*
X906867Y189866D01*
Y190578D01*
X908327Y192037D01*
X909038D01*
X916109Y199108D01*
Y199819D01*
X917569Y201279D01*
X918280D01*
X919739Y202738D01*
Y203450D01*
X921199Y204909D01*
X921910D01*
X923370Y206369D01*
Y207080D01*
X924829Y208540D01*
X925541D01*
X927000Y209999D01*
Y221550D01*
X926497Y222053D01*
Y224117D01*
X927000Y224620D01*
Y226684D01*
X926497Y227187D01*
Y229251D01*
X927000Y229754D01*
Y231818D01*
X926497Y232321D01*
Y234385D01*
X927000Y234888D01*
Y236952D01*
X924452Y239500D01*
X919845D01*
X918846Y238501D01*
G01X369500Y794250D02*
X370899Y792851D01*
Y791598D01*
X367799Y788498D01*
Y680402D01*
X863402Y184799D01*
X903499D01*
X928201Y209501D01*
Y237450D01*
X924950Y240701D01*
X919846D01*
X918846Y241701D01*
G01X336800Y826950D02*
X337279Y827429D01*
X348954D01*
X349338Y827045D01*
X352585D01*
G01X336800Y829150D02*
X337320Y828630D01*
X348954D01*
X349339Y829015D01*
X352585D01*
G01X340500Y862250D02*
X340850D01*
X341899Y861201D01*
Y859101D01*
X343400Y857600D01*
X349301D01*
X350760Y856141D01*
Y855429D01*
X352220Y853970D01*
X352931D01*
X355499Y851402D01*
Y850600D01*
X355235Y850336D01*
Y847917D01*
G01X357205Y847415D02*
Y850195D01*
X356700Y850700D01*
Y851900D01*
X349799Y858801D01*
X343898D01*
X343100Y859599D01*
Y860850D01*
X344500Y862250D01*
G01X363110Y847415D02*
Y850000D01*
X363494Y850384D01*
Y851006D01*
X360799Y853700D01*
X356899Y857601D01*
Y860851D01*
X355500Y862250D01*
G01X365080Y847415D02*
Y850115D01*
X364695Y850500D01*
Y851504D01*
X358100Y858099D01*
Y860850D01*
X359500Y862250D01*
G01X402250Y824000D02*
X400750Y822500D01*
X398199D01*
X394036Y826663D01*
X390382D01*
X390000Y827045D01*
X387415D01*
G01X402250Y820000D02*
X400951Y821299D01*
X397701D01*
X393538Y825462D01*
X390382D01*
X390000Y825080D01*
X387415D01*
G01Y819175D02*
X390000D01*
X390384Y818791D01*
X391408D01*
X398000Y812199D01*
Y808500D01*
X398899Y807601D01*
X400851D01*
X402250Y809000D01*
G01X387415Y817205D02*
X390000D01*
X390385Y817590D01*
X390910D01*
X396799Y811701D01*
Y808002D01*
X398401Y806400D01*
X400850D01*
X402250Y805000D01*
G01X382795Y812585D02*
Y810000D01*
X382530Y809735D01*
Y805470D01*
X387100Y800900D01*
Y799150D01*
X388500Y797750D01*
G01X380825Y812585D02*
Y810000D01*
X381329Y809496D01*
Y804972D01*
X385899Y800402D01*
Y799149D01*
X384500Y797750D01*
G01X374920Y812585D02*
Y809884D01*
X374536Y809500D01*
Y806536D01*
X372100Y804100D01*
Y799150D01*
X373500Y797750D01*
G01X372955Y812585D02*
Y809880D01*
X373335Y809500D01*
Y807034D01*
X370899Y804598D01*
Y799149D01*
X369500Y797750D01*
G01X372955Y847415D02*
Y850118D01*
X373337Y850500D01*
Y853036D01*
X377399Y857098D01*
Y860851D01*
X376000Y862250D01*
G01X374920Y847415D02*
Y850000D01*
X374538Y850382D01*
Y852538D01*
X378600Y856600D01*
Y860850D01*
X380000Y862250D01*
G01X380825Y847415D02*
Y850116D01*
X381209Y850500D01*
Y851408D01*
X386502Y856701D01*
X390201D01*
X392399Y858899D01*
Y860851D01*
X391000Y862250D01*
G01X382795Y847415D02*
Y850000D01*
X382410Y850385D01*
Y850910D01*
X387000Y855500D01*
X390699D01*
X393600Y858401D01*
Y860850D01*
X395000Y862250D01*
G01Y1165750D02*
X393600Y1164350D01*
Y1162599D01*
X398201Y1157998D01*
Y1112299D01*
X491829Y1018671D01*
X840259D01*
X840762Y1019174D01*
X842826D01*
X843329Y1018671D01*
X845393D01*
X845896Y1019174D01*
X847960D01*
X848463Y1018671D01*
X858463D01*
X858966Y1019174D01*
X861030D01*
X861533Y1018671D01*
X863597D01*
X864100Y1019174D01*
X866164D01*
X866667Y1018671D01*
X868731D01*
X869234Y1019174D01*
X871298D01*
X871801Y1018671D01*
X877500D01*
X878475Y1019646D01*
X882677D01*
G01X391000Y1165750D02*
X392399Y1164351D01*
Y1162101D01*
X397000Y1157500D01*
Y1111801D01*
X491331Y1017470D01*
X877500D01*
X878474Y1016496D01*
X882677D01*
G01X380000Y1165750D02*
X378600Y1164350D01*
Y1162600D01*
X375500Y1159500D01*
Y1117200D01*
X489899Y1002801D01*
X812909D01*
X813412Y1003304D01*
X815476D01*
X815979Y1002801D01*
X818043D01*
X818546Y1003304D01*
X820610D01*
X821113Y1002801D01*
X823177D01*
X823680Y1003304D01*
X825744D01*
X826247Y1002801D01*
X834593D01*
X835096Y1003304D01*
X837160D01*
X837663Y1002801D01*
X839727D01*
X840230Y1003304D01*
X842294D01*
X842797Y1002801D01*
X852797D01*
X853300Y1003304D01*
X855364D01*
X855867Y1002801D01*
X857931D01*
X858434Y1003304D01*
X860498D01*
X861001Y1002801D01*
X863065D01*
X863568Y1003304D01*
X865632D01*
X866135Y1002801D01*
X868199D01*
X874000Y997000D01*
X904101D01*
X909768Y1002667D01*
Y1003378D01*
X911227Y1004838D01*
X911939D01*
X913398Y1006297D01*
Y1007008D01*
X914858Y1008468D01*
X915569D01*
X917028Y1009927D01*
Y1010639D01*
X918488Y1012098D01*
X919199D01*
X926799Y1019698D01*
Y1027432D01*
X926296Y1027935D01*
Y1029999D01*
X926799Y1030502D01*
Y1032566D01*
X926296Y1033069D01*
Y1035133D01*
X926799Y1035636D01*
Y1037700D01*
X926296Y1038203D01*
Y1040267D01*
X926799Y1040770D01*
Y1048177D01*
X924452Y1050524D01*
X919845D01*
X918846Y1049525D01*
G01X376000Y1165750D02*
X377399Y1164351D01*
Y1163098D01*
X374299Y1159998D01*
Y1116702D01*
X489401Y1001600D01*
X867701D01*
X873502Y995799D01*
X904599D01*
X928000Y1019200D01*
Y1048675D01*
X924950Y1051725D01*
X919846D01*
X918846Y1052725D01*
G01X337500Y1198450D02*
X337979Y1198929D01*
X348954D01*
X349338Y1198545D01*
X352585D01*
G01X337500Y1200650D02*
X338020Y1200130D01*
X348954D01*
X349339Y1200515D01*
X352585D01*
G01X387415Y1206420D02*
X390664D01*
X391046Y1206038D01*
X393538D01*
X397600Y1210100D01*
X400850D01*
X402250Y1211500D01*
G01X387415Y1204455D02*
X390664D01*
X391046Y1204837D01*
X392536D01*
X392539Y1204834D01*
X393534D01*
X393537Y1204837D01*
X394036D01*
X398098Y1208899D01*
X400851D01*
X402250Y1207500D01*
G01X382795Y1184085D02*
Y1180839D01*
X382410Y1180454D01*
Y1179590D01*
X386300Y1175700D01*
X391429D01*
X393600Y1173529D01*
Y1170650D01*
X395000Y1169250D01*
G01X380825Y1184085D02*
Y1180838D01*
X381209Y1180454D01*
Y1179092D01*
X385802Y1174499D01*
X390931D01*
X392399Y1173031D01*
Y1170649D01*
X391000Y1169250D01*
G01X380000D02*
X378600Y1170650D01*
Y1175599D01*
X374538Y1179661D01*
Y1180454D01*
X374920Y1180836D01*
Y1184085D01*
G01X372955D02*
Y1180836D01*
X373337Y1180454D01*
Y1179163D01*
X377399Y1175101D01*
Y1170649D01*
X376000Y1169250D01*
G01X402250Y1226500D02*
X400850Y1225100D01*
X397971D01*
X396000Y1223129D01*
Y1218401D01*
X391510Y1213911D01*
X391046D01*
X390662Y1214295D01*
X387415D01*
G01X402250Y1222500D02*
X400851Y1223899D01*
X398469D01*
X397201Y1222631D01*
Y1217903D01*
X392008Y1212710D01*
X391046D01*
X390661Y1212325D01*
X387415D01*
G01X340500Y1233750D02*
X341150D01*
X341899Y1233001D01*
Y1230402D01*
X343502Y1228799D01*
X348208D01*
X351507Y1225496D01*
Y1224784D01*
X352965Y1223324D01*
X353676Y1223323D01*
X355235Y1221763D01*
Y1219417D01*
G01X357205Y1218915D02*
Y1221491D01*
X348706Y1230000D01*
X344000D01*
X343100Y1230900D01*
Y1232350D01*
X344500Y1233750D01*
G01X363110Y1218915D02*
Y1222161D01*
X363495Y1222546D01*
Y1223506D01*
X362601Y1224400D01*
X361701D01*
X356899Y1229202D01*
Y1232351D01*
X355500Y1233750D01*
G01X365080Y1218915D02*
Y1222162D01*
X364696Y1222546D01*
Y1224004D01*
X363099Y1225601D01*
X362199D01*
X358100Y1229700D01*
Y1232350D01*
X359500Y1233750D01*
G01X376000D02*
X377399Y1232351D01*
Y1228598D01*
X373337Y1224536D01*
Y1222546D01*
X372955Y1222164D01*
Y1218915D01*
G01X380000Y1233750D02*
X378600Y1232350D01*
Y1228100D01*
X374538Y1224038D01*
Y1222546D01*
X374920Y1222164D01*
Y1218915D01*
G01X380825D02*
Y1222162D01*
X381209Y1222546D01*
Y1224317D01*
X385093Y1228201D01*
X390201D01*
X392399Y1230399D01*
Y1232351D01*
X391000Y1233750D01*
G01X395000D02*
X393600Y1232350D01*
Y1229901D01*
X390699Y1227000D01*
X385591D01*
X382410Y1223819D01*
Y1222546D01*
X382795Y1222161D01*
Y1218915D01*
G01X387415Y1712795D02*
X390662D01*
X391046Y1712411D01*
X391734D01*
X396000Y1716677D01*
Y1721629D01*
X397971Y1723600D01*
X400850D01*
X402250Y1725000D01*
G01X387415Y1710825D02*
X390661D01*
X391046Y1711210D01*
X392232D01*
X397201Y1716179D01*
Y1721131D01*
X398469Y1722399D01*
X400851D01*
X402250Y1721000D01*
G01X387415Y1704920D02*
X390500D01*
X390884Y1704536D01*
X393036D01*
X397100Y1708600D01*
X400850D01*
X402250Y1710000D01*
G01X387415Y1702955D02*
X390500D01*
X390880Y1703335D01*
X393534D01*
X397598Y1707399D01*
X400851D01*
X402250Y1706000D01*
G01X365080Y1682585D02*
Y1680000D01*
X364693Y1679613D01*
Y1676693D01*
X358100Y1670100D01*
Y1669150D01*
X359500Y1667750D01*
G01X363110Y1682585D02*
Y1680000D01*
X363492Y1679618D01*
Y1677191D01*
X356899Y1670598D01*
Y1669149D01*
X355500Y1667750D01*
G01X344500D02*
X343100Y1669150D01*
Y1670100D01*
X344500Y1671500D01*
X349729D01*
X357205Y1678976D01*
Y1682585D01*
G01X340500Y1667750D02*
X341250D01*
X341899Y1668399D01*
Y1670598D01*
X344002Y1672701D01*
X349231D01*
X350690Y1674160D01*
Y1674872D01*
X352150Y1676331D01*
X352861D01*
X355235Y1678705D01*
Y1682083D01*
G01Y1717917D02*
Y1720846D01*
X353701Y1722380D01*
X349120D01*
X345630Y1725870D01*
X344919D01*
X343459Y1727329D01*
Y1728041D01*
X342000Y1729500D01*
Y1731300D01*
X341050Y1732250D01*
X340500D01*
G01X344500D02*
X343201Y1730951D01*
Y1729998D01*
X349618Y1723581D01*
X354199D01*
X357205Y1720575D01*
Y1717415D01*
G01X363110D02*
Y1720000D01*
X363494Y1720384D01*
Y1721006D01*
X359499Y1724999D01*
X358374Y1726124D01*
X356899Y1727601D01*
Y1730851D01*
X355500Y1732250D01*
G01X365080Y1717415D02*
Y1720115D01*
X364695Y1720500D01*
Y1721504D01*
X360349Y1725849D01*
X358100Y1728099D01*
Y1730850D01*
X359500Y1732250D01*
G01X405750Y820000D02*
X407149Y821399D01*
X409399D01*
X414000Y826000D01*
X444500D01*
X453500Y817000D01*
Y649694D01*
X491236Y611958D01*
X877000D01*
X877974Y610984D01*
X882677D01*
G01X405750Y809000D02*
X407350Y807400D01*
X409400D01*
X412300Y804500D01*
X430699D01*
X437201Y797998D01*
Y642942D01*
X489143Y591000D01*
X877918D01*
X878421Y591503D01*
X880485D01*
X880988Y591000D01*
X883052D01*
X883555Y591503D01*
X885619D01*
X886122Y591000D01*
X893520D01*
X894645Y592125D01*
X901625D01*
X906666Y597166D01*
Y597878D01*
X908126Y599337D01*
X908837D01*
X915908Y606408D01*
Y607119D01*
X917368Y608579D01*
X918079D01*
X919538Y610038D01*
Y610750D01*
X920998Y612209D01*
X921709D01*
X923169Y613669D01*
Y614380D01*
X924628Y615840D01*
X925340D01*
X926799Y617299D01*
Y625999D01*
X926296Y626502D01*
Y628566D01*
X926799Y629069D01*
Y631133D01*
X926296Y631636D01*
Y633700D01*
X926799Y634203D01*
Y636267D01*
X926296Y636770D01*
Y638834D01*
X926799Y639337D01*
Y642665D01*
X924452Y645012D01*
X919845D01*
X918846Y644013D01*
G01X405750Y805000D02*
X406949Y806199D01*
X408902D01*
X411802Y803299D01*
X430201D01*
X436000Y797500D01*
Y642444D01*
X488645Y589799D01*
X894018D01*
X895143Y590924D01*
X902123D01*
X928000Y616801D01*
Y643163D01*
X924950Y646213D01*
X919846D01*
X918846Y647213D01*
G01X405750Y824000D02*
X407150Y822600D01*
X408901D01*
X413502Y827201D01*
X444998D01*
X454701Y817498D01*
Y650192D01*
X491734Y613159D01*
X877159D01*
X878134Y614134D01*
X882677D01*
G01X918846Y1455037D02*
X919845Y1456036D01*
X924452D01*
X926799Y1453689D01*
Y1425998D01*
X903301Y1402500D01*
X879880D01*
X879377Y1403003D01*
X877313D01*
X876810Y1402500D01*
X874746D01*
X874243Y1403003D01*
X872179D01*
X871676Y1402500D01*
X869612D01*
X869109Y1403003D01*
X867045D01*
X866542Y1402500D01*
X856542D01*
X856039Y1403003D01*
X853975D01*
X853472Y1402500D01*
X851408D01*
X850905Y1403003D01*
X848841D01*
X848338Y1402500D01*
X836410D01*
X835907Y1403003D01*
X833843D01*
X833340Y1402500D01*
X831276D01*
X830773Y1403003D01*
X828709D01*
X828206Y1402500D01*
X826142D01*
X825639Y1403003D01*
X823575D01*
X823072Y1402500D01*
X813072D01*
X812569Y1403003D01*
X810505D01*
X810002Y1402500D01*
X807938D01*
X807435Y1403003D01*
X805371D01*
X804868Y1402500D01*
X704500D01*
X508201Y1206201D01*
X413099D01*
X409100Y1210200D01*
X407050D01*
X405750Y1211500D01*
G01X918846Y1458237D02*
X919846Y1457237D01*
X924950D01*
X928000Y1454187D01*
Y1425500D01*
X903799Y1401299D01*
X704998D01*
X508699Y1205000D01*
X412601D01*
X408602Y1208999D01*
X407249D01*
X405750Y1207500D01*
G01X882677Y1425158D02*
X878475D01*
X877500Y1424183D01*
X701484D01*
X507002Y1229701D01*
X413502D01*
X408902Y1225101D01*
X407149D01*
X405750Y1226500D01*
G01X882677Y1422008D02*
X878500D01*
X877526Y1422982D01*
X701982D01*
X507500Y1228500D01*
X414000D01*
X409400Y1223900D01*
X407150D01*
X405750Y1222500D01*
G01X882677Y1827520D02*
X878083D01*
X877109Y1828494D01*
X872494D01*
X865000Y1821000D01*
Y1799801D01*
X840699Y1775500D01*
X753199D01*
X704699Y1727000D01*
X414000D01*
X409399Y1722399D01*
X407149D01*
X405750Y1721000D01*
G01Y1710000D02*
X407350Y1708400D01*
X409500D01*
X412400Y1705500D01*
X445134D01*
X451115Y1711481D01*
X705481D01*
X747109Y1753109D01*
Y1753820D01*
X748569Y1755280D01*
X749280D01*
X750739Y1756739D01*
Y1757451D01*
X752199Y1758910D01*
X752910D01*
X754370Y1760370D01*
Y1761081D01*
X755829Y1762541D01*
X756541D01*
X758000Y1764000D01*
X847500D01*
X891228Y1807728D01*
X908029D01*
X915908Y1815607D01*
Y1816318D01*
X917368Y1817778D01*
X918079D01*
X919538Y1819237D01*
Y1819949D01*
X920998Y1821408D01*
X921709D01*
X923169Y1822868D01*
Y1823579D01*
X924628Y1825039D01*
X925340D01*
X926799Y1826498D01*
Y1843799D01*
X926296Y1844302D01*
Y1846366D01*
X926799Y1846869D01*
Y1848933D01*
X926296Y1849436D01*
Y1851500D01*
X926799Y1852003D01*
Y1854067D01*
X926296Y1854570D01*
Y1856634D01*
X926799Y1857137D01*
Y1859201D01*
X924452Y1861548D01*
X919845D01*
X918846Y1860549D01*
G01X405750Y1706000D02*
X406949Y1707199D01*
X409002D01*
X411902Y1704299D01*
X445632D01*
X451613Y1710280D01*
X705979D01*
X758498Y1762799D01*
X847998D01*
X891726Y1806527D01*
X908527D01*
X928000Y1826000D01*
Y1859699D01*
X924950Y1862749D01*
X919846D01*
X918846Y1863749D01*
G01X882677Y1830670D02*
X878084D01*
X877109Y1829695D01*
X871996D01*
X863799Y1821498D01*
Y1800299D01*
X840201Y1776701D01*
X752701D01*
X704201Y1728201D01*
X413502D01*
X408901Y1723600D01*
X407150D01*
X405750Y1725000D01*
G01X908346Y235394D02*
X907346Y236394D01*
Y239000D01*
X905746Y240600D01*
X900619D01*
X899526Y241693D01*
X895236D01*
G01X905146Y235394D02*
X906145Y236393D01*
Y238502D01*
X905248Y239399D01*
X900356D01*
X899500Y238543D01*
X895236D01*
G01X882677Y224370D02*
X877974D01*
X877000Y225344D01*
X874540D01*
X872941Y223745D01*
G01X882677Y227519D02*
X878019D01*
X877045Y226545D01*
X874541D01*
X872941Y228145D01*
G01X882677Y214921D02*
X877975D01*
X877000Y215896D01*
X868441D01*
X867441Y214896D01*
G01X882677Y218071D02*
X877974D01*
X877000Y217097D01*
X868440D01*
X867441Y218096D01*
G01X882677Y265315D02*
X878474D01*
X877500Y266289D01*
X868440D01*
X867441Y265290D01*
G01X882677Y274763D02*
X879000D01*
X878025Y275738D01*
X874541D01*
X872941Y274138D01*
G01X882677Y277913D02*
X878500D01*
X877526Y276939D01*
X874540D01*
X872941Y278538D01*
G01X882677Y293661D02*
X878500D01*
X877525Y294636D01*
X874541D01*
X872941Y293036D01*
G01X882677Y296811D02*
X878474D01*
X877500Y295837D01*
X874540D01*
X872941Y297436D01*
G01X882677Y312559D02*
X878500D01*
X877526Y313533D01*
X874540D01*
X872941Y311934D01*
G01X882677Y315708D02*
X878474D01*
X877500Y314734D01*
X874541D01*
X872941Y316334D01*
G01X882677Y268464D02*
X878500D01*
X877526Y267490D01*
X868441D01*
X867441Y268490D01*
G01X882677Y284212D02*
X878475D01*
X877500Y285187D01*
X868441D01*
X867441Y284187D01*
G01X882677Y287362D02*
X878474D01*
X877500Y286388D01*
X868440D01*
X867441Y287387D01*
G01X882677Y303110D02*
X878500D01*
X877525Y304085D01*
X868441D01*
X867441Y303085D01*
G01X882677Y306260D02*
X878474D01*
X877500Y305286D01*
X868440D01*
X867441Y306285D01*
G01X882677Y629882D02*
X878474D01*
X877500Y630856D01*
X874540D01*
X872941Y629257D01*
G01X882677Y620433D02*
X878500D01*
X877525Y621408D01*
X868441D01*
X867441Y620408D01*
G01X882677Y623583D02*
X878474D01*
X877500Y622609D01*
X868440D01*
X867441Y623608D01*
G01X895236Y647205D02*
X899526D01*
X900500Y646231D01*
X905627D01*
X907346Y644512D01*
Y641906D01*
X908346Y640906D01*
G01X895236Y644055D02*
X899500D01*
X900475Y645030D01*
X905129D01*
X906145Y644014D01*
Y641905D01*
X905146Y640906D01*
G01X882677Y633031D02*
X878474D01*
X877500Y632057D01*
X874541D01*
X872941Y633657D01*
G01X882677Y680275D02*
X878475D01*
X877500Y681250D01*
X874541D01*
X872941Y679650D01*
G01X882677Y683425D02*
X878500D01*
X877526Y682451D01*
X874540D01*
X872941Y684050D01*
G01X882677Y699173D02*
X878500D01*
X877525Y700148D01*
X874541D01*
X872941Y698548D01*
G01X882677Y702323D02*
X878500D01*
X877526Y701349D01*
X874540D01*
X872941Y702948D01*
G01X882677Y670827D02*
X878474D01*
X877500Y671801D01*
X868440D01*
X867441Y670802D01*
G01X882677Y673976D02*
X878500D01*
X877526Y673002D01*
X868441D01*
X867441Y674002D01*
G01X882677Y689724D02*
X878500D01*
X877525Y690699D01*
X868441D01*
X867441Y689699D01*
G01X882677Y692874D02*
X878500D01*
X877526Y691900D01*
X868440D01*
X867441Y692899D01*
G01X882677Y718071D02*
X878500D01*
X877526Y719045D01*
X874540D01*
X872941Y717446D01*
G01X882677Y721220D02*
X878474D01*
X877500Y720246D01*
X874541D01*
X872941Y721846D01*
G01X882677Y708622D02*
X878500D01*
X877525Y709597D01*
X868441D01*
X867441Y708597D01*
G01X882677Y711772D02*
X878500D01*
X877526Y710798D01*
X868440D01*
X867441Y711797D01*
G01X908346Y1046418D02*
X907346Y1047418D01*
Y1050024D01*
X905770Y1051600D01*
X900643D01*
X899526Y1052717D01*
X895236D01*
G01X905146Y1046418D02*
X906145Y1047417D01*
Y1049526D01*
X905272Y1050399D01*
X900332D01*
X899500Y1049567D01*
X895236D01*
G01X882677Y1035394D02*
X878474D01*
X877500Y1036368D01*
X874540D01*
X872941Y1034769D01*
G01X882677Y1038543D02*
X878474D01*
X877500Y1037569D01*
X874541D01*
X872941Y1039169D01*
G01X882677Y1025945D02*
X878475D01*
X877500Y1026920D01*
X868441D01*
X867441Y1025920D01*
G01X882677Y1029095D02*
X878474D01*
X877500Y1028121D01*
X868440D01*
X867441Y1029120D01*
G01X882677Y1085787D02*
X878500D01*
X877525Y1086762D01*
X874541D01*
X872941Y1085162D01*
G01X882677Y1088937D02*
X878500D01*
X877526Y1087963D01*
X874540D01*
X872941Y1089562D01*
G01X882677Y1104685D02*
X878500D01*
X877525Y1105660D01*
X874541D01*
X872941Y1104060D01*
G01X882677Y1107835D02*
X878474D01*
X877500Y1106861D01*
X874540D01*
X872941Y1108460D01*
G01X882677Y1123583D02*
X878500D01*
X877526Y1124557D01*
X874540D01*
X872941Y1122958D01*
G01X882677Y1126732D02*
X878474D01*
X877500Y1125758D01*
X874541D01*
X872941Y1127358D01*
G01X882677Y1076339D02*
X878474D01*
X877500Y1077313D01*
X868440D01*
X867441Y1076314D01*
G01X882677Y1079488D02*
X878500D01*
X877526Y1078514D01*
X868441D01*
X867441Y1079514D01*
G01X882677Y1095236D02*
X878500D01*
X877525Y1096211D01*
X868441D01*
X867441Y1095211D01*
G01X882677Y1098386D02*
X878474D01*
X877500Y1097412D01*
X868440D01*
X867441Y1098411D01*
G01X882677Y1114134D02*
X878500D01*
X877525Y1115109D01*
X868441D01*
X867441Y1114109D01*
G01X882677Y1117284D02*
X878474D01*
X877500Y1116310D01*
X868440D01*
X867441Y1117309D01*
G01X908346Y1451930D02*
X907346Y1452930D01*
Y1455536D01*
X905582Y1457300D01*
X900455D01*
X899526Y1458229D01*
X895236D01*
G01X905146Y1451930D02*
X906145Y1452929D01*
Y1455038D01*
X905084Y1456099D01*
X900520D01*
X899500Y1455079D01*
X895236D01*
G01X882677Y1440906D02*
X878500D01*
X877526Y1441880D01*
X874540D01*
X872941Y1440281D01*
G01X882677Y1444055D02*
X878474D01*
X877500Y1443081D01*
X874541D01*
X872941Y1444681D01*
G01X882677Y1491299D02*
X878500D01*
X877525Y1492274D01*
X874541D01*
X872941Y1490674D01*
G01X882677Y1494449D02*
X878500D01*
X877526Y1493475D01*
X874540D01*
X872941Y1495074D01*
G01X882677Y1431457D02*
X878475D01*
X877500Y1432432D01*
X868441D01*
X867441Y1431432D01*
G01X882677Y1434607D02*
X878474D01*
X877500Y1433633D01*
X868440D01*
X867441Y1434632D01*
G01X882677Y1481851D02*
X878474D01*
X877500Y1482825D01*
X868440D01*
X867441Y1481826D01*
G01X882677Y1485000D02*
X878474D01*
X877500Y1484026D01*
X868441D01*
X867441Y1485026D01*
G01X882677Y1500748D02*
X878500D01*
X877525Y1501723D01*
X868441D01*
X867441Y1500723D01*
G01X882677Y1510197D02*
X878500D01*
X877525Y1511172D01*
X874541D01*
X872941Y1509572D01*
G01X882677Y1513347D02*
X878500D01*
X877526Y1512373D01*
X874540D01*
X872941Y1513972D01*
G01X882677Y1529095D02*
X878500D01*
X877526Y1530069D01*
X874540D01*
X872941Y1528470D01*
G01X882677Y1532244D02*
X878474D01*
X877500Y1531270D01*
X874541D01*
X872941Y1532870D01*
G01X882677Y1503898D02*
X878474D01*
X877500Y1502924D01*
X868440D01*
X867441Y1503923D01*
G01X882677Y1519646D02*
X878500D01*
X877525Y1520621D01*
X868441D01*
X867441Y1519621D01*
G01X882677Y1522796D02*
X878474D01*
X877500Y1521822D01*
X868440D01*
X867441Y1522821D01*
G01X895236Y1863741D02*
X899526D01*
X900500Y1862767D01*
X905627D01*
X907346Y1861048D01*
Y1858442D01*
X908346Y1857442D01*
G01X895236Y1860591D02*
X899500D01*
X900475Y1861566D01*
X905129D01*
X906145Y1860550D01*
Y1858441D01*
X905146Y1857442D01*
G01X882677Y1846418D02*
X878474D01*
X877500Y1847392D01*
X874540D01*
X872941Y1845793D01*
G01X882677Y1849567D02*
X878567D01*
X877593Y1848593D01*
X874541D01*
X872941Y1850193D01*
G01X882677Y1836969D02*
X878475D01*
X877500Y1837944D01*
X868441D01*
X867441Y1836944D01*
G01X882677Y1840119D02*
X878474D01*
X877500Y1839145D01*
X868440D01*
X867441Y1840144D01*
G01X882677Y1896811D02*
X878500D01*
X877525Y1897786D01*
X874541D01*
X872941Y1896186D01*
G01X882677Y1899961D02*
X878500D01*
X877526Y1898987D01*
X874540D01*
X872941Y1900586D01*
G01X882677Y1915709D02*
X878291D01*
X877316Y1916684D01*
X874541D01*
X872941Y1915084D01*
G01X882677Y1918859D02*
X878159D01*
X877185Y1917885D01*
X874470D01*
X872941Y1919414D01*
Y1919484D01*
G01X882677Y1934607D02*
X878500D01*
X877526Y1935581D01*
X874540D01*
X872941Y1933982D01*
G01X882677Y1937756D02*
X878500D01*
X877526Y1936782D01*
X874541D01*
X872941Y1938382D01*
G01X882677Y1887363D02*
X878500D01*
X877526Y1888337D01*
X868440D01*
X867441Y1887338D01*
G01X882677Y1890512D02*
X878474D01*
X877500Y1889538D01*
X868441D01*
X867441Y1890538D01*
G01X882677Y1906260D02*
X878475D01*
X877500Y1907235D01*
X868441D01*
X867441Y1906235D01*
G01X882677Y1909410D02*
X878500D01*
X877526Y1908436D01*
X868440D01*
X867441Y1909435D01*
G01X882677Y1925158D02*
X878500D01*
X877525Y1926133D01*
X868441D01*
X867441Y1925133D01*
G01X882677Y1928308D02*
X878500D01*
X877526Y1927334D01*
X868440D01*
X867441Y1928333D01*
G54D10*
G01X328250Y408500D02*
X331300D01*
G01X328250Y838500D02*
X331300D01*
G01X328250Y1210000D02*
X331300D01*
G01X331500Y1708500D02*
X328250D01*
G01X352585Y404920D02*
X350080D01*
X346000Y409000D01*
X331800D01*
X331300Y408500D01*
G01X352585Y834920D02*
X350080D01*
X346000Y839000D01*
X331800D01*
X331300Y838500D01*
G01X352585Y1206420D02*
X350080D01*
X346000Y1210500D01*
X331800D01*
X331300Y1210000D01*
G01X352585Y1704920D02*
X350080D01*
X346000Y1709000D01*
X332000D01*
X331500Y1708500D01*
G01X898089Y1745256D02*
X826756D01*
X822500Y1741000D01*
Y1730250D01*
G01X820000Y1723500D02*
X822500Y1726000D01*
G01D02*
Y1729750D01*
G01X916500Y1722400D02*
X906900D01*
X899606Y1715106D01*
Y1712953D01*
G01X896500Y1685000D02*
Y1681000D01*
G01X919500Y1695000D02*
Y1686500D01*
X917000Y1684000D01*
X911800D01*
G01D02*
X909750D01*
X906000Y1687750D01*
G01X894484Y1716056D02*
Y1722200D01*
G01X846557Y1720000D02*
X853500D01*
X855000Y1718500D01*
Y1702500D01*
G01X899556Y1710984D02*
X901484D01*
X903500Y1713000D01*
Y1715500D01*
X907000Y1719000D01*
X909700D01*
G01D02*
X914750D01*
G01X868443Y1720000D02*
X861500D01*
X859500Y1718000D01*
Y1702750D01*
G01X887444Y1709016D02*
X879716D01*
G01D02*
X877000Y1706300D01*
Y1701000D01*
G01X911750Y1695000D02*
Y1691000D01*
G01Y1699000D02*
Y1695000D01*
G01Y1703000D02*
Y1699000D01*
G01Y1703000D02*
X906400D01*
X906000Y1703400D01*
G01D02*
X902353Y1707047D01*
X899606D01*
G01X859500Y1699250D02*
Y1696000D01*
G01D02*
X855500D01*
X855000Y1696500D01*
G01X904276Y1696100D02*
X906000Y1694376D01*
Y1691250D01*
G01X904276Y1696100D02*
X902126Y1698250D01*
X899950D01*
X896453Y1701747D01*
Y1703894D01*
G01X921900Y1722400D02*
Y1730600D01*
X915500Y1737000D01*
X897500D01*
X894500Y1734000D01*
Y1730800D01*
G01X890500Y1730750D02*
X894450D01*
X894500Y1730800D01*
G01X925500Y1695000D02*
X927500Y1697000D01*
Y1729728D01*
X911972Y1745256D01*
X898089D01*
G01X890500Y1727250D02*
X894450D01*
X894500Y1727200D01*
G01X898500Y1727250D02*
X894550D01*
X894500Y1727200D01*
G01X894484Y1722200D02*
Y1724984D01*
X894500Y1725000D01*
Y1727200D01*
G01X902500Y1730750D02*
Y1734000D01*
G01X915250Y1703000D02*
X919000D01*
X925000Y1709000D01*
Y1719300D01*
X921900Y1722400D01*
G01X918250Y1719000D02*
Y1719750D01*
X916500Y1721500D01*
Y1722400D01*
G01X915250Y1695000D02*
Y1699000D01*
G01X919500Y1695000D02*
X915250D01*
G01Y1691000D02*
Y1687500D01*
G01X916500Y1722400D02*
X921900D01*
X-63741Y15000D03*
X-42339Y1008909D03*
X-63741Y1977126D03*
X33465Y281496D03*
X11811Y571426D03*
Y949378D03*
Y1067489D03*
Y1484811D03*
Y1445441D03*
Y1862763D03*
X21654Y1922835D03*
X25499Y1950499D03*
X82087Y28858D03*
Y178464D03*
Y434370D03*
Y583976D03*
Y839882D03*
Y989488D03*
Y1245394D03*
Y1395000D03*
Y1650906D03*
Y1800512D03*
X133858Y17717D03*
X162008Y191614D03*
Y341220D03*
Y597126D03*
Y746732D03*
Y1002638D03*
Y1152244D03*
Y1408150D03*
Y1557756D03*
Y1813662D03*
Y1963268D03*
X275591Y279528D03*
Y685030D03*
Y1088573D03*
Y1903534D03*
X890354Y191614D03*
Y341220D03*
Y597126D03*
Y746732D03*
Y1002638D03*
Y1152244D03*
Y1408150D03*
Y1557756D03*
Y1813662D03*
Y1963268D03*
X1010999Y43999D03*
X998031Y163376D03*
Y686998D03*
Y1082667D03*
X1023228Y1416024D03*
Y1694212D03*
X998031Y1903534D03*
X1010499Y1950499D03*
X1101142Y15000D03*
Y1977126D03*
G54D20*
X30200Y1491900D03*
X26600D03*
X32850Y1514000D03*
X36350D03*
X82000Y247288D03*
X98400Y439200D03*
X82000Y652800D03*
X98400Y844700D03*
X83248Y1056436D03*
X98400Y1250200D03*
X82748Y1461948D03*
X98900Y1656100D03*
X54872Y1678348D03*
X58372D03*
X115700Y43600D03*
X144400Y434400D03*
Y839900D03*
X144700Y1245400D03*
X145900Y1650900D03*
X193000Y60300D03*
X194606Y1772990D03*
X395600Y401700D03*
X393500Y383800D03*
X341000Y406300D03*
X344500D03*
X368500Y432800D03*
X372000D03*
X341000Y836300D03*
X344500D03*
X393500Y833300D03*
X368500Y861800D03*
X372000D03*
X393500Y1181300D03*
X341000Y1207800D03*
X344500D03*
X395600Y1202300D03*
X368500Y1233300D03*
X372000D03*
X395700Y1700800D03*
X341000Y1706300D03*
X344500D03*
X369000Y1731300D03*
X372500D03*
X417500Y812800D03*
Y820800D03*
Y1215300D03*
Y1223300D03*
Y1713800D03*
Y1721800D03*
G54D11*
G01X40500Y1608500D02*
X41100Y1609100D01*
Y1615150D01*
G01X44020Y1952520D02*
X48043Y1948497D01*
Y1898957D01*
X56000Y1891000D01*
G01X105808Y114518D02*
X116958Y103368D01*
X184461D01*
G01X159500Y181000D02*
X127700D01*
X100400Y208300D01*
G01X108000Y522500D02*
X152000Y478500D01*
X170500D01*
G01X102500Y619000D02*
X127000Y594500D01*
X146500D01*
X159600Y581400D01*
G01X190330Y913530D02*
X190300Y913500D01*
X159831D01*
X143331Y930000D01*
X105994D01*
G01X100800Y1011600D02*
X128654Y983746D01*
X149982D01*
X154236Y988000D01*
X162200D01*
G01X128250Y1506500D02*
Y1523750D01*
X121260Y1530740D01*
X116910D01*
X112025Y1535625D01*
G01X112388Y1884007D02*
Y1931432D01*
X113370Y1932414D01*
G01X112388Y1884007D02*
X112366Y1883985D01*
G01X56000Y1891000D02*
X100647D01*
X107640Y1884007D01*
X112388D01*
G01X159500Y181000D02*
X146000Y167500D01*
X137800D01*
G01X173800Y379800D02*
X221800D01*
X225600Y376000D01*
X248547D01*
X257547Y385000D01*
X293000D01*
G01X157200Y412000D02*
X290500D01*
X294500Y408000D01*
G01X159600Y581400D02*
X127150D01*
X124150Y578400D01*
G01X156800Y816000D02*
X161500D01*
X182500Y837000D01*
X292000D01*
G01X214500Y1459000D02*
Y1578800D01*
X170550Y1622750D01*
X159450D01*
G01X220500Y67500D02*
Y44600D01*
X208150Y32250D01*
G01X214700Y784200D02*
X247300D01*
X293500Y738000D01*
G01X303200Y422600D02*
X307600D01*
G01X307900Y853100D02*
X303500D01*
G01X307200Y1224000D02*
X302500D01*
G01X307700Y1722100D02*
X301800D01*
G01X388000Y1736300D02*
X383000D01*
G01X388000Y1728700D02*
X383000D01*
G01X857735Y553465D02*
X852900Y548630D01*
Y540900D01*
X847500Y535500D01*
X663000D01*
G01X809000Y777000D02*
X803000Y783000D01*
Y799500D01*
X775900Y826600D01*
X662000D01*
G01X857623Y958977D02*
Y945923D01*
X848700Y937000D01*
X665000D01*
G01X866985Y1053500D02*
X660000D01*
G01X812250Y1180250D02*
X805750D01*
X802500Y1183500D01*
X662000D01*
G01X657000Y1331500D02*
X843105D01*
X854900Y1343295D01*
Y1361700D01*
X857688Y1364488D01*
G01X867359Y1459000D02*
X662000D01*
G01X764739Y1953007D02*
Y1936039D01*
X761800Y1933100D01*
X728700D01*
G01X867900Y648000D02*
X782500D01*
G01X809000Y1723500D02*
Y1739500D01*
X826000Y1756500D01*
X848250D01*
X857687Y1765937D01*
G01X866289Y1864000D02*
X844000D01*
X819000Y1839000D01*
X-49168Y52138D03*
X26000Y1965500D03*
X329500Y363500D03*
X327500Y1662000D03*
X404000Y432000D03*
X340500Y793500D03*
X405000Y862500D03*
X343000Y1166000D03*
X399500Y1734000D03*
X413500Y1247500D03*
X1009500Y27500D03*
X1010500Y1966000D03*
X1085741Y22661D03*
Y1967598D03*
G54D21*
X33000Y1778850D03*
Y1775350D03*
X80187Y1854268D03*
X180800Y553500D03*
X128300Y1502000D03*
X360800Y120500D03*
Y117000D03*
X367300Y76500D03*
X390800Y447500D03*
X355300D03*
X382800D03*
X347300D03*
X390800Y877500D03*
X355300D03*
X382800D03*
X347300D03*
X390800Y1249000D03*
X355300D03*
X382800D03*
X347300D03*
X355300Y1747500D03*
X347300D03*
X834800Y203000D03*
Y1817000D03*
X889300Y1698000D03*
X915300Y1691000D03*
Y1699000D03*
G54D30*
X36775Y1970275D03*
X88875Y377775D03*
Y783275D03*
X66895Y1012436D03*
X88875Y1188775D03*
X67540Y1417910D03*
X96200Y1497000D03*
Y1492000D03*
X87800Y1840600D03*
X97800Y1839900D03*
X87800Y1836300D03*
X88300Y1867400D03*
X148100Y426600D03*
X119200Y454500D03*
Y449500D03*
X170700Y556330D03*
X170695Y560416D03*
X148100Y832100D03*
X119200Y860000D03*
Y855000D03*
X169617Y960000D03*
X168230Y979729D03*
X148400Y1237600D03*
X119200Y1265500D03*
Y1260500D03*
X154659Y1352302D03*
Y1347802D03*
X112500Y1543700D03*
X149600Y1643100D03*
X119200Y1671000D03*
Y1666000D03*
X122400Y1943900D03*
X196700Y52500D03*
X193700Y135000D03*
X203700Y569000D03*
X194854Y1346488D03*
X328200Y408500D03*
Y404400D03*
Y421000D03*
Y417000D03*
Y425000D03*
X329200Y609000D03*
Y597000D03*
X280200Y573000D03*
Y565000D03*
Y585000D03*
Y577000D03*
Y597000D03*
Y589000D03*
X329200D03*
X328200Y838500D03*
Y847000D03*
Y834400D03*
Y851000D03*
Y855000D03*
Y1210000D03*
Y1205800D03*
Y1222500D03*
Y1218500D03*
Y1226500D03*
X280200Y1419500D03*
Y1411500D03*
Y1423500D03*
Y1403500D03*
Y1431500D03*
X328200Y1721000D03*
Y1708500D03*
Y1717000D03*
Y1704300D03*
X272200Y1722000D03*
X328200Y1725000D03*
X367200Y58000D03*
X334200Y377000D03*
X338200Y389000D03*
X334200Y381000D03*
Y385000D03*
X390700Y459000D03*
X355200D03*
X382700D03*
X347200D03*
X334200Y807000D03*
X338200Y819000D03*
X334200Y815000D03*
Y811000D03*
X390700Y889000D03*
X355200D03*
X382700D03*
X347200D03*
X338200Y1190500D03*
X334200Y1178500D03*
Y1182500D03*
Y1186500D03*
X390700Y1260500D03*
X355200D03*
X382700D03*
X347200D03*
X334200Y1677000D03*
X338200Y1691000D03*
X334200Y1681000D03*
Y1685000D03*
X355200Y1759000D03*
X347200D03*
X405700Y820000D03*
Y805000D03*
Y824000D03*
Y809000D03*
Y1207500D03*
Y1211500D03*
Y1222500D03*
Y1226500D03*
Y1721000D03*
Y1706000D03*
Y1710000D03*
Y1725000D03*
X763614Y1968282D03*
X802700Y193000D03*
Y198000D03*
X815375Y377775D03*
Y783275D03*
Y1188775D03*
Y1594275D03*
X802700Y1812000D03*
Y1807000D03*
X889700Y157000D03*
Y161000D03*
X898675Y154724D03*
X890516Y168354D03*
X865200Y553465D03*
X887950Y556715D03*
Y560715D03*
X896941Y560408D03*
X865200Y958977D03*
X887950Y962227D03*
Y966227D03*
X897174Y965913D03*
X865200Y1364488D03*
X887388Y1365200D03*
Y1369700D03*
X896785Y1371351D03*
X887950Y1773250D03*
X865200Y1770000D03*
X887950Y1777250D03*
X897100Y1776900D03*
X851300Y1945200D03*
X923200Y129953D03*
Y535465D03*
Y940977D03*
Y1346488D03*
X954700Y1668500D03*
Y1663500D03*
X919200Y1715000D03*
X923200Y1752000D03*
G54D12*
G01X-106883Y-224955D02*
Y-304955D01*
G01Y-260455D02*
X1019417D01*
G01X-106883Y-304955D02*
X1019417D01*
G01X-110883Y-208955D02*
G02I-12000J0D01*
G01X-116033D02*
G02I-6850J0D01*
G01X-122883Y-224955D02*
Y-192955D01*
G01X-106883Y-208955D02*
X-138883D01*
G01X-106883Y-224955D02*
X1019417D01*
G01X8858Y607646D02*
X15020D01*
X16500Y606166D01*
G01X8858Y610796D02*
X15130D01*
X16500Y612166D01*
G01X8858Y620245D02*
X15020D01*
X16500Y618765D01*
G01X8858Y623394D02*
X15129D01*
X16500Y624765D01*
G01X8858Y598197D02*
X16500D01*
G01X8858Y632843D02*
X15020D01*
X16500Y631363D01*
G01X8858Y635993D02*
X15130D01*
X16500Y637363D01*
G01X8858Y670638D02*
X15020D01*
X16500Y669158D01*
G01X8858Y673788D02*
X15130D01*
X16500Y675158D01*
G01X8858Y683237D02*
X15020D01*
X16500Y681757D01*
G01X8858Y686386D02*
X15129D01*
X16500Y687757D01*
G01X8858Y695835D02*
X15020D01*
X16500Y694355D01*
G01X8858Y698985D02*
X15130D01*
X16500Y700355D01*
G01Y644530D02*
X15589Y645441D01*
X8858D01*
G01X16500Y662226D02*
X15463Y661189D01*
X8858D01*
G01Y708433D02*
X15020D01*
X16500Y706953D01*
G01X8858Y711583D02*
X15130D01*
X16500Y712953D01*
G01X8858Y721032D02*
X15020D01*
X16500Y719552D01*
G01X8858Y724182D02*
X15130D01*
X16500Y725552D01*
G01X8858Y768276D02*
X15130D01*
X16500Y769646D01*
G01X8858Y765126D02*
X15020D01*
X16500Y763646D01*
G01X8858Y755678D02*
X15130D01*
X16500Y757048D01*
G01X8858Y733630D02*
X15370D01*
X16500Y732500D01*
G01X8858Y777725D02*
X16500D01*
G01X8858Y850166D02*
X15020D01*
X16500Y848686D01*
G01X8858Y840717D02*
X15130D01*
X16500Y842087D01*
G01X8858Y837567D02*
X15020D01*
X16500Y836087D01*
G01X8858Y828119D02*
X15130D01*
X16500Y829489D01*
G01X8858Y824969D02*
X15020D01*
X16500Y823489D01*
G01X8858Y815520D02*
X15129D01*
X16500Y816891D01*
G01X8858Y812371D02*
X15020D01*
X16500Y810891D01*
G01X8858Y802922D02*
X15130D01*
X16500Y804292D01*
G01X8858Y799772D02*
X15020D01*
X16500Y798292D01*
G01X8858Y790323D02*
X15129D01*
X16500Y791694D01*
G01X8858Y903709D02*
X15130D01*
X16500Y905079D01*
G01X8858Y900559D02*
X15020D01*
X16500Y899079D01*
G01X8858Y891111D02*
X14889D01*
X16500Y889500D01*
G01X8858Y887961D02*
X14961D01*
X16500Y889500D01*
G01X8858Y878512D02*
X15129D01*
X16500Y879883D01*
G01X8858Y875363D02*
X15020D01*
X16500Y873883D01*
G01X8858Y865914D02*
X15130D01*
X16500Y867284D01*
G01X8858Y862764D02*
X15020D01*
X16500Y861284D01*
G01X8858Y853315D02*
X15129D01*
X16500Y854686D01*
G01X8858Y913158D02*
X15020D01*
X16500Y911678D01*
G01X8858Y1116308D02*
X15020D01*
X16500Y1114828D01*
G01X8858Y1132056D02*
X15056D01*
X16500Y1133500D01*
G01X8858Y1141504D02*
X15020D01*
X16500Y1140024D01*
G01X8858Y1094260D02*
X16500D01*
G01X8858Y1106859D02*
X15130D01*
X16500Y1108229D01*
G01X8858Y1103709D02*
X15020D01*
X16500Y1102229D01*
G01X31707Y1081291D02*
Y1086000D01*
G01X8858Y1144654D02*
X15130D01*
X16500Y1146024D01*
G01X8858Y1154103D02*
X15020D01*
X16500Y1152623D01*
G01X8858Y1157252D02*
X15129D01*
X16500Y1158623D01*
G01X8858Y1166701D02*
X15020D01*
X16500Y1165221D01*
G01X8858Y1169851D02*
X15130D01*
X16500Y1171221D01*
G01X8858Y1179300D02*
X15020D01*
X16500Y1177820D01*
G01X8858Y1182449D02*
X15129D01*
X16500Y1183820D01*
G01X8858Y1191898D02*
X15020D01*
X16500Y1190418D01*
G01X8858Y1195048D02*
X15130D01*
X16500Y1196418D01*
G01X8858Y1204496D02*
X15020D01*
X16500Y1203016D01*
G01X8858Y1207646D02*
X15130D01*
X16500Y1209016D01*
G01X8858Y1217095D02*
X15020D01*
X16500Y1215615D01*
G01X8858Y1220245D02*
X15130D01*
X16500Y1221615D01*
G01X8858Y1251741D02*
X15130D01*
X16500Y1253111D01*
G01X8858Y1261189D02*
X15020D01*
X16500Y1259709D01*
G01X8858Y1264339D02*
X15130D01*
X16500Y1265709D01*
G01X8858Y1273788D02*
X15020D01*
X16500Y1272308D01*
G01X8858Y1276937D02*
X15129D01*
X16500Y1278308D01*
G01X8858Y1286386D02*
X15020D01*
X16500Y1284906D01*
G01X8858Y1229693D02*
X15307D01*
X16500Y1228500D01*
G01X8858Y1289536D02*
X15130D01*
X16500Y1290906D01*
G01X8858Y1298985D02*
X15020D01*
X16500Y1297505D01*
G01X8858Y1311583D02*
X16417D01*
G01X8858Y1321032D02*
X15020D01*
X16500Y1319552D01*
G01X8858Y1324182D02*
X15130D01*
X16500Y1325552D01*
G01X8858Y1333630D02*
X15020D01*
X16500Y1332150D01*
G01X8858Y1336780D02*
X15130D01*
X16500Y1338150D01*
G01X8858Y1346229D02*
X15020D01*
X16500Y1344749D01*
G01X8858Y1349378D02*
X15129D01*
X16500Y1350749D01*
G01X8858Y1358827D02*
X15020D01*
X16500Y1357347D01*
G01X8858Y1361977D02*
X15130D01*
X16500Y1363347D01*
G01X8858Y1371426D02*
X15020D01*
X16500Y1369946D01*
G01X8858Y1374575D02*
X15129D01*
X16500Y1375946D01*
G01X8858Y1384024D02*
X15020D01*
X16500Y1382544D01*
G01X8858Y1387174D02*
X15130D01*
X16500Y1388544D01*
G01X8858Y1396622D02*
X15020D01*
X16500Y1395142D01*
G01X8858Y1399772D02*
X15130D01*
X16500Y1401142D01*
G01X8858Y1409221D02*
X15020D01*
X16500Y1407741D01*
G01X8858Y1555677D02*
X14823D01*
X16500Y1554000D01*
G01X8858Y1543078D02*
X14922D01*
X16500Y1541500D01*
G01X8858Y1530480D02*
X15020D01*
X16500Y1529000D01*
G01X8858Y1521031D02*
X16500D01*
G01X8858Y1568275D02*
X14725D01*
X16500Y1566500D01*
G01X8858Y1558826D02*
X14826D01*
X16500Y1560500D01*
G01X8858Y1546228D02*
X14728D01*
X16500Y1548000D01*
G01X8858Y1533630D02*
X15130D01*
X16500Y1535000D01*
G01Y1512500D02*
X15582Y1511582D01*
X8858D01*
G01Y1628118D02*
X14882D01*
X16500Y1626500D01*
G01X8858Y1615519D02*
X14981D01*
X16500Y1614000D01*
G01X8858Y1590322D02*
X14678D01*
X16500Y1588500D01*
G01X8858Y1631267D02*
X14767D01*
X16500Y1633000D01*
G01X8858Y1618669D02*
X15169D01*
X16500Y1620000D01*
G01X8858Y1593472D02*
X14972D01*
X16500Y1595000D01*
G01X8858Y1580874D02*
X14874D01*
X16500Y1582500D01*
G01X8858Y1606070D02*
X15070D01*
X16500Y1607500D01*
G01X8858Y1602921D02*
X15079D01*
X16500Y1601500D01*
G01Y1639845D02*
X15629Y1640716D01*
X8858D01*
G01Y1678511D02*
X14989D01*
X16500Y1677000D01*
G01X8858Y1691110D02*
X14890D01*
X16500Y1689500D01*
G01X8858Y1694259D02*
X14759D01*
X16500Y1696000D01*
G01X8858Y1703708D02*
X15292D01*
X16500Y1702500D01*
G01Y1717462D02*
X15345Y1716307D01*
X8858D01*
G01X16500Y1683170D02*
X14991Y1681661D01*
X8858D01*
G01X16500Y1669933D02*
X15630Y1669063D01*
X8858D01*
G01Y1791897D02*
X15103D01*
X16500Y1790500D01*
G01X8858Y1782448D02*
X14948D01*
X16500Y1784000D01*
G01X8858Y1773000D02*
X15000D01*
X16500Y1774500D01*
G01X8858Y1763551D02*
X15051D01*
X16500Y1765000D01*
G01X8858Y1750952D02*
X14548D01*
X16500Y1749000D01*
G01X8858Y1738354D02*
X14646D01*
X16500Y1736500D01*
G01X8858Y1725756D02*
X14744D01*
X16500Y1724000D01*
G01Y1756052D02*
X14550Y1754102D01*
X8858D01*
G01X16500Y1743356D02*
X14648Y1741504D01*
X8858D01*
G01X16500Y1730658D02*
X14747Y1728905D01*
X8858D01*
G01X37300Y1960550D02*
Y1959240D01*
X44020Y1952520D01*
G01X78839Y51161D02*
X72214D01*
X64560Y43507D01*
Y12941D01*
X67201Y10300D01*
X85300D01*
X89136Y14136D01*
X98037D01*
G01X105400Y23850D02*
Y18336D01*
X101200Y14136D01*
X98037D01*
G01X89764Y114212D02*
X96000D01*
G01X89764Y107913D02*
X96000D01*
G01X89764Y98464D02*
X96000D01*
G01X89764Y79567D02*
X96000D01*
G01X89764Y70118D02*
X96000D01*
G01X78839Y91161D02*
X72500D01*
G01X78839Y86161D02*
X72500D01*
G01X71000Y58000D02*
X72839Y56161D01*
X78839D01*
G01X89764Y89015D02*
X96000D01*
G01X89764Y60669D02*
X95801D01*
X96000Y60868D01*
G01X89764Y51220D02*
X95020D01*
X96100Y52300D01*
G01X100000Y119000D02*
X96000D01*
G01X78839Y166161D02*
X72500D01*
G01X89764Y158307D02*
X96000D01*
G01X78839Y151161D02*
X72500D01*
G01X89764Y148858D02*
X96000D01*
G01X89764Y139409D02*
X96000D01*
G01X89764Y123661D02*
X96000D01*
G01X78839Y136161D02*
X72500D01*
G01X100000Y125000D02*
X104000D01*
G01X89764Y133110D02*
X95110D01*
X96000Y134000D01*
G01X77205Y125236D02*
X71000D01*
G01X82000Y247238D02*
X85250D01*
G01X96250Y201000D02*
X99300D01*
G01X59859Y208421D02*
X63179D01*
X63903Y209145D01*
G01X60306Y212338D02*
X59859Y211891D01*
Y208421D01*
G01X83589Y230965D02*
X80872D01*
X80153Y230246D01*
G01X82000Y243738D02*
Y239715D01*
G01X86500Y243000D02*
X85762Y243738D01*
X82000D01*
G01Y239715D02*
X85427D01*
G01X91825Y362750D02*
X94663D01*
X95849Y361564D01*
G01X100250Y370025D02*
Y369450D01*
X97400Y366600D01*
G01D02*
X97150D01*
X94500Y369250D01*
G01X97425Y401025D02*
X92325D01*
G01X92700Y358400D02*
X89900D01*
X87700Y360600D01*
Y366950D01*
X90000Y369250D01*
G01X110600Y396300D02*
X115100D01*
X116375Y397575D01*
Y401225D01*
G01X110600Y396300D02*
X107500D01*
X105025Y398775D01*
Y401025D01*
G01X65300Y396800D02*
X65800D01*
X67550Y398550D01*
Y407200D01*
G01X65300Y396800D02*
X63100D01*
X60200Y399700D01*
Y445423D01*
X71450Y456673D01*
X78839D01*
G01X89764Y475630D02*
X96000D01*
G01X89764Y466181D02*
X96000D01*
G01X78839Y461673D02*
X72827D01*
X71000Y463500D01*
G01X89764Y456732D02*
X96000D01*
G01X78839Y556673D02*
X72500D01*
G01X78839Y541673D02*
X72500D01*
G01X89764Y544921D02*
X96000D01*
G01X89764Y529173D02*
X96000D01*
G01X89764Y519724D02*
X96000D01*
G01X89764Y513425D02*
X96000D01*
G01X89764Y503976D02*
X96000D01*
G01X89764Y494527D02*
X96000D01*
G01X89764Y485079D02*
X96000D01*
G01X78839Y496673D02*
X72500D01*
G01X78839Y491673D02*
X72500D01*
G01X100000Y531000D02*
X104000D01*
G01X89764Y538622D02*
X95122D01*
X96000Y539500D01*
G01X89764Y554370D02*
X95999D01*
X96000Y554369D01*
G01X100000Y525000D02*
X105500D01*
X108000Y522500D01*
G01X96000Y524000D02*
X97000Y525000D01*
X100000D01*
G01X77205Y530748D02*
X71000D01*
G01X78839Y571673D02*
X72500D01*
G01X89764Y563819D02*
X96000D01*
G01X92500Y603250D02*
X89400D01*
G01X63623Y611120D02*
Y608937D01*
X62426Y607740D01*
G01X82000Y652750D02*
X85250D01*
G01X67414Y631712D02*
X76400D01*
X80153Y635465D01*
Y635758D01*
G01X83589Y636477D02*
X80872D01*
X80153Y635758D01*
G01X82000Y645227D02*
Y649250D01*
G01D02*
X85750D01*
X86500Y648500D01*
G01X85223Y645227D02*
X82000D01*
G01X91825Y768250D02*
X87075D01*
G01X100250Y775525D02*
Y775350D01*
X97000Y772100D01*
G01D02*
X94500Y774600D01*
Y774750D01*
G01X90000D02*
X86900D01*
G01X97600Y805700D02*
X92700D01*
G01X111200Y802054D02*
X115300D01*
X116750Y803504D01*
Y807100D01*
G01X105200Y805700D02*
Y804154D01*
X107300Y802054D01*
X111200D01*
G01X70150Y803150D02*
X67850D01*
X61200Y809800D01*
Y851935D01*
X71450Y862185D01*
X78839D01*
G01X70150Y813200D02*
Y803150D01*
G01X89764Y918937D02*
X96000D01*
G01X89764Y909488D02*
X96000D01*
G01X89764Y900039D02*
X96000D01*
G01X89764Y890591D02*
X96000D01*
G01X89764Y881142D02*
X96000D01*
G01X89764Y862244D02*
X96000D01*
G01X78839Y902185D02*
X72500D01*
G01X78839Y897185D02*
X72500D01*
G01X78839Y867185D02*
X72815D01*
X71000Y869000D01*
G01X89764Y871693D02*
X95999D01*
X96000Y871692D01*
G01X78839Y977185D02*
X72500D01*
G01X89764Y969331D02*
X96000D01*
G01X78839Y962185D02*
X72500D01*
G01X89764Y959882D02*
X96000D01*
G01X78839Y947185D02*
X72500D01*
G01X89764Y950433D02*
X96000D01*
G01X89764Y934685D02*
X96000D01*
G01X89764Y925236D02*
X96000D01*
G01X100000Y936000D02*
X104000D01*
G01X89764Y944134D02*
X95134D01*
X96000Y945000D01*
G01X105994Y930000D02*
X100000D01*
G01X77205Y936260D02*
X71000D01*
G01X100000Y930000D02*
X96000D01*
G01X103200Y1042500D02*
X101750Y1041050D01*
Y1038863D01*
G01X83248Y1056386D02*
Y1059636D01*
G01X93000Y1008750D02*
Y1005700D01*
G01X84000Y1042750D02*
X81689Y1040439D01*
Y1039600D01*
G01X77750Y1052886D02*
Y1056750D01*
G01X83248Y1052886D02*
X77750D01*
G01X86498D02*
X83248D01*
G01X64040Y1020235D02*
Y1016657D01*
X64037Y1016654D01*
G01D02*
X64040Y1016651D01*
Y1013031D01*
X63445Y1012436D01*
G01X96100Y1176700D02*
X100250Y1180850D01*
Y1181025D01*
G01X94500Y1180250D02*
Y1178300D01*
X96100Y1176700D01*
G01X87900Y1173300D02*
X88750Y1174150D01*
X91825D01*
G01X97500Y1211800D02*
X91900D01*
G01X90000Y1180250D02*
Y1178800D01*
X88500Y1177300D01*
G01X111000Y1207800D02*
X115000D01*
X116750Y1209550D01*
Y1212600D01*
G01X111000Y1207800D02*
X107700D01*
X105100Y1210400D01*
Y1211800D01*
G01X68150Y1218700D02*
Y1208200D01*
G01D02*
X65300D01*
X63759Y1209741D01*
Y1260006D01*
X71450Y1267697D01*
X78839D01*
G01X89764Y1277205D02*
X96000D01*
G01X89764Y1267756D02*
X96000D01*
G01X78839Y1272697D02*
X72803D01*
X71000Y1274500D01*
G01X78839Y1352697D02*
X72500D01*
G01X89764Y1355945D02*
X96000D01*
G01X89764Y1340197D02*
X96000D01*
G01X89764Y1330748D02*
X96000D01*
G01X89764Y1324449D02*
X96000D01*
G01X89764Y1315000D02*
X96000D01*
G01X89764Y1305551D02*
X96000D01*
G01X89764Y1296103D02*
X96000D01*
G01X89764Y1286654D02*
X96000D01*
G01X78839Y1307697D02*
X72500D01*
G01X78839Y1302697D02*
X72500D01*
G01X100000Y1341000D02*
X104000D01*
G01X89764Y1349646D02*
X95146D01*
X96000Y1350500D01*
G01X77205Y1341772D02*
X71000D01*
G01X100000Y1335000D02*
X96000D01*
G01X89764Y1374843D02*
X96000D01*
G01X70838Y1384165D02*
X72306Y1382697D01*
X78839D01*
G01Y1367697D02*
X74349D01*
X72285Y1365633D01*
G01X89764Y1365394D02*
X95999D01*
X96000Y1365393D01*
G01X96250Y1417500D02*
Y1414400D01*
G01X63797Y1425738D02*
Y1423435D01*
X62962Y1422600D01*
G01X64090Y1417910D02*
X62715Y1419285D01*
Y1422353D01*
X62962Y1422600D01*
G01X82748Y1461898D02*
Y1465560D01*
G01X83589Y1447500D02*
X80872D01*
X80153Y1446781D01*
G01X85998Y1458398D02*
X82748D01*
G01X110000Y1470000D02*
Y1473250D01*
G01X82748Y1458398D02*
Y1455148D01*
G01X76750Y1458600D02*
Y1462762D01*
G01X83875Y1580125D02*
X88076Y1575924D01*
G01X91125Y1570250D02*
Y1565900D01*
G01X88076Y1575924D02*
X89648Y1577496D01*
Y1580877D01*
X89625Y1580900D01*
G01X109050Y1548200D02*
X105700D01*
G01X79375Y1580125D02*
Y1571210D01*
X80465Y1570120D01*
G01X112025Y1535625D02*
X109050Y1538600D01*
Y1540600D01*
G01Y1543700D02*
Y1540600D01*
G01X109125Y1580900D02*
X113841D01*
G01X93100Y1619700D02*
X94400D01*
X97400Y1616700D01*
G01X111000Y1613200D02*
X115500D01*
X116750Y1614450D01*
Y1618100D01*
G01X111000Y1613200D02*
X108500D01*
X105000Y1616700D01*
G01X66450Y1624000D02*
Y1615050D01*
X64700Y1613300D01*
X63200D01*
G01D02*
X61600D01*
X59708Y1615192D01*
Y1668433D01*
X64484Y1673209D01*
X78839D01*
G01X89764Y1701615D02*
X96000D01*
G01X89764Y1711063D02*
X96000D01*
G01X89764Y1673268D02*
X96000D01*
G01X89764Y1692166D02*
X96000D01*
G01X78839Y1678209D02*
X72791D01*
X71000Y1680000D01*
G01X78839Y1713209D02*
X72500D01*
G01X78839Y1708209D02*
X72500D01*
G01X89764Y1720512D02*
X96000D01*
G01X89764Y1682717D02*
X95999D01*
X96000Y1682716D01*
G01X89764Y1729961D02*
X96000D01*
G01X89764Y1736260D02*
X96000D01*
G01X89764Y1755158D02*
X96000D01*
G01X89764Y1761457D02*
X96000D01*
G01X89764Y1770906D02*
X96000D01*
G01X78839Y1758209D02*
X72500D01*
G01X78839Y1773209D02*
X72500D01*
G01X78839Y1788209D02*
X72500D01*
G01X89764Y1780355D02*
X96000D01*
G01X100000Y1755500D02*
Y1759000D01*
G01X89764Y1745709D02*
X95400D01*
X96000Y1745109D01*
G01X77205Y1747284D02*
X71000D01*
G01X100000Y1749500D02*
X102300D01*
X104000Y1747800D01*
G01X76975Y1859650D02*
Y1864000D01*
G01Y1859650D02*
Y1856924D01*
X76637Y1856586D01*
Y1854268D01*
G01X97250Y1821500D02*
X99600D01*
X100300Y1820800D01*
G01X71725Y1823331D02*
X72105D01*
X77159Y1818277D01*
G01X80137Y1854268D02*
Y1853507D01*
X77100Y1850470D01*
Y1849650D01*
G01X94350Y1839900D02*
X93136Y1838686D01*
Y1837382D01*
X91036Y1835282D01*
G01X97237Y1825915D02*
X100287D01*
G01X97250Y1830000D02*
X100300D01*
G01X77100Y1849650D02*
X79850D01*
X80600Y1848900D01*
G01X84350Y1836300D02*
X74530D01*
X73560Y1837270D01*
G01D02*
Y1839746D01*
X72123Y1841183D01*
G01X52000Y1884250D02*
Y1887500D01*
G01X113370Y1932414D02*
Y1938320D01*
X118950Y1943900D01*
G01X56000Y1891000D02*
Y1884250D01*
G01X66950Y1961325D02*
X71666D01*
G01X61625Y1954250D02*
X56875D01*
G01X41800Y1960550D02*
Y1959350D01*
X43935Y1957215D01*
G01X47850Y1961425D02*
Y1958950D01*
X46115Y1957215D01*
X43935D01*
G01X61050Y1961800D02*
X57800D01*
G01X125200Y1972400D02*
Y1975200D01*
X123000Y1977400D01*
X90500D01*
X87200Y1974100D01*
Y1968000D01*
G01X74450Y1965200D02*
X79400D01*
X80600Y1964000D01*
G01X87200Y1960400D02*
X84200D01*
X80600Y1964000D01*
G01X174750Y31475D02*
X170034D01*
G01X116600Y46800D02*
X115700Y45900D01*
Y43550D01*
G01X167250Y27600D02*
Y36250D01*
X165700Y37800D01*
G01D02*
X161600D01*
X160400Y36600D01*
G01X121600Y51350D02*
Y54700D01*
G01X125700Y54400D02*
Y51350D01*
G01X147125Y156250D02*
Y160500D01*
G01X179147Y137913D02*
X175894D01*
G01X150557Y139750D02*
Y142854D01*
G01X170402Y147703D02*
X167298D01*
G01X170402D02*
X172404D01*
X175894Y144213D01*
Y141413D01*
G01X137800Y167500D02*
X136125Y165825D01*
Y162475D01*
G01X195750Y167000D02*
Y169921D01*
X194552Y171119D01*
X185194D01*
X182886Y168811D01*
X171106D01*
G01X163994Y151286D02*
Y149477D01*
X165768Y147703D01*
X167298D01*
G01X165256Y203917D02*
X171595D01*
G01X154331Y211771D02*
X148095D01*
G01X165256Y218917D02*
X171595D01*
G01X154331Y221220D02*
X148095D01*
G01X165256Y233917D02*
X171595D01*
G01X154331Y230669D02*
X148095D01*
G01X154331Y236968D02*
X148095D01*
G01X154331Y246417D02*
X148095D01*
G01X154331Y255866D02*
X148095D01*
G01X154331Y262165D02*
X148095D01*
G01X144000Y247500D02*
X140000D01*
G01X166890Y244842D02*
X173095D01*
G01X144000Y241500D02*
X148000D01*
G01X154331Y271614D02*
X148095D01*
G01X154331Y281063D02*
X148095D01*
G01X154331Y290511D02*
X148095D01*
G01X154331Y299960D02*
X148095D01*
G01X154331Y309409D02*
X148095D01*
G01X154331Y318858D02*
X148095D01*
G01X165256Y278917D02*
X171595D01*
G01X165256Y283917D02*
X171595D01*
G01X165256Y313917D02*
X171583D01*
X173000Y312500D01*
G01X126445Y335067D02*
Y338300D01*
G01X114295Y335067D02*
Y338300D01*
G01X186400Y368300D02*
Y325405D01*
X179912Y318917D01*
X165256D01*
G01X123875Y405100D02*
X119159D01*
G01X119750Y370025D02*
X124466D01*
G01X145900Y408500D02*
X143375Y405975D01*
Y405100D01*
G01X149125Y405875D02*
X146500Y408500D01*
X145900D01*
G01X146600Y375300D02*
X151300D01*
G01X153625Y405875D02*
Y408425D01*
X157200Y412000D01*
G01X133100Y379700D02*
X137179D01*
X139000Y377879D01*
Y375300D01*
G01X127250Y373900D02*
Y377800D01*
X129150Y379700D01*
X133100D01*
G01X186400Y368300D02*
X178850D01*
G01X148700Y413400D02*
X149350Y412750D01*
X152175D01*
X152275Y412850D01*
G01X120800Y441050D02*
Y438000D01*
G01X125300Y441050D02*
Y438000D01*
G01X177250Y553500D02*
X174000D01*
G01X154500Y541250D02*
X157750D01*
G01X180750Y553500D02*
X184500D01*
G01X155250Y569500D02*
X158500D01*
G01X165256Y609429D02*
X171595D01*
G01X154331Y617283D02*
X148095D01*
G01X165256Y624429D02*
X171595D01*
G01X154331Y626732D02*
X148095D01*
G01X136125Y563750D02*
X132350D01*
G01X124150Y578400D02*
X122025Y576275D01*
Y573125D01*
G01X151750Y569500D02*
Y570250D01*
X155500Y574000D01*
G01D02*
X158760D01*
X160975Y571785D01*
X162144D01*
G01D02*
Y565017D01*
X166745Y560416D01*
X167245D01*
G01X165256Y639429D02*
X171895D01*
G01X154331Y636181D02*
X148095D01*
G01X154331Y642480D02*
X148095D01*
G01X154331Y651929D02*
X148095D01*
G01X154331Y661378D02*
X148095D01*
G01X154331Y667677D02*
X148095D01*
G01X154331Y677126D02*
X148095D01*
G01X154331Y686575D02*
X148095D01*
G01X154331Y696023D02*
X148095D01*
G01X165256Y684429D02*
X171595D01*
G01X165256Y689429D02*
X171595D01*
G01X144000Y654000D02*
X140000D01*
G01X144000Y648000D02*
X148000D01*
G01X166890Y650354D02*
X173095D01*
G01X119750Y775525D02*
X124966D01*
G01X154331Y705472D02*
X148095D01*
G01X154331Y714921D02*
X148095D01*
G01X154331Y724370D02*
X148095D01*
G01X165256Y719429D02*
X171571D01*
X173000Y718000D01*
G01X122445Y740667D02*
Y743800D01*
G01X117945Y740667D02*
Y743800D01*
G01X187800Y775400D02*
Y731454D01*
X180775Y724429D01*
X165256D01*
G01X179050Y775400D02*
X187800D01*
G01X124250Y810975D02*
X119534D01*
G01X122251Y845496D02*
Y842400D01*
G01X152275Y818350D02*
X148950D01*
X148600Y818700D01*
G01X147100Y814200D02*
X146975D01*
X143750Y810975D01*
G01X147100Y814200D02*
X149500Y811800D01*
Y811750D01*
G01X146700Y780600D02*
X151800D01*
G01X126800Y845550D02*
Y842500D01*
G01X156800Y816000D02*
X154000Y813200D01*
Y811750D01*
G01X132900Y783900D02*
X135800D01*
X139100Y780600D01*
G01X132900Y783900D02*
X128673D01*
X127250Y782477D01*
Y779400D01*
G01X182000Y952750D02*
Y949000D01*
G01X178000Y956250D02*
Y960000D01*
G01X182000Y956250D02*
X178000D01*
G01X161095Y980622D02*
X160496Y980023D01*
Y976999D01*
G01X161095Y980622D02*
X163887D01*
X164780Y979729D01*
G01X165256Y1014941D02*
X171595D01*
G01X154331Y1022795D02*
X148095D01*
G01X165256Y1029941D02*
X171595D01*
G01X154331Y1032244D02*
X148095D01*
G01X165256Y1044941D02*
X171595D01*
G01X154331Y1041693D02*
X148095D01*
G01X154331Y1047992D02*
X148095D01*
G01X154331Y1057441D02*
X148095D01*
G01X144000Y1059500D02*
X140000D01*
G01X166890Y1055866D02*
X173095D01*
G01X144000Y1053500D02*
X148000D01*
G01X154331Y1066890D02*
X148095D01*
G01X154331Y1073189D02*
X148095D01*
G01X154331Y1082638D02*
X148095D01*
G01X154331Y1092087D02*
X148095D01*
G01X154331Y1101535D02*
X148095D01*
G01X154331Y1110984D02*
X148095D01*
G01X154331Y1120433D02*
X148095D01*
G01X154331Y1129882D02*
X148095D01*
G01X165256Y1089941D02*
X171595D01*
G01X165256Y1094941D02*
X171595D01*
G01X165256Y1124941D02*
X171559D01*
X173000Y1123500D01*
G01X188000Y1179500D02*
Y1144000D01*
X173941Y1129941D01*
X165256D01*
G01X122400Y1146050D02*
Y1149200D01*
G01X119750Y1181025D02*
X124100D01*
G01X145300Y1185900D02*
X152200D01*
G01X117900Y1146050D02*
Y1149200D01*
G01X133100Y1191700D02*
X135800D01*
X137700Y1189800D01*
Y1185900D01*
G01X127250Y1184900D02*
Y1189500D01*
X129450Y1191700D01*
X133100D01*
G01X188000Y1179500D02*
X178550D01*
G01X124250Y1216475D02*
X119534D01*
G01X152575Y1223850D02*
X157325D01*
G01X118250Y1252050D02*
X121500D01*
G01X149500Y1217250D02*
X147250Y1219500D01*
X146800D01*
X146700Y1219600D01*
G01D02*
Y1219425D01*
X143750Y1216475D01*
G01X154000Y1217250D02*
X156854D01*
X158052Y1216052D01*
G01X126000Y1252050D02*
X129150D01*
G01X175894Y1353048D02*
X179147D01*
G01X170402Y1363238D02*
X172404D01*
X175894Y1359748D01*
Y1356548D01*
G01X151209Y1347802D02*
X147956D01*
G01X165256Y1420453D02*
X171595D01*
G01X154331Y1428307D02*
X148095D01*
G01X151125Y1371785D02*
Y1376608D01*
G01X140125Y1378010D02*
Y1381300D01*
G01X167301Y1363238D02*
X170402D01*
G01X190250Y1382000D02*
Y1384947D01*
X188333Y1386864D01*
X177476D01*
X175935Y1385323D01*
X171124D01*
G01X167301Y1363238D02*
X165029D01*
X164066Y1364201D01*
Y1368077D01*
G01X165256Y1435453D02*
X171595D01*
G01X154331Y1437756D02*
X148095D01*
G01X165256Y1450453D02*
X171895D01*
G01X154331Y1447205D02*
X148095D01*
G01X154331Y1453504D02*
X148095D01*
G01X154331Y1462953D02*
X148095D01*
G01X154331Y1472402D02*
X148095D01*
G01X154331Y1478701D02*
X148095D01*
G01X154331Y1488150D02*
X148095D01*
G01X154331Y1497599D02*
X148095D01*
G01X165256Y1495453D02*
X171595D01*
G01X165256Y1500453D02*
X171595D01*
G01X114000Y1473250D02*
Y1470000D01*
G01X122000Y1473250D02*
Y1470000D01*
G01X130000Y1473250D02*
Y1470000D01*
G01X144000Y1464000D02*
X140000D01*
G01X124750Y1502000D02*
X123500Y1503250D01*
Y1505200D01*
G01X118000Y1470000D02*
Y1473250D01*
G01X126000D02*
Y1466000D01*
G01X144000Y1458000D02*
X148000D01*
G01X128250Y1502000D02*
Y1506500D01*
G01X166890Y1461378D02*
X173095D01*
G01X154331Y1507047D02*
X148095D01*
G01X154331Y1516496D02*
X148095D01*
G01X154331Y1525945D02*
X148095D01*
G01X154331Y1535394D02*
X148095D01*
G01X165256Y1530453D02*
X171547D01*
X173000Y1529000D01*
G01X186700Y1585700D02*
Y1549100D01*
X173053Y1535453D01*
X165256D01*
G01X124250Y1621975D02*
X119534D01*
G01X149500Y1622750D02*
X144525D01*
X143750Y1621975D01*
G01D02*
Y1625250D01*
X143500Y1625500D01*
G01X153775Y1629350D02*
X153700Y1629425D01*
Y1633600D01*
G01X152200Y1589800D02*
X149800D01*
X148100Y1591500D01*
X132500D01*
X129725Y1588725D01*
G01X150200Y1628000D02*
Y1626550D01*
X154000Y1622750D01*
G01X159450D02*
X154000D01*
G01X129725Y1581125D02*
X125366D01*
X123042Y1583449D01*
G01X116625Y1584775D02*
X121716D01*
X123042Y1583449D01*
G01X179650Y1585700D02*
X186700D01*
G01X117000Y1657750D02*
Y1654600D01*
G01X126900Y1657750D02*
Y1654700D01*
G01X177717Y1778162D02*
X172002D01*
X170818Y1776978D01*
X170080D01*
G01X170942Y1790692D02*
X180075D01*
G01X165256Y1825965D02*
X171595D01*
G01X154331Y1833819D02*
X148095D01*
G01X165256Y1840965D02*
X171595D01*
G01X154331Y1843268D02*
X148095D01*
G01X165256Y1855965D02*
X171595D01*
G01X154331Y1852717D02*
X148095D01*
G01X154331Y1859016D02*
X148095D01*
G01X166890Y1866890D02*
X173095D01*
G01X144000Y1864000D02*
X148000D01*
G01X154331Y1868465D02*
X148095D01*
G01X154331Y1877914D02*
X148095D01*
G01X154331Y1884213D02*
X148095D01*
G01X154331Y1893662D02*
X148095D01*
G01X154331Y1903111D02*
X148095D01*
G01X154331Y1912559D02*
X148095D01*
G01X154331Y1922008D02*
X148095D01*
G01X154331Y1931457D02*
X148095D01*
G01X165256Y1900965D02*
X171595D01*
G01X165256Y1905965D02*
X171595D01*
G01X165256Y1935965D02*
X171535D01*
X173000Y1934500D01*
G01X144000Y1870000D02*
X140000D01*
G01X154331Y1940906D02*
X148095D01*
G01X126500Y1947250D02*
X123200D01*
G01X143450Y1965200D02*
Y1975664D01*
G01D02*
Y1978867D01*
X146083Y1981500D01*
X177500D01*
X181051Y1977949D01*
Y1947051D01*
X174965Y1940965D01*
X165256D01*
G01X231917Y-224955D02*
Y-304955D01*
G01X200000Y32250D02*
X196665Y35585D01*
G01X200875Y38750D02*
X205625D01*
G01X194250Y31475D02*
Y33170D01*
X196665Y35585D01*
G01X204500Y32250D02*
X208150D01*
G01X195750Y158000D02*
X198800D01*
G01X195750Y162500D02*
X198800D01*
G01X195750Y167000D02*
X198800D01*
G01X199000Y546250D02*
X195500D01*
G01X199000Y538750D02*
X195500D01*
G01X199000Y531250D02*
X195500D01*
G01X203000Y538750D02*
X206500D01*
G01X203000Y546250D02*
X206500D01*
G01X203000Y531250D02*
X206500D01*
G01X195250Y564500D02*
Y561300D01*
G01Y573500D02*
Y576700D01*
G01Y569000D02*
X200250D01*
G01D02*
Y572100D01*
G01X201125Y952727D02*
Y957200D01*
G01X195750Y969500D02*
X198900D01*
G01X207350Y965477D02*
Y968627D01*
G01X195750Y974000D02*
X198900D01*
G01X195750Y978500D02*
X198900D01*
G01X229500Y949727D02*
Y946600D01*
G01X190250Y1373000D02*
X193400D01*
G01X190250Y1377500D02*
X193400D01*
G01X190250Y1382000D02*
X193400D01*
G01X252538Y1490152D02*
X269690D01*
G01X217125Y1763750D02*
X220800D01*
G01X194606Y1772940D02*
X191353D01*
G01X194750Y1781500D02*
X197900D01*
G01X248350Y1769900D02*
X251900D01*
G01X200198Y1762250D02*
X194606Y1767842D01*
Y1769440D01*
G01X200198Y1762250D02*
X201544D01*
X202644Y1763350D01*
X203299D01*
G01X194750Y1786000D02*
X197900D01*
G01X194750Y1790500D02*
X197900D01*
G01X219450Y1776200D02*
X222500D01*
G01X305100Y404050D02*
Y407700D01*
G01X330750Y377000D02*
X327500D01*
G01X309300Y393050D02*
X312500D01*
G01X328250Y404400D02*
X329250Y403400D01*
X333300D01*
G01X321500Y413000D02*
X324750D01*
G01X307900Y416200D02*
X304400D01*
G01X340500Y425000D02*
X328250D01*
G01X329250Y597000D02*
X332500D01*
G01X329250Y589000D02*
X332500D01*
G01X313000Y562250D02*
Y559000D01*
G01X326100Y583400D02*
X329400D01*
X329600Y583200D01*
G01X292000Y608750D02*
Y612000D01*
G01X296000Y608750D02*
Y612000D01*
G01X304000Y608750D02*
Y612000D01*
G01X308000Y608750D02*
Y612000D01*
G01X284000Y608750D02*
Y612000D01*
G01X316000Y608750D02*
Y612000D01*
G01X320100Y583400D02*
Y587200D01*
G01X298450Y562250D02*
Y559000D01*
G01X290580Y562250D02*
Y559000D01*
G01X276750Y585000D02*
X273500D01*
G01X276750Y589000D02*
X273500D01*
G01X276750Y597000D02*
X273500D01*
G01X276750Y573000D02*
X273500D01*
G01X276750Y577000D02*
X273500D01*
G01X276750Y565000D02*
X273500D01*
G01X317500Y562250D02*
Y559000D01*
G01X329250Y593000D02*
X332500D01*
G01X329250Y601000D02*
X332500D01*
G01X324750Y843000D02*
X321500D01*
G01X307900Y846700D02*
X304400D01*
G01X304500Y833550D02*
Y836700D01*
G01Y822550D02*
X301300D01*
G01X330750Y807000D02*
X327500D01*
G01X308600Y822550D02*
X310050D01*
X312000Y824500D01*
G01X333800Y833000D02*
X329650D01*
X328250Y834400D01*
G01Y855000D02*
X340500D01*
G01X305200Y1205000D02*
Y1208300D01*
G01X330750Y1178500D02*
X327500D01*
G01X309300Y1194000D02*
X312500D01*
G01X334500Y1204250D02*
X329800D01*
X328250Y1205800D01*
G01X324750Y1214500D02*
X321500D01*
G01X308000Y1217500D02*
X304500D01*
G01X328250Y1226500D02*
X340500D01*
G01X311500Y1392250D02*
Y1389000D01*
G01X297600Y1395500D02*
Y1392000D01*
G01X303500Y1392250D02*
Y1389000D01*
G01X276750Y1407500D02*
X273500D01*
G01X297600Y1401500D02*
X301400D01*
G01X315500Y1392250D02*
Y1389000D01*
G01X293100Y1386750D02*
Y1383500D01*
G01X284900Y1386750D02*
Y1383500D01*
G01X276750Y1419500D02*
X273500D01*
G01X276750Y1411500D02*
X273500D01*
G01X276750Y1423500D02*
X273500D01*
G01X323250Y1417500D02*
X326500D01*
G01X323250Y1425700D02*
X326500D01*
G01X323250Y1405400D02*
X326500D01*
G01X323250Y1413500D02*
X326500D01*
G01X323250Y1429700D02*
X326500D01*
G01X276750Y1403500D02*
X273500D01*
G01X307500Y1392250D02*
Y1389000D01*
G01X269690Y1473000D02*
Y1490152D01*
G01D02*
Y1507304D01*
G01Y1490152D02*
X286842D01*
G01X276750Y1431500D02*
X273500D01*
G01X287600Y1444750D02*
Y1448000D01*
G01X279650Y1444750D02*
Y1448000D01*
G01X299600Y1444750D02*
Y1448000D01*
G01X291600Y1444750D02*
Y1448000D01*
G01X323250Y1437700D02*
X326500D01*
G01X311600Y1444750D02*
Y1448000D01*
G01X303600Y1444750D02*
Y1448000D01*
G01X324750Y1713000D02*
X321500D01*
G01X330750Y1673000D02*
X327500D01*
G01X309000Y1715700D02*
X305300D01*
G01X306200Y1703500D02*
Y1709600D01*
G01X330750Y1677000D02*
X327500D01*
G01X310300Y1692500D02*
X313500D01*
G01X328250Y1704300D02*
X332800D01*
X333600Y1703500D01*
G01X288000Y1746000D02*
Y1742500D01*
G01X293000Y1746000D02*
Y1742500D01*
G01X279500Y1791750D02*
Y1795000D01*
G01X287500Y1791750D02*
Y1795000D01*
G01X271500Y1791750D02*
Y1795000D01*
G01X280500Y1731250D02*
X284000D01*
G01X291500Y1791750D02*
Y1796500D01*
X290000Y1798000D01*
X285000D01*
X283500Y1796500D01*
G01Y1791750D02*
Y1796500D01*
G01D02*
X282000Y1798000D01*
X277000D01*
X275500Y1796500D01*
Y1791750D01*
G01X297000Y1777000D02*
Y1788500D01*
X293750Y1791750D01*
X291500D01*
G01X293000Y1752000D02*
X297000D01*
G01X293000D02*
X288000D01*
G01X268750Y1722000D02*
X265500D01*
G01X280250D02*
X283500D01*
G01X328250Y1725000D02*
X340500D01*
G01X369417Y-224955D02*
Y-304955D01*
G01X377500Y101250D02*
Y98000D01*
G01X357250Y117000D02*
Y120500D01*
G01D02*
Y124000D01*
G01X373500Y101250D02*
Y98000D01*
G01X363750Y68500D02*
Y65250D01*
G01X352500Y71750D02*
Y68500D01*
G01X374300Y84650D02*
Y81400D01*
G01X363750Y76500D02*
Y73300D01*
G01X378100Y84650D02*
Y81500D01*
G01X363750Y58000D02*
Y54250D01*
G01X382200Y84650D02*
Y81500D01*
G01X382000Y101250D02*
Y98000D01*
G01X360750Y117000D02*
Y120500D01*
G01D02*
Y124000D01*
G01X358000Y64000D02*
Y67250D01*
G01X348500Y71750D02*
X344500D01*
G01X367250Y76500D02*
Y77750D01*
X363500Y81500D01*
G01X367250Y68500D02*
Y76500D01*
G01Y63000D02*
Y58000D01*
G01Y63000D02*
Y68500D01*
G01X378100Y88150D02*
X374300D01*
G01X382200D02*
X378100D01*
G01X374300D02*
X368950D01*
X368800Y88300D01*
G01X373500Y104750D02*
X368450D01*
X368350Y104650D01*
G01X377500Y104750D02*
X382000D01*
G01X377500D02*
X373500D01*
G01X356250Y352500D02*
Y349000D01*
G01X344500Y406250D02*
X341000D01*
G01D02*
X337500D01*
G01X334750Y393000D02*
X331500D01*
G01X393500Y383750D02*
X397000D01*
G01X383750Y349000D02*
Y352500D01*
G01X391750D02*
Y355750D01*
X391800Y355800D01*
G01X395600Y401650D02*
X401350D01*
X401500Y401500D01*
G01X349706Y355693D02*
X348250Y354237D01*
Y352500D01*
G01X398000Y410250D02*
X401500D01*
G01X356250Y341000D02*
Y344169D01*
X356257Y344176D01*
G01X391750Y341000D02*
Y344500D01*
G01X383750Y341000D02*
Y344500D01*
G01X348250Y341000D02*
Y344108D01*
X348256Y344114D01*
G01X334750Y389000D02*
X331500D01*
G01X368500Y371250D02*
X365150D01*
X365100Y371200D01*
G01X395600Y398150D02*
X398850D01*
X401500Y395500D01*
G01X393500Y380250D02*
X397000D01*
G01X372000Y371250D02*
X375200D01*
G01X341000Y402750D02*
X344500D01*
G01X333300Y403400D02*
X335200D01*
X335850Y402750D01*
X341000D01*
G01X346500Y416750D02*
X343000D01*
G01D02*
X339500D01*
G01X393500Y414750D02*
X397000D01*
G01X379250Y447500D02*
Y451000D01*
G01X343750Y447500D02*
Y451000D01*
G01X350241Y444377D02*
X351750Y445886D01*
Y447500D01*
G01X385896Y444265D02*
X387250Y445619D01*
Y447500D01*
G01X351750Y459000D02*
Y455831D01*
X351729Y455810D01*
G01X379250Y459000D02*
Y455900D01*
X379258Y455892D01*
G01X387250Y459000D02*
Y455883D01*
X387249Y455882D01*
G01X343750Y459000D02*
Y455831D01*
X343729Y455810D01*
G01X368500Y429250D02*
X364759D01*
X364758Y429249D01*
G01X372000Y429250D02*
X375200D01*
G01X398700Y420500D02*
X396450Y418250D01*
X393500D01*
G01D02*
Y422000D01*
G01X343000Y420250D02*
Y422500D01*
X340500Y425000D01*
G01X346500Y420250D02*
X343000D01*
G01X332750Y578600D02*
X336000D01*
G01X332750Y570580D02*
X336000D01*
G01X377250Y771000D02*
Y774500D01*
G01X385250Y771000D02*
Y774110D01*
X385238Y774122D01*
G01X339500Y846750D02*
X343000D01*
G01X337500Y836250D02*
X341000D01*
G01X334750Y823000D02*
X331500D01*
G01X341000Y836250D02*
X344500D01*
G01X343000Y846750D02*
X346500D01*
G01X393500Y844750D02*
X397000D01*
G01X393500Y833250D02*
X396250Y836000D01*
X401500D01*
G01X377250Y779000D02*
Y782500D01*
G01X391750Y806500D02*
X395000D01*
G01X385250Y782500D02*
Y785700D01*
G01X400750Y840500D02*
X404000D01*
G01X334750Y819000D02*
X331500D01*
G01X401500Y830000D02*
X397500D01*
X397250Y829750D01*
X393500D01*
G01X362000Y803750D02*
X358950D01*
X358800Y803600D01*
G01X365500Y803750D02*
X368700D01*
G01X388250Y806500D02*
Y803300D01*
G01X398700Y850500D02*
X396450Y848250D01*
X393500D01*
G01D02*
Y852000D01*
G01X341000Y832750D02*
X344500D01*
G01X333800Y833000D02*
X334050Y832750D01*
X341000D01*
G01X351740Y880717D02*
Y880551D01*
X351750Y880541D01*
Y877500D01*
G01X368500Y861750D02*
Y865000D01*
G01X372000Y861750D02*
Y865000D01*
G01X387250Y881000D02*
Y877500D01*
G01X343750D02*
Y874299D01*
X343749Y874298D01*
G01X379250Y877500D02*
Y874299D01*
X379228Y874277D01*
G01X351750Y889000D02*
Y885877D01*
X351792Y885835D01*
G01X379250Y889000D02*
Y885917D01*
X379270Y885897D01*
G01X387250Y889000D02*
Y885939D01*
X387292Y885897D01*
G01X343750Y889000D02*
Y885917D01*
X343770Y885897D01*
G01X360800Y858500D02*
X364500D01*
X364750Y858250D01*
X368500D01*
G01X372000D02*
X375200D01*
G01X340500Y855000D02*
X343000Y852500D01*
Y850250D01*
G01D02*
X346500D01*
G01X334750Y1194500D02*
X331500D01*
G01X344500Y1207750D02*
X341000D01*
G01D02*
X337500D01*
G01X383750Y1150500D02*
Y1154000D01*
G01X393500Y1181250D02*
X396750D01*
G01X391750Y1154000D02*
Y1157837D01*
X391765Y1157852D01*
G01X395600Y1202250D02*
X401750D01*
X402000Y1202500D01*
G01X402250Y1192000D02*
X405500D01*
G01X391750Y1142500D02*
Y1145668D01*
X391758Y1145676D01*
G01X383750Y1142500D02*
Y1145648D01*
X383757Y1145655D01*
G01X334750Y1190500D02*
X331500D01*
G01X367500Y1174750D02*
X364450D01*
X364300Y1174900D01*
G01X395600Y1198750D02*
X399750D01*
X402000Y1196500D01*
G01X371000Y1174750D02*
X374200D01*
G01X393500Y1177750D02*
X394887D01*
X396637Y1176000D01*
G01X344500Y1204250D02*
X341000D01*
G01X334500D02*
X341000D01*
G01X387208Y1252212D02*
Y1249042D01*
X387250Y1249000D01*
G01X343000Y1218250D02*
X339500D01*
G01X346500D02*
X343000D01*
G01X393500Y1221750D02*
Y1220500D01*
X391500Y1218500D01*
G01X379250Y1249000D02*
Y1245783D01*
X379249Y1245782D01*
G01X343750Y1249000D02*
Y1245720D01*
X343749Y1245719D01*
G01X351771Y1252213D02*
X351750Y1252192D01*
Y1249000D01*
G01Y1260500D02*
Y1257380D01*
G01X379250Y1260500D02*
Y1257400D01*
X379270Y1257380D01*
G01X387250Y1260500D02*
Y1257402D01*
X387292Y1257360D01*
G01X343750Y1260500D02*
Y1257391D01*
X343760Y1257381D01*
G01X368500Y1229750D02*
X365250D01*
X365200Y1229800D01*
G01X393500Y1225250D02*
Y1225300D01*
X400700Y1232500D01*
G01D02*
Y1237500D01*
G01X372000Y1229750D02*
X375200D01*
G01X343000Y1221750D02*
Y1224000D01*
X340500Y1226500D01*
G01X346500Y1221750D02*
X343000D01*
G01X356250Y1641000D02*
Y1644120D01*
X356247Y1644123D01*
G01X348250Y1641000D02*
Y1644125D01*
X348257Y1644132D01*
G01X334750Y1695000D02*
X331500D01*
G01X344500Y1706250D02*
X341000D01*
G01D02*
X337500D01*
G01X343000Y1716750D02*
X339500D01*
G01X346500D02*
X343000D01*
G01X388750Y1676500D02*
Y1673000D01*
G01X348250Y1649000D02*
Y1652500D01*
G01X402000Y1701000D02*
X401750Y1700750D01*
X395700D01*
G01X356250Y1652500D02*
Y1655710D01*
X356238Y1655722D01*
G01X334750Y1691000D02*
X331500D01*
G01X372500Y1673750D02*
X369150D01*
X369100Y1673700D01*
G01X402000Y1695000D02*
X399750Y1697250D01*
X395700D01*
G01X385250Y1676500D02*
Y1673000D01*
G01X376000Y1673750D02*
X379500D01*
G01X340500Y1725000D02*
X343000Y1722500D01*
Y1720250D01*
G01D02*
X346500D01*
G01X344500Y1702750D02*
X341000D01*
G01X333600Y1703500D02*
X334350Y1702750D01*
X341000D01*
G01X389750Y1723500D02*
X393000D01*
G01X351750Y1751000D02*
Y1747500D01*
G01X343750D02*
Y1744228D01*
X343709Y1744187D01*
G01X379000Y1732750D02*
Y1736000D01*
G01X351750Y1759000D02*
Y1755500D01*
G01X343750Y1759000D02*
Y1755500D01*
G01X369000Y1727750D02*
X365750D01*
X365700Y1727700D01*
G01X386250Y1723500D02*
Y1726950D01*
X388000Y1728700D01*
G01X372500Y1727750D02*
X375700D01*
G01X406300Y420500D02*
X410550D01*
G01X414281Y820751D02*
X414355D01*
X414356Y820750D01*
X417500D01*
G01X421000Y812750D02*
X417500D01*
G01X429000Y820750D02*
X425911D01*
X425890Y820729D01*
G01X429000Y812750D02*
X425891D01*
G01X406300Y850500D02*
X410550D01*
G01X417500Y1223250D02*
X414278D01*
X414274Y1223246D01*
G01X420743Y1215266D02*
X420727Y1215250D01*
X417500D01*
G01X408300Y1232500D02*
Y1237500D01*
G01X429000Y1215250D02*
X425500D01*
G01X429000Y1223250D02*
X425500D01*
G01X421000Y1713750D02*
X417500D01*
G01X429000D02*
X425500D01*
G01X429000Y1721750D02*
X425905D01*
X425879Y1721724D01*
G01X417500Y1721750D02*
X414299D01*
G01X484417Y-224955D02*
Y-304955D01*
G01X651917Y-224955D02*
Y-304955D01*
G01X816500Y774750D02*
X811250D01*
X809000Y777000D01*
G01X872500Y1053500D02*
X866985D01*
G01X816500Y1180250D02*
X812250D01*
G01X872500Y1459000D02*
X867359D01*
G01X764739Y1959757D02*
Y1953007D01*
G01X821917Y-224955D02*
Y-304955D01*
G01X828500Y174250D02*
Y171000D01*
G01X836500Y174250D02*
X840000D01*
G01X820500D02*
Y171000D01*
G01X832500Y174250D02*
Y171000D01*
G01X824500Y174250D02*
Y171000D01*
G01X816500Y174250D02*
Y171000D01*
G01X831250Y203000D02*
X828000D01*
G01X844000Y190000D02*
Y199000D01*
X839999Y203001D01*
X834751D01*
X834750Y203000D01*
G01X821000Y369250D02*
X824335Y365915D01*
G01D02*
X826750Y368330D01*
Y370025D01*
G01X820125Y362750D02*
X815375D01*
G01X816500Y369250D02*
X813350D01*
G01X821000Y774750D02*
X824335Y771415D01*
G01D02*
X826750Y773830D01*
Y775525D01*
G01X820125Y768250D02*
X815375D01*
G01X821000Y1180250D02*
X824335Y1176915D01*
G01D02*
X826750Y1179330D01*
Y1181025D01*
G01X820125Y1173750D02*
X815375D01*
G01X821000Y1585750D02*
X824335Y1582415D01*
G01D02*
X826750Y1584830D01*
Y1586525D01*
G01X820125Y1579250D02*
X816625D01*
G01X813000Y1585750D02*
X816500D01*
G01X837500Y1788250D02*
Y1785000D01*
G01X829500Y1788250D02*
Y1785000D01*
G01X819000Y1788250D02*
Y1785000D01*
G01X857687Y1765937D02*
X861750Y1770000D01*
G01X815000Y1785000D02*
Y1788250D01*
G01X825500Y1785000D02*
X822500Y1782000D01*
X818000D01*
X815000Y1785000D01*
G01X825500D02*
Y1788250D01*
G01X841500D02*
Y1785000D01*
X838500Y1782000D01*
X828500D01*
X825500Y1785000D01*
G01X831250Y1817000D02*
X827500D01*
G01X871500Y1864000D02*
X866289D01*
G01X834750Y1823285D02*
Y1817000D01*
G01X769239Y1955776D02*
Y1959757D01*
G01X794489Y1960532D02*
X799205D01*
G01X784964Y1953257D02*
X780214D01*
G01X774989Y1960532D02*
Y1955708D01*
G01X788389Y1960907D02*
X785239D01*
G01X853600Y1973100D02*
Y1975400D01*
X852000Y1977000D01*
X818400D01*
X815339Y1973939D01*
Y1967007D01*
G01X801989Y1964407D02*
X806439D01*
X808339Y1962507D01*
G01X815339Y1959407D02*
X811439D01*
X808339Y1962507D01*
G01X905240Y136513D02*
X908493D01*
G01X869250Y141125D02*
Y144750D01*
G01X885531Y164804D02*
Y166819D01*
X887066Y168354D01*
G01X886250Y161000D02*
Y164085D01*
X885531Y164804D01*
G01X899648Y147203D02*
X896441D01*
G01X866961Y159411D02*
Y162539D01*
G01X905134Y140013D02*
Y143713D01*
X901644Y147203D01*
X899648D01*
G01X896441D02*
X896133D01*
X893708Y149628D01*
Y151978D01*
X895225Y153495D01*
Y154724D01*
G01X882677Y255866D02*
X876441D01*
G01X882677Y262165D02*
X876441D01*
G01X893602Y203917D02*
X899941D01*
G01X882677Y211771D02*
X876441D01*
G01X893602Y218917D02*
X899941D01*
G01X882677Y221220D02*
X876441D01*
G01X893602Y233917D02*
X899941D01*
G01X882677Y230669D02*
X876441D01*
G01X882677Y236968D02*
X876441D01*
G01X882677Y246417D02*
X876441D01*
G01X872500Y245000D02*
Y241500D01*
G01Y251000D02*
X876500D01*
G01X895236Y244842D02*
X901441D01*
G01X882677Y271614D02*
X876441D01*
G01X882677Y281063D02*
X876441D01*
G01X882677Y290511D02*
X876441D01*
G01X882677Y299960D02*
X876441D01*
G01X882677Y309409D02*
X876441D01*
G01X882677Y318858D02*
X876441D01*
G01X893602Y278917D02*
X899941D01*
G01X893602Y283917D02*
X899941D01*
G01X893602Y313917D02*
X900083D01*
X901500Y312500D01*
G01X856200Y334250D02*
Y337300D01*
G01X844050Y334250D02*
Y337300D01*
G01X915900Y368600D02*
Y326666D01*
X908151Y318917D01*
X893602D01*
G01X846250Y370025D02*
X850966D01*
G01X874400Y376400D02*
X881000D01*
G01X861890Y383014D02*
X864986D01*
X866800Y381200D01*
Y376400D01*
G01X853750Y373900D02*
Y381750D01*
X855014Y383014D01*
X861890D01*
G01X908250Y368600D02*
X915900D01*
G01X904240Y542025D02*
X907493D01*
G01X872875Y539715D02*
Y535275D01*
G01X898754Y552715D02*
X895547D01*
G01X904240Y545525D02*
Y549225D01*
X900750Y552715D01*
X898754D01*
G01X861750Y553465D02*
X857735D01*
G01X895547Y552715D02*
X895133D01*
X892708Y555140D01*
Y557490D01*
X893491Y558273D01*
Y560408D01*
G01X882677Y617283D02*
X876441D01*
G01X893602Y624429D02*
X899941D01*
G01X882677Y626732D02*
X876441D01*
G01X893602Y609429D02*
X899941D01*
G01X884500Y560715D02*
Y563800D01*
X883781Y564519D01*
G01X923250Y569965D02*
Y572774D01*
X921602Y574422D01*
X899426D01*
G01X882677Y696023D02*
X876441D01*
G01X893602Y689429D02*
X899941D01*
G01X893602Y639429D02*
X899941D01*
G01X882677Y636181D02*
X876441D01*
G01X882677Y642480D02*
X876441D01*
G01X882677Y651929D02*
X876441D01*
G01X882677Y661378D02*
X876441D01*
G01X882677Y667677D02*
X876441D01*
G01X882677Y677126D02*
X876441D01*
G01X882677Y686575D02*
X876441D01*
G01X893602Y684429D02*
X899941D01*
G01X872500Y654000D02*
X868500D01*
G01X895236Y650354D02*
X901441D01*
G01X872500Y648000D02*
X876500D01*
G01X882677Y705472D02*
X876441D01*
G01X882677Y714921D02*
X876441D01*
G01X882677Y724370D02*
X876441D01*
G01X893602Y719429D02*
X900071D01*
X901500Y718000D01*
G01X856100Y740250D02*
Y743300D01*
G01X846250Y775525D02*
X850966D01*
G01X846200Y740250D02*
Y743300D01*
G01X893602Y724429D02*
X909809D01*
X915800Y730420D01*
Y774600D01*
G01D02*
X907950D01*
G01X873900Y781900D02*
X880900D01*
G01X859737Y789667D02*
X864333D01*
X866300Y787700D01*
Y781900D01*
G01X853750Y779400D02*
Y788250D01*
X855167Y789667D01*
X859737D01*
G01X904240Y947537D02*
X907493D01*
G01X872875Y945227D02*
Y940925D01*
G01X895547Y958227D02*
X895169D01*
Y958330D01*
X895030D01*
X892708Y960652D01*
Y963559D01*
X893724Y964575D01*
Y965913D01*
G01X884500Y966227D02*
Y969312D01*
X883781Y970031D01*
G01X904240Y951037D02*
Y954737D01*
X900750Y958227D01*
X898648D01*
G01X895547D02*
X898648D01*
G01X861750Y958977D02*
X857623D01*
G01X883781Y970031D02*
Y972132D01*
X885506Y973857D01*
X889909D01*
G01X882677Y1057441D02*
X876441D01*
G01X893602Y1014941D02*
X899941D01*
G01X882677Y1022795D02*
X876441D01*
G01X893602Y1029941D02*
X899941D01*
G01X882677Y1032244D02*
X876441D01*
G01X893602Y1044941D02*
X899941D01*
G01X882677Y1041693D02*
X876441D01*
G01X882677Y1047992D02*
X876441D01*
G01X872500Y1059500D02*
X868500D01*
G01X872500Y1053500D02*
X876500D01*
G01X895236Y1055866D02*
X901441D01*
G01X882677Y1129882D02*
X876441D01*
G01X893602Y1124941D02*
X900059D01*
X901500Y1123500D01*
G01X882677Y1066890D02*
X876441D01*
G01X882677Y1073189D02*
X876441D01*
G01X882677Y1082638D02*
X876441D01*
G01X882677Y1092087D02*
X876441D01*
G01X882677Y1101535D02*
X876441D01*
G01X882677Y1110984D02*
X876441D01*
G01X882677Y1120433D02*
X876441D01*
G01X893602Y1089941D02*
X899941D01*
G01X893602Y1094941D02*
X899941D01*
G01X919100Y1180600D02*
Y1147400D01*
X901641Y1129941D01*
X893602D01*
G01X854500Y1145650D02*
Y1148700D01*
G01X846250Y1181025D02*
X850600D01*
G01X880600Y1184900D02*
X878100Y1187400D01*
X873900D01*
G01X844600Y1145650D02*
Y1148700D01*
G01X860272Y1194370D02*
X864630D01*
X866300Y1192700D01*
Y1187400D01*
G01X853750Y1184900D02*
Y1192750D01*
X855370Y1194370D01*
X860272D01*
G01X912050Y1180600D02*
X919100D01*
G01X904240Y1353048D02*
X907493D01*
G01X872875Y1350738D02*
Y1346488D01*
G01X898748Y1363738D02*
X900750D01*
X904240Y1360248D01*
Y1356548D01*
G01X893602Y1420453D02*
X899941D01*
G01X882677Y1428307D02*
X876441D01*
G01X893335Y1371351D02*
Y1369893D01*
X892724Y1369282D01*
Y1366290D01*
X892808Y1366206D01*
Y1366163D01*
X894571Y1364400D01*
X894614D01*
X895276Y1363738D01*
X895647D01*
G01X883938Y1369700D02*
Y1372785D01*
X883219Y1373504D01*
G01X861750Y1364488D02*
X857688D01*
G01X898748Y1363738D02*
X895647D01*
G01X890213Y1376446D02*
X886161D01*
X883219Y1373504D01*
G01X882677Y1488150D02*
X876441D01*
G01X882677Y1497599D02*
X876441D01*
G01X893602Y1495453D02*
X899941D01*
G01X893602Y1500453D02*
X899941D01*
G01X882677Y1437756D02*
X876441D01*
G01X893602Y1450453D02*
X899941D01*
G01X882677Y1447205D02*
X876441D01*
G01X882677Y1453504D02*
X876441D01*
G01X882677Y1462953D02*
X876441D01*
G01X882677Y1472402D02*
X876441D01*
G01X882677Y1478701D02*
X876441D01*
G01X893602Y1435453D02*
X899941D01*
G01X872500Y1465000D02*
X868500D01*
G01X872500Y1459000D02*
X876500D01*
G01X895236Y1461378D02*
X901441D01*
G01X882677Y1507047D02*
X876441D01*
G01X882677Y1516496D02*
X876441D01*
G01X882677Y1525945D02*
X876441D01*
G01X882677Y1535394D02*
X876441D01*
G01X893602Y1530453D02*
X900047D01*
X901500Y1529000D01*
G01X855500Y1551250D02*
Y1554300D01*
G01X845600Y1551250D02*
Y1554300D01*
G01X918600Y1584600D02*
Y1545875D01*
X908178Y1535453D01*
X893602D01*
G01X846250Y1586525D02*
X850966D01*
G01X881800Y1590400D02*
X877800Y1594400D01*
X873900D01*
G01X858185Y1601013D02*
X863400D01*
X866300Y1598113D01*
Y1594400D01*
G01X853750Y1590400D02*
Y1599500D01*
X855263Y1601013D01*
X858185D01*
G01X910550Y1584600D02*
X918600D01*
G01X885750Y1698000D02*
Y1701500D01*
G01X884500Y1723200D02*
X887800D01*
X891000Y1720000D01*
G01X910500Y1713500D02*
X906000D01*
G01X901500Y1685000D02*
Y1681500D01*
G01X881500Y1699750D02*
Y1702500D01*
X884223Y1705223D01*
G01X881500Y1696250D02*
X880250Y1695000D01*
X877000D01*
G01X901500Y1691000D02*
X896500D01*
G01Y1696300D02*
Y1691000D01*
G01X910500Y1707500D02*
X907000D01*
X905484Y1709016D01*
G01X916200Y1708700D02*
X915000Y1707500D01*
X910500D01*
G01X898000Y1719500D02*
X902500Y1724000D01*
Y1727250D01*
G01X872875Y1756250D02*
Y1751600D01*
G01X906500Y1730750D02*
Y1734100D01*
G01X904240Y1758560D02*
X907493D01*
G01X898500Y1730750D02*
Y1734000D01*
G01X910500Y1731250D02*
Y1734600D01*
G01X904240Y1762060D02*
Y1765760D01*
X900750Y1769250D01*
X898800D01*
G01D02*
X895547D01*
G01X884500Y1777250D02*
Y1780335D01*
X883781Y1781054D01*
G01X898942Y1790816D02*
X920199D01*
X923228Y1787787D01*
Y1786522D01*
X923250Y1786500D01*
G01X895547Y1769250D02*
X894257D01*
X891753Y1771754D01*
Y1775003D01*
X893650Y1776900D01*
G01X884500Y1730800D02*
X879800D01*
X878000Y1729000D01*
G01X910500Y1727750D02*
Y1724700D01*
G01X902500Y1727250D02*
X906500D01*
G01D02*
X908000D01*
X908500Y1727750D01*
X910500D01*
G01X882677Y1852717D02*
X876441D01*
G01X882677Y1859016D02*
X876441D01*
G01X882677Y1843268D02*
X876441D01*
G01X882677Y1833819D02*
X876441D01*
G01X893602Y1840965D02*
X899941D01*
G01X893602Y1825965D02*
X899941D01*
G01X893602Y1855965D02*
X899941D01*
G01X871500Y1864000D02*
X876000D01*
G01X895236Y1866890D02*
X901441D01*
G01X871500Y1870000D02*
X867500D01*
G01X882677Y1931457D02*
X876441D01*
G01X882677Y1903111D02*
X876441D01*
G01X882677Y1912559D02*
X876441D01*
G01X882677Y1868465D02*
X876441D01*
G01X882677Y1877914D02*
X876441D01*
G01X882677Y1884213D02*
X876441D01*
G01X882677Y1893662D02*
X876441D01*
G01X893602Y1905965D02*
X899941D01*
G01X893602Y1900965D02*
X899941D01*
G01X893602Y1935965D02*
X900035D01*
X901500Y1934500D01*
G01X882677Y1922008D02*
X876441D01*
G01X847850Y1949700D02*
X844800D01*
G01X882677Y1940906D02*
X876441D01*
G01X847850Y1945200D02*
X844700D01*
G01X893602Y1940965D02*
X903963D01*
X903964Y1940964D01*
X908000Y1945000D01*
Y1977000D01*
X904600Y1980400D01*
X874200D01*
X871750Y1977950D01*
Y1975500D01*
G01Y1965500D02*
Y1975500D01*
G01X923250Y155500D02*
X926347D01*
G01X923250Y160000D02*
X926347D01*
G01X923250Y164453D02*
X926347D01*
G01X923250Y561000D02*
X926365D01*
G01X923250Y565500D02*
X926365D01*
G01X923250Y569965D02*
X926365D01*
G01X923250Y966500D02*
X926477D01*
G01X923250Y975477D02*
X926477D01*
G01X923250Y971000D02*
X926477D01*
G01X923250Y1372000D02*
X926300D01*
G01X923250Y1380988D02*
X926300D01*
G01X923250Y1376500D02*
X926300D01*
G01X959000Y1627400D02*
Y1631000D01*
G01X963500Y1671000D02*
Y1675000D01*
G01Y1661000D02*
Y1657000D01*
G01X959000Y1671750D02*
Y1675000D01*
G01Y1660250D02*
Y1657000D01*
G01X916200Y1708700D02*
Y1711350D01*
X915750Y1711800D01*
Y1715000D01*
G01X919250D02*
Y1711500D01*
G01X916500Y1726600D02*
Y1729500D01*
G01X923250Y1777500D02*
X926400D01*
G01X923250Y1782000D02*
X926400D01*
G01X923250Y1786500D02*
X926400D01*
G01X1019417Y-224955D02*
Y-304955D01*
G01X1047417Y-208955D02*
G02I-12000J0D01*
G01X1042267D02*
G02I-6850J0D01*
G01X1035417Y-224955D02*
Y-192955D01*
G01X1051417Y-208955D02*
X1019417D01*
X20000Y40000D03*
Y20000D03*
X5500Y40982D03*
Y20982D03*
X10018Y5500D03*
X30018D03*
X20000Y80000D03*
Y100000D03*
Y120000D03*
Y60000D03*
X5500Y120982D03*
Y100982D03*
Y80982D03*
Y60982D03*
X20000Y160000D03*
Y180000D03*
Y140000D03*
X5500Y180982D03*
Y160982D03*
Y140982D03*
X20000Y240000D03*
Y200000D03*
Y220000D03*
X5500Y260982D03*
Y240982D03*
Y220982D03*
Y200982D03*
Y320982D03*
Y300982D03*
Y280982D03*
X27500Y380000D03*
X20000D03*
Y400000D03*
X5500Y400982D03*
Y380982D03*
Y360982D03*
Y340982D03*
X20000Y340000D03*
X27000Y440000D03*
X20000Y460000D03*
Y440000D03*
Y480000D03*
Y420000D03*
X5500Y480982D03*
Y460982D03*
Y440982D03*
Y420982D03*
X27500Y540000D03*
Y553500D03*
X20000Y540000D03*
Y500000D03*
Y520000D03*
X5500Y540982D03*
Y520982D03*
Y500982D03*
X24500Y624897D03*
Y612249D03*
Y619093D03*
Y606544D03*
Y599700D03*
X16500Y624765D03*
Y618765D03*
Y612166D03*
Y606166D03*
Y598197D03*
X20000Y607620D03*
Y610820D03*
Y620218D03*
Y623418D03*
X27529Y601522D03*
Y604722D03*
Y614071D03*
Y617271D03*
Y626719D03*
Y629919D03*
X24500Y700488D03*
Y694733D03*
Y687889D03*
Y675291D03*
Y682135D03*
Y669537D03*
Y662693D03*
Y637496D03*
Y644340D03*
Y631741D03*
X16500Y700355D03*
Y694355D03*
Y687757D03*
Y681757D03*
Y675158D03*
Y669158D03*
Y662226D03*
Y657000D03*
Y649500D03*
Y644530D03*
Y637363D03*
Y631363D03*
X20000Y658013D03*
Y661213D03*
Y670612D03*
Y673812D03*
Y683210D03*
Y686410D03*
Y632817D03*
Y636017D03*
Y695809D03*
Y699009D03*
Y645415D03*
Y648615D03*
X27529Y664515D03*
Y667715D03*
Y677113D03*
Y680313D03*
Y689711D03*
Y692911D03*
Y702310D03*
Y639318D03*
Y642518D03*
X24500Y769579D03*
Y763825D03*
Y756981D03*
Y725485D03*
Y732329D03*
Y719730D03*
Y712886D03*
Y707332D03*
X16500Y769646D03*
Y763646D03*
Y757048D03*
Y725552D03*
Y719552D03*
Y712953D03*
Y706953D03*
Y751658D03*
Y732500D03*
X20000Y708407D03*
Y711607D03*
Y721006D03*
Y724206D03*
Y752502D03*
Y755702D03*
Y765100D03*
Y768300D03*
X27529Y714708D03*
Y717908D03*
Y727307D03*
Y730507D03*
Y758803D03*
Y762003D03*
Y705510D03*
Y771401D03*
Y774601D03*
X27699Y737535D03*
X24500Y848664D03*
Y841820D03*
Y836266D03*
Y829422D03*
Y816823D03*
Y823667D03*
Y804225D03*
Y811069D03*
Y798470D03*
Y791626D03*
Y776423D03*
X16500Y848686D03*
Y842087D03*
Y836087D03*
Y829489D03*
Y823489D03*
Y816891D03*
Y810891D03*
Y804292D03*
Y798292D03*
Y791694D03*
Y785694D03*
Y777725D03*
X20000Y837541D03*
Y840741D03*
Y787147D03*
Y790347D03*
Y799746D03*
Y802946D03*
Y812344D03*
Y815544D03*
Y824943D03*
Y828143D03*
X27529Y843642D03*
Y846842D03*
Y793448D03*
Y796648D03*
Y806047D03*
Y809247D03*
Y818645D03*
Y821845D03*
Y831244D03*
Y834444D03*
X24500Y911856D03*
Y905012D03*
Y892414D03*
Y899258D03*
Y886509D03*
Y879665D03*
Y867017D03*
Y873861D03*
Y854419D03*
Y861263D03*
X16500Y917678D03*
Y911678D03*
Y905079D03*
Y899079D03*
Y879883D03*
Y873883D03*
Y867284D03*
Y861284D03*
Y854686D03*
Y889500D03*
X20000Y900533D03*
Y903733D03*
Y850139D03*
Y853339D03*
Y913132D03*
Y916332D03*
Y862738D03*
Y865938D03*
Y875336D03*
Y878536D03*
X27529Y894236D03*
Y897436D03*
Y856241D03*
Y859441D03*
Y906834D03*
Y910034D03*
Y868839D03*
Y872039D03*
Y881487D03*
Y884687D03*
X34872Y890906D03*
X36000Y960000D03*
X20000Y980000D03*
Y960000D03*
Y940000D03*
X16000Y931000D03*
X34500Y925000D03*
X5500Y980299D03*
X30000Y991000D03*
X36500Y999500D03*
X5500Y1040299D03*
Y1020299D03*
Y1000299D03*
X23291Y1062791D03*
X24500Y1133365D03*
Y1102601D03*
Y1095769D03*
Y1108368D03*
Y1115200D03*
X16500Y1140024D03*
Y1120828D03*
Y1114828D03*
Y1108229D03*
Y1102229D03*
Y1133500D03*
Y1094260D03*
X31707Y1086000D03*
X20000Y1103683D03*
Y1106883D03*
Y1116281D03*
Y1119481D03*
X27529Y1135181D03*
Y1138381D03*
Y1097585D03*
Y1100785D03*
Y1110184D03*
Y1113384D03*
X32335Y1122002D03*
X37396Y1130912D03*
X33971Y1131741D03*
X24500Y1208955D03*
Y1196357D03*
Y1203189D03*
Y1183758D03*
Y1190590D03*
Y1171160D03*
Y1177992D03*
Y1165394D03*
Y1158562D03*
Y1152795D03*
Y1145963D03*
Y1140197D03*
X16500Y1209016D03*
Y1203016D03*
Y1196418D03*
Y1190418D03*
Y1183820D03*
Y1177820D03*
Y1171221D03*
Y1165221D03*
Y1158623D03*
Y1152623D03*
Y1146024D03*
X20000Y1141478D03*
Y1144678D03*
Y1191872D03*
Y1195072D03*
Y1154076D03*
Y1157276D03*
Y1204470D03*
Y1207670D03*
Y1166675D03*
Y1169875D03*
Y1179273D03*
Y1182473D03*
X27529Y1185574D03*
Y1188774D03*
Y1147779D03*
Y1150979D03*
Y1198173D03*
Y1201373D03*
Y1160378D03*
Y1163578D03*
Y1210771D03*
Y1172976D03*
Y1176176D03*
X24500Y1285079D03*
Y1278247D03*
Y1272480D03*
Y1265648D03*
Y1259882D03*
Y1253050D03*
Y1228386D03*
Y1221554D03*
Y1215787D03*
X16500Y1284906D03*
Y1278308D03*
Y1272308D03*
Y1265709D03*
Y1259709D03*
Y1253111D03*
Y1247721D03*
Y1221615D03*
Y1215615D03*
Y1228500D03*
X20000Y1261163D03*
Y1264363D03*
Y1273761D03*
Y1276961D03*
Y1217069D03*
Y1220269D03*
Y1248565D03*
Y1251765D03*
X27529Y1254866D03*
Y1258066D03*
Y1267464D03*
Y1270664D03*
Y1280063D03*
Y1283263D03*
Y1213971D03*
Y1223370D03*
Y1226570D03*
X33201Y1230674D03*
X32959Y1234478D03*
X36000Y1236000D03*
X24500Y1357720D03*
Y1350888D03*
Y1345121D03*
Y1338289D03*
Y1332523D03*
Y1325691D03*
Y1319924D03*
Y1313092D03*
Y1290845D03*
Y1297677D03*
X34000Y1321000D03*
X16500Y1357347D03*
Y1350749D03*
Y1344749D03*
Y1338150D03*
Y1332150D03*
Y1325552D03*
Y1319552D03*
Y1303505D03*
Y1297505D03*
Y1290906D03*
X16417Y1311583D03*
X20000Y1321006D03*
Y1324206D03*
Y1333604D03*
Y1336804D03*
Y1346202D03*
Y1349402D03*
Y1286360D03*
Y1289560D03*
Y1298958D03*
Y1302158D03*
X27529Y1314908D03*
Y1318108D03*
Y1327507D03*
Y1330707D03*
Y1340105D03*
Y1343305D03*
Y1352704D03*
Y1355904D03*
Y1292661D03*
Y1295861D03*
X36170Y1308434D03*
X33699Y1301782D03*
X26500Y1305121D03*
X33938Y1311000D03*
X38500D03*
X30000Y1305000D03*
X30700Y1308600D03*
X24500Y1401081D03*
Y1407913D03*
Y1388483D03*
Y1395315D03*
Y1375884D03*
Y1382716D03*
Y1370118D03*
Y1363286D03*
X21000Y1424500D03*
X16500Y1413741D03*
Y1407741D03*
Y1401142D03*
Y1395142D03*
Y1388544D03*
Y1382544D03*
Y1375946D03*
Y1369946D03*
Y1363347D03*
X20000Y1371399D03*
Y1374599D03*
Y1383998D03*
Y1387198D03*
Y1396596D03*
Y1399796D03*
Y1358801D03*
Y1362001D03*
Y1409195D03*
Y1412395D03*
X27529Y1365102D03*
Y1368302D03*
Y1377700D03*
Y1380900D03*
Y1390299D03*
Y1393499D03*
Y1402897D03*
Y1406097D03*
X27000Y1417500D03*
X32500Y1417600D03*
X22000Y1487000D03*
X37000Y1443500D03*
X30500Y1463500D03*
X28000Y1444000D03*
X36401Y1521623D03*
X32801D03*
X24500Y1560197D03*
Y1566907D03*
Y1547598D03*
Y1554308D03*
Y1522401D03*
Y1529111D03*
Y1541710D03*
Y1535000D03*
X16500Y1573000D03*
Y1566500D03*
Y1560500D03*
Y1554000D03*
Y1548000D03*
Y1541500D03*
Y1535000D03*
Y1529000D03*
Y1521031D03*
Y1512500D03*
X20000Y1530454D03*
Y1533654D03*
Y1543052D03*
Y1546252D03*
Y1555650D03*
Y1558850D03*
Y1568249D03*
Y1571449D03*
X27529Y1524156D03*
Y1527356D03*
Y1536755D03*
Y1539955D03*
Y1549353D03*
Y1552553D03*
Y1561952D03*
Y1565152D03*
X33001Y1518123D03*
X36201D03*
X24500Y1632638D03*
Y1639348D03*
Y1626749D03*
Y1620039D03*
Y1614151D03*
Y1607441D03*
Y1601552D03*
Y1594842D03*
Y1588954D03*
Y1582244D03*
X16500Y1644735D03*
Y1639845D03*
Y1633000D03*
Y1626500D03*
Y1620000D03*
Y1614000D03*
Y1607500D03*
Y1601500D03*
Y1595000D03*
Y1588500D03*
Y1582500D03*
X20000Y1640690D03*
Y1643890D03*
Y1593496D03*
Y1590296D03*
Y1606094D03*
Y1602894D03*
Y1618693D03*
Y1615493D03*
Y1631291D03*
Y1628091D03*
X27529Y1634393D03*
Y1637593D03*
Y1587199D03*
Y1583999D03*
Y1599797D03*
Y1596597D03*
Y1612396D03*
Y1609196D03*
Y1624994D03*
Y1621794D03*
X24500Y1717868D03*
Y1702531D03*
Y1695821D03*
Y1689932D03*
Y1683222D03*
Y1677334D03*
Y1670624D03*
X16500Y1669933D03*
Y1677000D03*
Y1683170D03*
Y1689500D03*
Y1696000D03*
Y1702500D03*
Y1712000D03*
Y1717462D03*
Y1665044D03*
X20000Y1716331D03*
Y1713131D03*
Y1665887D03*
Y1669087D03*
Y1678485D03*
Y1681685D03*
Y1691083D03*
Y1694283D03*
X27529Y1719623D03*
Y1672379D03*
Y1675579D03*
Y1684977D03*
Y1688177D03*
Y1697576D03*
Y1700776D03*
X35900Y1706000D03*
X34224Y1709000D03*
X38000Y1715000D03*
X31981Y1768323D03*
X24500Y1755663D03*
Y1762373D03*
Y1743065D03*
Y1749775D03*
Y1730466D03*
Y1737176D03*
Y1724578D03*
X22219Y1768323D03*
X16500Y1749000D03*
Y1756052D03*
Y1765000D03*
Y1774500D03*
Y1784000D03*
Y1790500D03*
Y1724000D03*
Y1730658D03*
Y1736500D03*
Y1743356D03*
X20000Y1728929D03*
Y1725729D03*
Y1741528D03*
Y1738328D03*
Y1754126D03*
Y1750926D03*
X27529Y1722823D03*
Y1735421D03*
Y1732221D03*
Y1748020D03*
Y1744820D03*
Y1760618D03*
Y1757418D03*
X25500Y1769558D03*
X28700D03*
X39500Y1823300D03*
X39400Y1819900D03*
X38400Y1846750D03*
X38300Y1859050D03*
X5500Y1880685D03*
Y1888685D03*
X38500Y1871350D03*
X38200Y1883800D03*
X19974Y1943969D03*
X33700Y1960300D03*
X20000Y1960000D03*
Y1980000D03*
X32559Y1986626D03*
X12559D03*
X5500Y1973685D03*
Y1953685D03*
X30200Y1970300D03*
X40000Y40000D03*
Y20000D03*
X90018Y5500D03*
X110018D03*
X50018D03*
X70018D03*
X109038Y62310D03*
X109000Y81106D03*
X109160Y105900D03*
X60000Y80000D03*
X40000D03*
Y100000D03*
Y120000D03*
Y60000D03*
X109038Y68476D03*
X109000Y87476D03*
X109160Y100476D03*
X96000Y114212D03*
Y107913D03*
Y98464D03*
Y89015D03*
Y79567D03*
Y70118D03*
Y60868D03*
X96100Y52300D03*
X72500Y91161D03*
Y86161D03*
X71000Y58000D03*
X96000Y119000D03*
X99500Y95940D03*
Y91540D03*
Y77042D03*
Y72642D03*
Y58244D03*
Y53844D03*
X105000Y104788D03*
Y101588D03*
Y85891D03*
Y82691D03*
Y66993D03*
Y63793D03*
X72500Y61161D03*
X67500Y124088D03*
X108917Y150188D03*
X100000Y180000D03*
X99800Y194200D03*
X40000Y160000D03*
Y180000D03*
Y140000D03*
X67500Y135830D03*
X108917Y156976D03*
X72500Y166161D03*
X96000Y158307D03*
X72500Y151161D03*
X96000Y148858D03*
X72500Y136161D03*
X96000Y139409D03*
Y134000D03*
Y123661D03*
X104000Y125000D03*
X71000Y125236D03*
X68000Y128359D03*
Y131559D03*
X99500Y146333D03*
Y141933D03*
X105000Y155182D03*
Y151982D03*
X85250Y247238D03*
X80000Y200000D03*
X77306Y259381D03*
X40000Y240000D03*
Y200000D03*
Y220000D03*
X99300Y201000D03*
X60306Y212338D03*
X80153Y230246D03*
X85427Y239715D03*
X100400Y208300D03*
X70500Y242988D03*
X80300Y234465D03*
X97400Y220200D03*
X97000Y296500D03*
X111500Y276000D03*
X84500Y315000D03*
X67000Y269000D03*
X66512Y287899D03*
X66610Y295956D03*
X56024Y292549D03*
X97400Y366600D03*
X95849Y361564D03*
X46487Y360400D03*
X48822Y393916D03*
X100400Y406000D03*
X104400D03*
X107900D03*
X96900D03*
X110000Y362500D03*
X106500D03*
X110000Y366000D03*
X106500D03*
X92700Y358400D03*
X52066Y370649D03*
X109044Y467822D03*
X51500Y469000D03*
X112600Y442500D03*
X98300Y443400D03*
X109044Y473988D03*
X96000Y485079D03*
Y475630D03*
Y466181D03*
Y456732D03*
X71000Y463500D03*
X112600Y439000D03*
X99500Y482554D03*
Y478154D03*
Y463656D03*
Y459256D03*
X105000Y472505D03*
Y469305D03*
X72500Y466673D03*
X109000Y486618D03*
X109138Y505912D03*
X67500Y529600D03*
X108917Y555700D03*
X67500Y541342D03*
X109000Y492988D03*
X109138Y511488D03*
X72500Y556673D03*
X96000Y554369D03*
X72500Y541673D03*
X96000Y544921D03*
Y539500D03*
Y529173D03*
Y519724D03*
Y513425D03*
Y503976D03*
Y494527D03*
X72500Y496673D03*
Y491673D03*
X104000Y531000D03*
X71000Y530748D03*
X96000Y524000D03*
X68000Y533871D03*
Y537071D03*
X99500Y551845D03*
Y547445D03*
Y501452D03*
Y497052D03*
X105000Y557494D03*
Y510300D03*
Y507100D03*
Y491403D03*
Y488203D03*
X71000Y524464D03*
X99900Y582400D03*
X61100Y600100D03*
X61900Y584300D03*
X72900Y605400D03*
X94700Y599800D03*
X80000Y600000D03*
X108917Y562488D03*
X72500Y571673D03*
X96000Y563819D03*
X89400Y603250D03*
X95900Y605500D03*
X62426Y607740D03*
X105000Y560694D03*
X88600Y623300D03*
X85250Y652750D03*
X61500Y682500D03*
X59000Y659500D03*
X49000Y638000D03*
X76500Y665000D03*
X80153Y635758D03*
X85223Y645227D03*
X70500Y648500D03*
X48000Y649500D03*
X46500Y653500D03*
X80300Y639977D03*
X50560Y653500D03*
X97000Y772100D03*
X87075Y768250D03*
X102500Y737500D03*
X83200Y768300D03*
X76000Y706500D03*
X62000Y736500D03*
X61500Y748000D03*
X51500Y730500D03*
Y757500D03*
X106500Y771500D03*
X110000D03*
Y768000D03*
X106500D03*
X86900Y774750D03*
X49500Y771000D03*
X67500Y822500D03*
X63100Y788800D03*
X73500Y779500D03*
X100600Y811300D03*
X104600D03*
X108100D03*
X97100D03*
X112500Y848700D03*
Y845200D03*
X80215Y777137D03*
X109040Y873334D03*
X109000Y892130D03*
X109187Y911424D03*
X51000Y913500D03*
X63500Y899000D03*
X65500Y867500D03*
X98300Y850400D03*
X109040Y879500D03*
X109000Y898500D03*
X109187Y917000D03*
X96000Y918937D03*
Y909488D03*
Y900039D03*
Y890591D03*
Y881142D03*
Y871692D03*
Y862244D03*
X72500Y902185D03*
Y897185D03*
X71000Y869000D03*
X47500Y901500D03*
X99500Y906964D03*
Y902564D03*
Y888066D03*
Y883666D03*
Y869168D03*
Y864768D03*
X105000Y915812D03*
Y912612D03*
Y896915D03*
Y893715D03*
Y878017D03*
Y874817D03*
X72500Y872185D03*
X67500Y935111D03*
X109000Y961212D03*
X67000Y953500D03*
X96532Y977682D03*
X107400Y994000D03*
X67500Y946855D03*
X109000Y968000D03*
X72500Y977185D03*
X96000Y969331D03*
X72500Y962185D03*
X96000Y959882D03*
X72500Y947185D03*
X96000Y950433D03*
Y945000D03*
Y934685D03*
Y925236D03*
X104000Y936000D03*
X96000Y930000D03*
X71000Y936260D03*
X68000Y939383D03*
Y942583D03*
X99500Y957357D03*
Y952957D03*
X105000Y966206D03*
Y963006D03*
X65500Y927500D03*
X71000Y925500D03*
X99600Y1001400D03*
X102403Y1058209D03*
X103200Y1042500D03*
X83248Y1059636D03*
X93000Y1005700D03*
X81689Y1039600D03*
X77750Y1056750D03*
X96500Y1011200D03*
X64037Y1016654D03*
X74000Y1047500D03*
X41000Y1057500D03*
X81689Y1049400D03*
X106100Y1030000D03*
X71000Y1109000D03*
X42286Y1089500D03*
Y1085500D03*
X67090Y1070360D03*
X41608Y1125065D03*
X39959Y1128308D03*
X96100Y1176700D03*
X87900Y1173300D03*
X111500Y1145000D03*
X75000Y1182500D03*
X41500Y1165500D03*
Y1178000D03*
X67500Y1191500D03*
X110000Y1173500D03*
X106500D03*
X110000Y1177000D03*
X106500D03*
X88500Y1177300D03*
X40097Y1142513D03*
X85300Y1182000D03*
X109040Y1278846D03*
X81500Y1213000D03*
X99100Y1219800D03*
X104500Y1217000D03*
X108000D03*
X95700Y1219700D03*
X112600Y1254300D03*
X98300Y1255900D03*
X109040Y1285012D03*
X96000Y1277205D03*
Y1267756D03*
X71000Y1274500D03*
X112600Y1250800D03*
X99500Y1274680D03*
Y1270280D03*
X105000Y1283529D03*
Y1280329D03*
X72500Y1277697D03*
X109000Y1297642D03*
X109133Y1316936D03*
X67500Y1340624D03*
X64000Y1328500D03*
X58500Y1320500D03*
X67500Y1352366D03*
X109000Y1304012D03*
X109133Y1322512D03*
X72500Y1352697D03*
X96000Y1355945D03*
Y1350500D03*
Y1340197D03*
Y1330748D03*
Y1324449D03*
Y1315000D03*
Y1305551D03*
Y1296103D03*
Y1286654D03*
X72500Y1307697D03*
Y1302697D03*
X104000Y1341000D03*
X71000Y1341772D03*
X96000Y1335000D03*
X68000Y1344895D03*
Y1348095D03*
X99500Y1312476D03*
Y1308076D03*
Y1293578D03*
Y1289178D03*
X105000Y1321324D03*
Y1318124D03*
Y1302427D03*
Y1299227D03*
X71000Y1335488D03*
X58900Y1317000D03*
X109000Y1366724D03*
Y1373512D03*
X70838Y1384165D03*
X96000Y1374843D03*
X72285Y1365633D03*
X96000Y1365393D03*
X96250Y1414400D03*
X62962Y1422600D03*
X100000Y1423000D03*
X99900Y1419600D03*
X99500Y1362869D03*
Y1358469D03*
X105000Y1371718D03*
Y1368518D03*
X48000Y1482000D03*
X82748Y1465560D03*
X80000Y1480000D03*
X109500Y1486000D03*
X110000Y1470000D03*
X99300Y1431200D03*
X82748Y1455148D03*
X76750Y1462762D03*
X80153Y1446781D03*
X73000Y1455100D03*
X69365Y1474719D03*
X80300Y1451000D03*
X88076Y1575924D03*
X90500Y1521500D03*
X96000Y1541100D03*
X72000Y1551500D03*
X72100Y1536400D03*
Y1509900D03*
X48000Y1505500D03*
X91125Y1565900D03*
X105700Y1548200D03*
X82005Y1540500D03*
X85808D03*
X110500Y1573200D03*
X107000D03*
X103500D03*
X80465Y1570120D03*
X109050Y1540600D03*
X46893Y1519979D03*
X47368Y1527323D03*
X42644Y1521957D03*
X46845Y1514264D03*
X43000Y1526000D03*
X42960Y1517408D03*
X64500Y1581500D03*
X100500Y1622500D03*
X104500D03*
X108000D03*
X97000D03*
X40500Y1608500D03*
X107000Y1576700D03*
X103500D03*
X110500D03*
X42919Y1583175D03*
X64525Y1591016D03*
X109040Y1684358D03*
X109000Y1703154D03*
X66500Y1694000D03*
X68000Y1651500D03*
X98600Y1659800D03*
X109040Y1690524D03*
X109000Y1709524D03*
X96000Y1701615D03*
Y1711063D03*
Y1673268D03*
X72500Y1708209D03*
X96000Y1682716D03*
Y1692166D03*
X71000Y1680000D03*
X72500Y1713209D03*
X96000Y1720512D03*
X99500Y1713588D03*
Y1717988D03*
Y1694690D03*
Y1699090D03*
Y1675792D03*
Y1680192D03*
X105000Y1704739D03*
Y1707939D03*
Y1685841D03*
Y1689041D03*
X72500Y1683209D03*
X51635Y1665355D03*
X66400Y1706900D03*
X109137Y1722448D03*
X67500Y1757886D03*
X109030Y1778736D03*
X100000Y1780000D03*
X67500Y1746128D03*
X109137Y1728024D03*
X109030Y1772524D03*
X96000Y1729961D03*
Y1736260D03*
Y1745109D03*
Y1755158D03*
Y1761457D03*
Y1770906D03*
X72500Y1758209D03*
Y1773209D03*
Y1788209D03*
X96000Y1780355D03*
X100000Y1759000D03*
X71000Y1747284D03*
X104000Y1747800D03*
X68000Y1750407D03*
Y1753607D03*
X99500Y1763981D03*
Y1768381D03*
X105000Y1774030D03*
Y1777230D03*
Y1723636D03*
Y1726836D03*
X67000Y1738000D03*
X71015D03*
X93600Y1848200D03*
X45100Y1850800D03*
X42300Y1846750D03*
X42200Y1859050D03*
X45200Y1839300D03*
Y1843300D03*
Y1854700D03*
X40800Y1832300D03*
Y1827300D03*
X76975Y1864000D03*
X100300Y1820800D03*
X77159Y1818277D03*
X91036Y1835282D03*
X72123Y1841183D03*
X100287Y1825915D03*
X100300Y1830000D03*
X80600Y1848900D03*
X98000Y1848800D03*
X85000Y1817100D03*
X74100Y1796200D03*
X67800Y1855200D03*
X93625Y1802200D03*
X52000Y1877500D03*
X100000Y1928000D03*
X80000D03*
X60000D03*
X74300Y1900000D03*
X107543Y1898024D03*
X111000Y1879570D03*
X100100Y1896300D03*
X80000Y1920000D03*
X60000D03*
Y1900000D03*
X44000D03*
X40556Y1917072D03*
X40000Y1940000D03*
X52000Y1887500D03*
X41700Y1883700D03*
X42100Y1871350D03*
X112366Y1883985D03*
X46868Y1887765D03*
X60897Y1885848D03*
X48000Y1877500D03*
X110700Y1974100D03*
X80000Y1980000D03*
X100300Y1980900D03*
X71666Y1961325D03*
X43935Y1957215D03*
X56875Y1954250D03*
X40000Y1980000D03*
X112559Y1986626D03*
X92559D03*
X72559D03*
X52559D03*
X94700Y1974100D03*
X98800D03*
X103300D03*
X107000D03*
X80400Y1957900D03*
X73400D03*
X76900D03*
X87500Y1954300D03*
X80400Y1954400D03*
X83900D03*
X73400D03*
X76900D03*
X57800Y1961800D03*
X170034Y31475D03*
X155018Y5500D03*
X170018D03*
X116600Y46800D03*
X177300Y39000D03*
X180800D03*
X184300D03*
X180800Y35500D03*
X177300D03*
X184300D03*
X152400Y41500D03*
X180000Y80000D03*
X160000D03*
X140000D03*
X154700Y65000D03*
X150200D03*
X141700Y64900D03*
X138200D03*
X131700Y61300D03*
X128200D03*
X121600Y54700D03*
X184461Y103368D03*
X125700Y54400D03*
X179147Y137913D03*
X180000Y180000D03*
X124000Y135859D03*
Y124059D03*
X147125Y160500D03*
X158300Y135200D03*
X150557Y142854D03*
X167298Y147703D03*
X159500Y181000D03*
X124000Y128359D03*
Y131559D03*
X167298Y151203D03*
X114579Y137775D03*
X154875Y160500D03*
X135064Y213390D03*
X134941Y264178D03*
X135500Y200500D03*
X125500Y265500D03*
X132500Y236000D03*
X128500Y248000D03*
X176492Y231103D03*
X180100Y231095D03*
X135064Y219602D03*
X171595Y203917D03*
X148095Y211771D03*
X171595Y218917D03*
X148095Y221220D03*
X171595Y233917D03*
X148095Y230669D03*
Y236968D03*
Y246417D03*
Y255866D03*
Y262165D03*
X140000Y247500D03*
X173095Y244842D03*
X148000Y241500D03*
X180000Y235394D03*
X176800D03*
X144595Y223745D03*
Y228145D03*
X139095Y214896D03*
Y218096D03*
Y265290D03*
X172900Y249400D03*
X143600Y252100D03*
X129000Y255500D03*
X135095Y288972D03*
X134995Y301768D03*
X126000Y293000D03*
X125000Y312000D03*
X145800Y332400D03*
X131300D03*
X134941Y269602D03*
X135095Y282602D03*
X134995Y307602D03*
X148095Y271614D03*
Y281063D03*
Y290511D03*
Y299960D03*
Y309409D03*
Y318858D03*
X171595Y278917D03*
Y283917D03*
X173000Y312500D03*
X131300Y335900D03*
X126445Y338300D03*
X114295D03*
X144595Y274138D03*
Y278538D03*
Y293036D03*
Y297436D03*
Y311934D03*
Y316334D03*
X139095Y268490D03*
Y284187D03*
Y287387D03*
Y303085D03*
Y306285D03*
X171595Y308917D03*
X145900Y408500D03*
X119159Y405100D03*
X124466Y370025D03*
X143500Y370000D03*
X147000D03*
X139500D03*
X136000D03*
X134000Y409500D03*
X137500D03*
X130500D03*
X127000D03*
X117000Y362500D03*
Y366000D03*
X113500Y362500D03*
Y366000D03*
X173800Y379800D03*
X157200Y412000D03*
X158500Y408000D03*
X148700Y413400D03*
X180000Y480000D03*
X163500Y423000D03*
X180000Y460000D03*
X120000D03*
X140000Y480000D03*
Y460000D03*
X160000Y440000D03*
X140000D03*
X120800Y438000D03*
X127000Y413000D03*
X130500D03*
X134000D03*
X137500D03*
X170500Y478500D03*
X125300Y438000D03*
X157500Y551200D03*
X160000Y520000D03*
X180000D03*
X124000Y541373D03*
Y529573D03*
X165138Y536500D03*
X174000Y553500D03*
X157750Y541250D03*
X184500Y553500D03*
X124000Y533873D03*
Y537073D03*
X157750Y544750D03*
X135095Y625402D03*
X158500Y569500D03*
X131500Y610500D03*
X180000Y620000D03*
Y580000D03*
X139500Y600400D03*
X180000Y600000D03*
X135095Y618614D03*
X171595Y609429D03*
X148095Y617283D03*
X171595Y624429D03*
X148095Y626732D03*
X132350Y563750D03*
X159600Y581400D03*
X155500Y574000D03*
X144595Y629257D03*
X139095Y620408D03*
Y623608D03*
X150850Y574350D03*
X134941Y669690D03*
X135095Y694484D03*
X176492Y636617D03*
X180308D03*
X134941Y675114D03*
X135095Y688114D03*
X171895Y639429D03*
X148095Y636181D03*
Y642480D03*
Y651929D03*
Y661378D03*
Y667677D03*
Y677126D03*
Y686575D03*
Y696023D03*
X171595Y684429D03*
Y689429D03*
X140000Y654000D03*
X148000Y648000D03*
X173095Y650354D03*
X180000Y640906D03*
X176800D03*
X144595Y633657D03*
Y679650D03*
Y684050D03*
Y698548D03*
Y702948D03*
X139095Y670802D03*
Y674002D03*
Y689699D03*
Y692899D03*
X173000Y655200D03*
X134993Y707280D03*
X124966Y775525D03*
X125500Y719000D03*
X180000Y720000D03*
X136100Y775600D03*
X139600D03*
X147100D03*
X143600D03*
X145800Y737100D03*
X131400Y738200D03*
X134993Y713114D03*
X148095Y705472D03*
Y714921D03*
Y724370D03*
X173000Y718000D03*
X131400Y741700D03*
X122445Y743800D03*
X117000Y771500D03*
Y768000D03*
X113500Y771500D03*
Y768000D03*
X117945Y743800D03*
X144595Y717446D03*
Y721846D03*
X139095Y708597D03*
Y711797D03*
X171595Y714429D03*
X148600Y818700D03*
X147100Y814200D03*
X119534Y810975D03*
X116000Y814500D03*
X122251Y842400D03*
X127000Y818500D03*
X130500D03*
X134000D03*
X137500D03*
X134000Y815000D03*
X137500D03*
X130500D03*
X127000D03*
X156800Y816000D03*
X126800Y842500D03*
X143800Y807400D03*
X160000Y880000D03*
X140000Y900000D03*
X182000Y949000D03*
X180000Y980000D03*
X167000Y945909D03*
Y935909D03*
X178000Y960000D03*
X162200Y988000D03*
X161095Y980622D03*
X167000Y939309D03*
Y942509D03*
X174500Y960000D03*
X157200Y950800D03*
X155900Y954200D03*
X157000Y957500D03*
X161200Y946100D03*
X161700Y950800D03*
X135095Y1030914D03*
X180000Y1000000D03*
X176492Y1042129D03*
X180308D03*
X135095Y1024126D03*
X171595Y1014941D03*
X148095Y1022795D03*
X171595Y1029941D03*
X148095Y1032244D03*
X171595Y1044941D03*
X148095Y1041693D03*
Y1047992D03*
Y1057441D03*
Y1066890D03*
X140000Y1059500D03*
X129000Y1051500D03*
X173095Y1055866D03*
X148000Y1053500D03*
X180000Y1046418D03*
X176800D03*
X144595Y1034769D03*
Y1039169D03*
X139095Y1025920D03*
Y1029120D03*
X137500Y1014500D03*
X173000Y1060400D03*
X139300Y1067000D03*
X134941Y1075202D03*
X135095Y1099996D03*
X135001Y1112792D03*
X180000Y1140000D03*
X129500Y1084500D03*
X122500Y1107000D03*
X123500Y1123500D03*
X180000Y1120000D03*
Y1100000D03*
Y1080000D03*
X147800Y1140000D03*
X134941Y1080626D03*
X135095Y1093626D03*
X135001Y1118626D03*
X148095Y1073189D03*
Y1082638D03*
Y1092087D03*
Y1101535D03*
Y1110984D03*
Y1120433D03*
Y1129882D03*
X171595Y1089941D03*
Y1094941D03*
X173000Y1123500D03*
X144595Y1085162D03*
Y1089562D03*
Y1104060D03*
Y1108460D03*
Y1122958D03*
Y1127358D03*
X139095Y1076314D03*
Y1079514D03*
Y1095211D03*
Y1098411D03*
Y1114109D03*
Y1117309D03*
X171595Y1119941D03*
X124100Y1181025D03*
X143500Y1180400D03*
X147000D03*
X139500D03*
X136000D03*
X131500Y1143200D03*
Y1146700D03*
X122400Y1149200D03*
X117000Y1173500D03*
Y1177000D03*
X113500Y1173500D03*
Y1177000D03*
X117900Y1149200D03*
X146700Y1219600D03*
X119534Y1216475D03*
X157325Y1223850D03*
X120000Y1280000D03*
X140000D03*
X160000D03*
X180000D03*
X120000Y1220000D03*
X180000D03*
X118250Y1252050D03*
X127000Y1224000D03*
X130500Y1220500D03*
Y1224000D03*
X134000D03*
X137500D03*
X134000Y1220500D03*
X137500D03*
X127000D03*
X158052Y1216052D03*
X129150Y1252050D03*
X179147Y1353048D03*
X160000Y1340000D03*
X180000D03*
X140000D03*
Y1300000D03*
X160000D03*
X180000D03*
X129500Y1352321D03*
Y1340521D03*
X147956Y1347802D03*
X129500Y1344821D03*
Y1348021D03*
X154709Y1344513D03*
X121320Y1425396D03*
X117690Y1397168D03*
X143087Y1403623D03*
X180000Y1400000D03*
Y1420000D03*
X135095Y1429638D03*
X171595Y1420453D03*
X148095Y1428307D03*
X160000Y1360000D03*
X151125Y1376608D03*
X140125Y1381300D03*
X167301Y1363238D03*
Y1366838D03*
X158875Y1376100D03*
X135095Y1436426D03*
X134935Y1480714D03*
X126916Y1447364D03*
X180000Y1440000D03*
Y1500000D03*
X176492Y1447634D03*
X180308D03*
X134935Y1486138D03*
X135095Y1499138D03*
X171595Y1435453D03*
X148095Y1437756D03*
X171895Y1450453D03*
X148095Y1447205D03*
Y1453504D03*
Y1462953D03*
Y1472402D03*
Y1478701D03*
Y1488150D03*
Y1497599D03*
X171595Y1495453D03*
Y1500453D03*
X130000Y1470000D03*
X122000D03*
X114000D03*
X140000Y1464000D03*
X118000Y1470000D03*
X148000Y1458000D03*
X126000Y1466000D03*
X173095Y1461378D03*
X180000Y1451930D03*
X176800D03*
X144595Y1440281D03*
Y1444681D03*
Y1490674D03*
Y1495074D03*
X139095Y1431432D03*
Y1434632D03*
Y1481826D03*
Y1485026D03*
Y1500723D03*
X148095Y1468752D03*
X173100Y1466300D03*
X135095Y1505508D03*
X134995Y1518304D03*
X147700Y1545500D03*
X123400Y1522600D03*
X116500Y1505500D03*
X180000Y1520000D03*
X130600Y1549100D03*
X134995Y1524138D03*
X148095Y1507047D03*
Y1516496D03*
Y1525945D03*
Y1535394D03*
X173000Y1529000D03*
X123500Y1505200D03*
X144200Y1545500D03*
X114000Y1573200D03*
X128250Y1506500D03*
X144595Y1509572D03*
Y1513972D03*
Y1528470D03*
Y1532870D03*
X139095Y1503923D03*
Y1519621D03*
Y1522821D03*
X171595Y1525453D03*
X143500Y1625500D03*
X119534Y1621975D03*
X113841Y1580900D03*
X153700Y1633600D03*
X181500Y1641500D03*
X182500Y1622500D03*
X172000Y1595000D03*
X171500Y1613500D03*
X143300Y1586900D03*
X146800D03*
X138800Y1585100D03*
X135300D03*
X126800Y1630100D03*
X130300D03*
X133800D03*
X126800Y1626600D03*
X130300D03*
X137300Y1630100D03*
Y1626600D03*
X133800D03*
X114000Y1576700D03*
X150200Y1628000D03*
X160200Y1710300D03*
X117300Y1696500D03*
X136600Y1681900D03*
X121700Y1654800D03*
X143000Y1656000D03*
X137000Y1666500D03*
X120000Y1678000D03*
X123000Y1702000D03*
X136700Y1720100D03*
X160000Y1720000D03*
Y1700000D03*
X180000D03*
Y1680000D03*
X113200Y1659800D03*
Y1656300D03*
X117000Y1654600D03*
X126900Y1654700D03*
X144400Y1720400D03*
X159800Y1730000D03*
X148000Y1787000D03*
X125000Y1757834D03*
Y1746034D03*
X177717Y1778162D03*
X180075Y1790692D03*
X125000Y1750334D03*
Y1753534D03*
X136500Y1733000D03*
X137000Y1727500D03*
X140825Y1729825D03*
X157898Y1780145D03*
X140300Y1724100D03*
X147200Y1724400D03*
X135065Y1835438D03*
X128800Y1854000D03*
X145500Y1807500D03*
X136500Y1811500D03*
X140000Y1820000D03*
X160000Y1800000D03*
X180000D03*
Y1840000D03*
X180308Y1853146D03*
X176492D03*
X135065Y1841650D03*
X171595Y1825965D03*
X148095Y1833819D03*
X171595Y1840965D03*
X148095Y1843268D03*
X171595Y1855965D03*
X148095Y1852717D03*
Y1859016D03*
X173095Y1866890D03*
X148000Y1864000D03*
X180000Y1857442D03*
X176800D03*
X144595Y1850193D03*
Y1845793D03*
X139095Y1840144D03*
Y1836944D03*
X151452Y1810000D03*
X134895Y1905020D03*
X128800Y1921300D03*
X129500Y1883500D03*
X115228Y1879770D03*
X128200Y1900300D03*
X180000Y1880000D03*
Y1900000D03*
Y1940000D03*
X134895Y1886150D03*
Y1891650D03*
Y1910650D03*
X134995Y1923650D03*
Y1929650D03*
X148095Y1868465D03*
Y1877914D03*
Y1884213D03*
Y1893662D03*
Y1903111D03*
Y1912559D03*
Y1922008D03*
Y1931457D03*
X171595Y1900965D03*
Y1905965D03*
X173000Y1934500D03*
X140000Y1870000D03*
X144595Y1900586D03*
Y1896186D03*
Y1919484D03*
Y1915084D03*
Y1938382D03*
Y1933982D03*
X139095Y1890538D03*
Y1887338D03*
Y1909435D03*
Y1906235D03*
Y1928333D03*
Y1925133D03*
X171595Y1930965D03*
X113500Y1875970D03*
X173500Y1871700D03*
X133000Y1977100D03*
X114200Y1974100D03*
X118500Y1971400D03*
X139100Y1977100D03*
X172559Y1986626D03*
X152559D03*
X132559D03*
X148095Y1940906D03*
X123200Y1947250D03*
X130500Y1946200D03*
X137300Y1969900D03*
X136800Y1959900D03*
X150800Y1958900D03*
X150600Y1970300D03*
X196665Y35585D03*
X205625Y38750D03*
X240000Y20000D03*
Y40000D03*
X230018Y5500D03*
X250018D03*
X190018D03*
X210018D03*
X187800Y39000D03*
Y35500D03*
X208150Y32250D03*
X220000Y80000D03*
X240000D03*
X200000D03*
X220500Y67500D03*
X240000Y140000D03*
X220000D03*
Y160000D03*
X240000D03*
X200000Y180000D03*
X220000D03*
X240000D03*
X198800Y158000D03*
Y162500D03*
Y167000D03*
X194500Y236902D03*
X200000Y200000D03*
X240000Y220000D03*
X220000D03*
Y200000D03*
X240000D03*
X200000Y260000D03*
X240000D03*
X220000D03*
X194500Y243300D03*
X190500Y238501D03*
Y241701D03*
X200000Y280000D03*
X220000D03*
X240000D03*
Y320000D03*
Y300000D03*
X220000D03*
X200000D03*
Y320000D03*
X220000D03*
X240000Y340000D03*
X220000Y360000D03*
X240000D03*
X220000Y340000D03*
X200000D03*
Y360000D03*
X220000Y480000D03*
X200000D03*
X220000Y460000D03*
X200000D03*
X220000Y420000D03*
X200000Y440000D03*
Y420000D03*
Y520000D03*
X220000D03*
X195500Y531250D03*
Y546250D03*
Y538750D03*
X188854Y527099D03*
Y530902D03*
X206500Y538750D03*
Y546250D03*
Y531250D03*
X220000Y620000D03*
X240000Y600000D03*
Y580000D03*
X200000D03*
X195250Y561300D03*
Y576700D03*
X200250Y572100D03*
X190500Y639713D03*
X200000Y700000D03*
X220000D03*
Y680000D03*
X200000D03*
Y660000D03*
X220000D03*
Y640000D03*
X190500Y651513D03*
Y644013D03*
Y647213D03*
X240000Y760000D03*
X220000Y720000D03*
Y740000D03*
X200000Y760000D03*
Y740000D03*
Y720000D03*
X214700Y784200D03*
X200000Y900000D03*
X240000Y860000D03*
X220000D03*
Y880000D03*
X240000D03*
X190330Y913530D03*
X194200Y985900D03*
X220000Y940000D03*
X240000D03*
X201125Y957200D03*
X195500Y949750D03*
X198900Y969500D03*
X207350Y968627D03*
X198900Y974000D03*
Y978500D03*
X229500Y946600D03*
X198900Y965477D03*
X208875Y957200D03*
X190600Y1045226D03*
X220000Y1040000D03*
Y1020000D03*
X240000D03*
Y1000000D03*
Y1060000D03*
X220000D03*
X240000Y1040000D03*
X190600Y1057024D03*
X190500Y1049525D03*
Y1052725D03*
X200000Y1080000D03*
Y1100000D03*
Y1140000D03*
Y1120000D03*
X220000Y1140000D03*
Y1120000D03*
X240000D03*
Y1100000D03*
X220000D03*
Y1080000D03*
X240000D03*
X255674Y1099470D03*
X196000Y1070300D03*
X208500Y1190000D03*
X200000Y1200000D03*
X240000D03*
Y1180000D03*
X200000Y1160000D03*
Y1280000D03*
X220000D03*
X240000D03*
Y1220000D03*
X220000D03*
X200000Y1340000D03*
X220000D03*
X240000D03*
X200000Y1300000D03*
X220000D03*
X240000D03*
X227000Y1359500D03*
X215000Y1368000D03*
X240000Y1367500D03*
Y1420000D03*
Y1400000D03*
X193400Y1373000D03*
Y1377500D03*
Y1382000D03*
X190400Y1462536D03*
X240000Y1460000D03*
Y1440000D03*
X200000D03*
Y1460000D03*
Y1480000D03*
X240000D03*
Y1500000D03*
X200000D03*
X190400Y1450738D03*
X214500Y1459000D03*
X190500Y1455037D03*
Y1458237D03*
X202000Y1534000D03*
X200000Y1520000D03*
X220000D03*
X240000D03*
X200000Y1560000D03*
X220000D03*
X240000D03*
X203500Y1618500D03*
X229500Y1614500D03*
X189300Y1577200D03*
X220000Y1580000D03*
X248500Y1713005D03*
Y1716808D03*
X242500Y1702500D03*
X251800Y1718400D03*
X220000Y1720000D03*
X200000Y1660000D03*
Y1680000D03*
X220000D03*
Y1660000D03*
X240000Y1680000D03*
Y1660000D03*
X220200Y1740900D03*
X206000Y1735000D03*
X256000Y1745500D03*
X220000Y1734500D03*
X207600Y1777500D03*
X220800Y1763750D03*
X191353Y1772940D03*
X197900Y1781500D03*
X251900Y1769900D03*
X203299Y1763350D03*
X197900Y1786000D03*
Y1790500D03*
X222500Y1776200D03*
X255495Y1738573D03*
X251692D03*
X203299Y1759750D03*
X224875Y1768100D03*
X194620Y1859298D03*
X200000Y1800000D03*
X220000D03*
X240000D03*
X220000Y1840000D03*
X240000D03*
X194620Y1865000D03*
X190500Y1860549D03*
Y1863749D03*
X200000Y1880000D03*
Y1900000D03*
X220000D03*
X240000Y1920000D03*
X220000D03*
X200000D03*
Y1940000D03*
X220000D03*
X240000D03*
X256549Y1898366D03*
X240000Y1880000D03*
X256500D03*
X200000Y1980000D03*
Y1960000D03*
X220000Y1980000D03*
Y1960000D03*
X240000Y1980000D03*
Y1960000D03*
X252559Y1986626D03*
X232559D03*
X212559D03*
X192559D03*
X300000Y40000D03*
Y20000D03*
X320000D03*
Y40000D03*
X260000D03*
Y20000D03*
X280000D03*
Y40000D03*
X310018Y5500D03*
X330018D03*
X270018D03*
X290018D03*
X320000Y80000D03*
X300000Y60000D03*
X320000D03*
Y120000D03*
X300000D03*
X280000D03*
X260000Y100000D03*
X280000D03*
X300000D03*
X320000D03*
X300000Y80000D03*
X280000D03*
X260000D03*
Y160000D03*
X320000D03*
X300000Y140000D03*
X320000D03*
X260000Y180000D03*
X280000D03*
X292600Y166955D03*
X280000Y220000D03*
X260000D03*
Y200000D03*
X280000D03*
X300000D03*
Y220000D03*
X320000D03*
Y240000D03*
Y320000D03*
X300000D03*
X280000D03*
X260000D03*
X320000Y280000D03*
X300000D03*
X260000Y300000D03*
X318656Y391440D03*
X326156D03*
X280000Y360000D03*
X260000D03*
Y340000D03*
X280000D03*
X300000D03*
X320000D03*
X304553Y374081D03*
X313500Y386000D03*
X309000Y365000D03*
X313500Y362000D03*
X320000Y359500D03*
X327500Y373000D03*
X305100Y407700D03*
X293000Y385000D03*
X294500Y408000D03*
X315000Y412000D03*
X321400Y404400D03*
X327500Y377000D03*
X321500Y408500D03*
X312500Y393050D03*
X304400Y416200D03*
X280000Y460000D03*
Y480000D03*
X300000D03*
Y460000D03*
X320000D03*
X300000Y440000D03*
X280000D03*
Y420000D03*
X260000D03*
Y440000D03*
Y480000D03*
Y460000D03*
X321500Y413000D03*
X303200Y422600D03*
X313200Y427500D03*
X317000D03*
X321500Y425200D03*
Y417000D03*
Y421000D03*
X260000Y520000D03*
X320000Y540000D03*
X296470Y555500D03*
X292667D03*
X297300Y505017D03*
X260000Y560000D03*
Y600000D03*
X280000Y620000D03*
X260000D03*
X302500Y583000D03*
X297500D03*
Y588000D03*
X302500D03*
X300000Y585500D03*
X288000Y586484D03*
X313000Y559000D03*
X329600Y583200D03*
X273500Y597000D03*
Y589000D03*
Y585000D03*
Y577000D03*
X284000Y612000D03*
X273500Y573000D03*
Y565000D03*
X296000Y612000D03*
X292000D03*
X316000D03*
X308000D03*
X304000D03*
X290580Y559000D03*
X298450D03*
X320100Y587200D03*
X317500Y559000D03*
X286130Y615700D03*
X270000Y579030D03*
X310030Y615500D03*
X298030Y621000D03*
X269800Y590930D03*
X270000Y567130D03*
X289933Y615700D03*
X270000Y582833D03*
X313833Y615500D03*
X301833Y621000D03*
X269800Y594733D03*
X270000Y570933D03*
X298500Y660200D03*
Y680200D03*
X320000Y700000D03*
X260000D03*
X320000Y640000D03*
X300000D03*
X280000D03*
X260000D03*
X298200Y720000D03*
X260000D03*
X320000D03*
X293500Y738000D03*
X326167Y811099D03*
Y814902D03*
X304400Y846700D03*
X321500Y807000D03*
X297840Y804552D03*
X280000Y820000D03*
X325053Y782652D03*
X309000Y795000D03*
X321500Y843000D03*
X323000Y819500D03*
X313500Y792000D03*
X320000Y789500D03*
X327500Y803000D03*
X304500Y836700D03*
X301300Y822550D03*
X292000Y837000D03*
X321500Y847000D03*
X315000Y842000D03*
X321500Y838500D03*
X321400Y834400D03*
X327500Y807000D03*
X312000Y824500D03*
X260000Y860000D03*
Y880000D03*
X300000D03*
X280000D03*
Y860000D03*
X295200Y903000D03*
X305200D03*
Y913000D03*
X295200D03*
X303500Y853100D03*
X321500Y855200D03*
Y851000D03*
X317000Y857900D03*
X313200D03*
X260000Y940000D03*
X280000D03*
X300000D03*
X260000Y980000D03*
X280000D03*
X300000D03*
X292500Y965500D03*
X320000Y1060000D03*
X300000D03*
X260000D03*
Y1040000D03*
X280000D03*
X300000D03*
X320000D03*
Y1020000D03*
X280000D03*
X300000D03*
X260000D03*
X280000Y1000000D03*
X300000D03*
X320000D03*
Y1140000D03*
X260000Y1120000D03*
X280000D03*
X300000D03*
X320000Y1100000D03*
X300000D03*
Y1080000D03*
X320000D03*
X294000Y1111500D03*
X260000Y1200000D03*
X280000D03*
Y1180000D03*
X260000Y1160000D03*
X296011Y1185470D03*
X309000Y1166500D03*
X295400Y1172655D03*
X313500Y1187500D03*
X320000Y1161000D03*
X327500Y1174500D03*
X305200Y1208300D03*
X321400Y1205900D03*
X321500Y1210000D03*
X327500Y1178500D03*
X312500Y1194000D03*
X304500Y1217500D03*
X320000Y1280000D03*
X300000Y1240000D03*
X320000Y1260000D03*
X300000Y1280000D03*
Y1260000D03*
X280000Y1280000D03*
X260000D03*
Y1260000D03*
X280000D03*
Y1220000D03*
X260000D03*
X321500Y1214500D03*
X295000Y1245000D03*
X294500Y1254000D03*
X302500Y1224000D03*
X321600Y1226600D03*
X313200Y1228800D03*
X317000D03*
X314437Y1213382D03*
X321500Y1222500D03*
Y1218500D03*
X280000Y1340000D03*
X260000D03*
X300000Y1300000D03*
X280000D03*
X260000D03*
X287167Y1380000D03*
X290970D03*
X311500Y1389000D03*
X280000Y1380000D03*
X260000Y1400000D03*
Y1420000D03*
X300000Y1421500D03*
X302500Y1424000D03*
X297500D03*
Y1419000D03*
X302500D03*
X303500Y1389000D03*
X297600Y1392000D03*
X273500Y1407500D03*
X319500Y1389000D03*
X301400Y1401500D03*
X315500Y1389000D03*
X293100Y1383500D03*
X284900D03*
X273500Y1419500D03*
Y1411500D03*
Y1423500D03*
X326500Y1417500D03*
Y1425700D03*
Y1405400D03*
Y1413500D03*
Y1429700D03*
X328000Y1381500D03*
Y1374000D03*
X327500Y1368500D03*
X273500Y1403500D03*
X307500Y1389000D03*
X330000Y1423470D03*
X270100Y1425697D03*
X330300Y1411100D03*
X270000Y1413530D03*
X330000Y1419667D03*
X270100Y1429500D03*
X330300Y1407297D03*
X270000Y1417333D03*
X260000Y1440000D03*
X300984Y1433500D03*
X273500Y1431500D03*
X287600Y1448000D03*
X279650D03*
X299600D03*
X291600D03*
X326500Y1437700D03*
X311600Y1448000D03*
X303600D03*
X330000Y1435170D03*
X293830Y1451500D03*
X305830Y1451300D03*
X282030Y1451400D03*
X330000Y1431367D03*
X297633Y1451500D03*
X309633Y1451300D03*
X285833Y1451400D03*
X260000Y1520000D03*
X280000D03*
X300000D03*
X320000Y1540000D03*
Y1560000D03*
X300000D03*
X280000D03*
X260000D03*
X258585Y1508386D03*
X260000Y1620000D03*
Y1600000D03*
X300000Y1620000D03*
X280000Y1600000D03*
Y1620000D03*
X300000Y1600000D03*
X320000D03*
X318156Y1692440D03*
X325656D03*
X289300Y1696200D03*
Y1701800D03*
X292200Y1688900D03*
X295800D03*
X306200Y1689400D03*
X259000Y1702500D03*
X260000Y1680000D03*
Y1660000D03*
X321500Y1713000D03*
X327500Y1673000D03*
X305300Y1715700D03*
X306200Y1709600D03*
X301800Y1722100D03*
X265500Y1722000D03*
X283500D03*
X285000Y1700600D03*
X295600Y1693400D03*
X285000Y1697400D03*
X292400Y1693400D03*
X315000Y1712000D03*
X321500Y1721000D03*
X327500Y1677000D03*
X321500Y1717000D03*
Y1708500D03*
X321400Y1704400D03*
X313500Y1692500D03*
X320000Y1760000D03*
Y1780000D03*
X260000Y1740000D03*
X288000Y1742500D03*
X293000D03*
X284000Y1731250D03*
X268800Y1774600D03*
X276402Y1726146D03*
X272599D03*
X297000Y1777000D03*
Y1752000D03*
X302000D03*
X321500Y1725200D03*
X317000Y1727300D03*
X313200D03*
X260000Y1800000D03*
Y1840000D03*
X280000D03*
X320000Y1860000D03*
X300000D03*
Y1840000D03*
X320000Y1820000D03*
Y1840000D03*
X271500Y1795000D03*
X279500D03*
X287500D03*
X300000Y1800000D03*
X320000Y1940000D03*
X300000D03*
X280000D03*
X260000D03*
X280071Y1924667D03*
X300000Y1900000D03*
Y1920000D03*
X320000D03*
Y1900000D03*
X300000Y1880000D03*
X320000D03*
X260000Y1980000D03*
Y1960000D03*
X280000Y1980000D03*
Y1960000D03*
X300000Y1980000D03*
Y1960000D03*
X320000Y1980000D03*
Y1960000D03*
X312559Y1986626D03*
X292559D03*
X272559D03*
X380000Y20000D03*
Y40000D03*
X400000D03*
Y20000D03*
X340000Y40000D03*
Y20000D03*
X360000Y40000D03*
Y20000D03*
X390018Y5500D03*
X350018D03*
X370018D03*
X400000Y100000D03*
Y80000D03*
X377500Y98000D03*
X400000Y60000D03*
X340000Y80000D03*
Y100000D03*
Y60000D03*
X400000Y120000D03*
X340000D03*
X373500Y98000D03*
X363750Y65250D03*
X352500Y68500D03*
X358500Y93500D03*
X374300Y81400D03*
X363750Y73300D03*
X378100Y81500D03*
X363750Y54250D03*
X382200Y81500D03*
X382000Y98000D03*
X358000Y64000D03*
X344500Y71750D03*
X340000Y180000D03*
X360000D03*
X380000D03*
X400000D03*
Y140000D03*
Y160000D03*
X380000Y140000D03*
Y160000D03*
X360000Y140000D03*
Y160000D03*
X340000D03*
Y140000D03*
X357250Y124000D03*
X360750D03*
X400000Y220000D03*
Y200000D03*
X380000D03*
X340000Y240000D03*
Y260000D03*
X360000D03*
Y280000D03*
X369000Y294000D03*
X370000Y411000D03*
Y405500D03*
X375500D03*
X381000D03*
X375500Y411000D03*
X381000D03*
X359000D03*
X364500D03*
Y405500D03*
X359000D03*
X370000Y400000D03*
X381000D03*
X375500D03*
X370000Y389000D03*
Y394500D03*
X375500D03*
Y389000D03*
X381000D03*
Y394500D03*
X364500Y400000D03*
X365000Y394500D03*
Y389000D03*
X359000D03*
Y394500D03*
Y400000D03*
X370128Y361337D03*
X349706Y355693D03*
X356250Y349000D03*
X337500Y406250D03*
X331500Y393000D03*
X368500Y364500D03*
X372000D03*
X401500Y401500D03*
X397000Y383750D03*
X383750Y349000D03*
X391800Y355800D03*
X401500Y410250D03*
X356257Y344176D03*
X391750Y344500D03*
X383750D03*
X348256Y344114D03*
X331500Y389000D03*
X365100Y371200D03*
X397000Y380250D03*
X375200Y371250D03*
X349870Y348870D03*
X331300Y408500D03*
X400000Y440000D03*
Y460000D03*
Y480000D03*
X339500Y416750D03*
X370397Y439122D03*
X368500Y436000D03*
X372000D03*
X397000Y414750D03*
X379250Y451000D03*
X385896Y444265D03*
X343750Y451000D03*
X350241Y444377D03*
X351729Y455810D03*
X379258Y455892D03*
X387249Y455882D03*
X343729Y455810D03*
X364758Y429249D03*
X375200Y429250D03*
X350137Y451250D03*
X385607Y451232D03*
X400000Y540000D03*
X340000D03*
X380000Y500000D03*
Y540000D03*
X400000Y520000D03*
X339500Y572667D03*
Y576470D03*
X400000Y560000D03*
X332500Y597000D03*
Y589000D03*
X360000Y580000D03*
X340000Y560000D03*
Y600000D03*
Y620000D03*
X380000D03*
X400000D03*
X380000Y560000D03*
X332500Y605000D03*
X336000Y570580D03*
Y578600D03*
X332500Y593000D03*
Y601000D03*
X380000Y660000D03*
X400000Y640000D03*
Y680000D03*
Y700000D03*
X340000Y660000D03*
Y680000D03*
Y700000D03*
X360000D03*
Y680000D03*
Y660000D03*
Y640000D03*
X380000D03*
X400000Y740000D03*
Y720000D03*
X340000Y740000D03*
Y720000D03*
X360000D03*
X377250Y774500D03*
X385238Y774122D03*
X400000Y780000D03*
X340000D03*
X370000Y841000D03*
Y835500D03*
X375500D03*
X381000D03*
X375500Y841000D03*
X381000D03*
X359000D03*
X364500D03*
Y835500D03*
X359000D03*
X370000Y830000D03*
X381000D03*
X375500D03*
X370000Y819000D03*
Y824500D03*
X375500D03*
Y819000D03*
X381000D03*
Y824500D03*
X364500Y830000D03*
X365000Y824500D03*
Y819000D03*
X359000D03*
Y824500D03*
Y830000D03*
X362000Y797000D03*
X365500D03*
X358000Y794000D03*
X397000Y844750D03*
X339500Y846750D03*
X337500Y836250D03*
X331500Y823000D03*
X401500Y836000D03*
X377250Y779000D03*
X385250Y785700D03*
X395000Y806500D03*
X331500Y819000D03*
X358800Y803600D03*
X368700Y803750D03*
X388250Y803300D03*
X385196Y779112D03*
X331300Y838500D03*
X402000Y844000D03*
X360100Y808080D03*
X371059Y903347D03*
X355622Y919857D03*
X380000Y920000D03*
X400000D03*
Y900000D03*
X368500Y865000D03*
X372000D03*
X379228Y874277D03*
X387250Y881000D03*
X351740Y880717D03*
X343749Y874298D03*
X351792Y885835D03*
X379270Y885897D03*
X387292D03*
X343770D03*
X360800Y858500D03*
X375200Y858250D03*
X343894Y880707D03*
X379372Y880728D03*
X335823Y940330D03*
X340000Y980000D03*
X360000D03*
X380000D03*
X400000D03*
Y960000D03*
X380000D03*
X340000D03*
X360000D03*
Y940000D03*
X380000D03*
X400000D03*
Y1060000D03*
X380000D03*
X400000Y1040000D03*
X380000D03*
X360000Y1060000D03*
X340000D03*
X360000Y1040000D03*
X340000D03*
Y1000000D03*
Y1020000D03*
X360000Y1000000D03*
Y1020000D03*
X380000Y1000000D03*
Y1020000D03*
X400000Y1000000D03*
Y1020000D03*
X360000Y1140000D03*
X340000D03*
X380000Y1100000D03*
X400000Y1080000D03*
X380000D03*
X360000Y1100000D03*
X340000D03*
X360000Y1080000D03*
X340000D03*
Y1160000D03*
X354228Y1164233D03*
X370000Y1212500D03*
Y1207000D03*
X375500D03*
X381000D03*
X375500Y1212500D03*
X381000D03*
X359000D03*
X364500D03*
Y1207000D03*
X359000D03*
X370000Y1201500D03*
X381000D03*
X375500D03*
X370000Y1190500D03*
Y1196000D03*
X375500D03*
Y1190500D03*
X381000D03*
Y1196000D03*
X364500Y1201500D03*
X365000Y1196000D03*
Y1190500D03*
X359000D03*
Y1196000D03*
Y1201500D03*
X337500Y1207750D03*
X331500Y1194500D03*
X371000Y1168000D03*
X367500D03*
X363500Y1165000D03*
X402000Y1202500D03*
X383750Y1150500D03*
X391765Y1157852D03*
X396750Y1181250D03*
X391758Y1145676D03*
X383757Y1145655D03*
X331500Y1190500D03*
X364300Y1174900D03*
X374200Y1174750D03*
X391900Y1150250D03*
X331300Y1210000D03*
X398750Y1188250D03*
X359175Y1179640D03*
X400000Y1280000D03*
Y1260000D03*
X339500Y1218250D03*
X370200Y1239700D03*
X368500Y1236500D03*
X372000D03*
X343749Y1245719D03*
X351771Y1252213D03*
X379249Y1245782D03*
X387208Y1252212D03*
X391500Y1218500D03*
X351750Y1257380D03*
X379270D03*
X387292Y1257360D03*
X343760Y1257381D03*
X365200Y1229800D03*
X400700Y1237500D03*
X375200Y1229750D03*
X343822Y1252222D03*
X379395Y1252274D03*
X400000Y1340000D03*
X380000D03*
Y1320000D03*
X400000D03*
X380000Y1300000D03*
X400000D03*
X360000Y1340000D03*
Y1320000D03*
X340000Y1340000D03*
X380000Y1420000D03*
Y1400000D03*
X400000Y1420000D03*
Y1400000D03*
Y1380000D03*
Y1360000D03*
X380000D03*
Y1380000D03*
X360000D03*
Y1360000D03*
X340000D03*
Y1380000D03*
X380000Y1500000D03*
X360000D03*
X340000Y1480000D03*
Y1460000D03*
X400000D03*
X380000Y1440000D03*
X400000D03*
X360000Y1560000D03*
X400000Y1540000D03*
X380000D03*
X360000D03*
Y1520000D03*
X380000D03*
X400000D03*
Y1580000D03*
X380000D03*
X348250Y1649000D03*
X356247Y1644123D03*
X348257Y1644132D03*
X356174Y1649291D03*
X334500Y1650000D03*
Y1665000D03*
X380000Y1660000D03*
X400000D03*
X359000Y1705500D03*
Y1700000D03*
Y1694500D03*
Y1689000D03*
X365000D03*
Y1694500D03*
X364500Y1700000D03*
Y1705500D03*
Y1711000D03*
X359000D03*
X381000D03*
X375500D03*
X381000Y1705500D03*
X375500D03*
X381000Y1694500D03*
Y1689000D03*
X375500D03*
Y1694500D03*
X370000D03*
Y1689000D03*
Y1705500D03*
Y1711000D03*
X381000Y1700000D03*
X375500D03*
X370000D03*
X402000Y1701000D03*
X339500Y1716750D03*
X337500Y1706250D03*
X331500Y1695000D03*
X368500Y1664000D03*
X372500Y1667000D03*
X376000D03*
X388750Y1673000D03*
X356238Y1655722D03*
X331500Y1691000D03*
X369100Y1673700D03*
X385250Y1673000D03*
X331500Y1708500D03*
X395500Y1690500D03*
X376890Y1678000D03*
X368500Y1768000D03*
X400000Y1760000D03*
X365400Y1734400D03*
X369000Y1734500D03*
X372500D03*
X393000Y1723500D03*
X351750Y1751000D03*
X343709Y1744187D03*
X376808Y1755434D03*
X373005D03*
X379000Y1736000D03*
X351750Y1755500D03*
X343750D03*
X383000Y1736300D03*
X365700Y1727700D03*
X383000Y1728700D03*
X375700Y1727750D03*
X343668Y1750741D03*
X379000Y1726000D03*
X400000Y1860000D03*
X380000D03*
X360000D03*
X340000D03*
Y1800000D03*
Y1840000D03*
X360000D03*
X380000D03*
X400000D03*
Y1820000D03*
X380000D03*
X360000D03*
X340000D03*
X360000Y1800000D03*
X400000D03*
X380000D03*
X400000Y1940000D03*
X380000D03*
X360000D03*
X340000D03*
Y1900000D03*
Y1920000D03*
X360000D03*
Y1900000D03*
X380000D03*
Y1920000D03*
X400000D03*
Y1900000D03*
X340000Y1880000D03*
X360000D03*
X380000D03*
X400000D03*
X340000Y1980000D03*
Y1960000D03*
X360000Y1980000D03*
Y1960000D03*
X380000Y1980000D03*
Y1960000D03*
X400000Y1980000D03*
Y1960000D03*
X392559Y1986626D03*
X372559D03*
X352559D03*
X332559D03*
X460000Y20000D03*
Y40000D03*
X420000Y20000D03*
Y40000D03*
X440000D03*
Y20000D03*
X470018Y5500D03*
X410018D03*
X430018D03*
X450018D03*
X460000Y100000D03*
X420000D03*
X440000D03*
X460000Y80000D03*
Y60000D03*
X440000D03*
Y80000D03*
X420000D03*
Y60000D03*
X460000Y120000D03*
X440000D03*
X420000D03*
Y180000D03*
X440000D03*
X460000D03*
Y140000D03*
Y160000D03*
X440000D03*
Y140000D03*
X420000D03*
Y160000D03*
Y200000D03*
X460000D03*
X440000D03*
X420000Y220000D03*
X440000D03*
X460000D03*
Y240000D03*
X440000D03*
X420000D03*
Y260000D03*
X440000D03*
X460000D03*
X440000Y280000D03*
X460000D03*
X440000Y320000D03*
X460000D03*
Y300000D03*
X405500Y277500D03*
X405000Y289000D03*
X440000Y400000D03*
X460000D03*
Y380000D03*
X440000D03*
Y360000D03*
X460000D03*
Y340000D03*
X440000D03*
X460000Y480000D03*
Y460000D03*
X440000Y480000D03*
Y460000D03*
Y440000D03*
X460000D03*
Y420000D03*
X440000D03*
X410550Y420500D03*
X420000Y520000D03*
Y540000D03*
X440000D03*
Y520000D03*
X460000D03*
Y500000D03*
X420000D03*
Y620000D03*
X440000Y600000D03*
X460000Y580000D03*
X420000Y600000D03*
X440000Y580000D03*
X420000Y560000D03*
Y700000D03*
X460000Y660000D03*
Y680000D03*
Y700000D03*
X420000Y680000D03*
Y660000D03*
Y720000D03*
Y740000D03*
X460000Y720000D03*
Y760000D03*
X420000D03*
Y840000D03*
X440000D03*
X460000D03*
Y820000D03*
Y800000D03*
Y780000D03*
X420000D03*
X414281Y820751D03*
X421000Y812750D03*
X425890Y820729D03*
X425891Y812750D03*
X404000Y840500D03*
X420722Y820627D03*
X420000Y920000D03*
X440000D03*
X460000D03*
Y900000D03*
X440000D03*
X420000D03*
Y880000D03*
X460000D03*
X440000D03*
X420000Y860000D03*
X440000D03*
X460000D03*
X410550Y850500D03*
X420000Y980000D03*
X440000D03*
X460000D03*
Y960000D03*
X440000D03*
X420000D03*
Y940000D03*
X440000D03*
X460000D03*
X420000Y1060000D03*
X440000Y1040000D03*
X420000D03*
Y1000000D03*
Y1020000D03*
X440000Y1000000D03*
Y1020000D03*
X460000D03*
Y1000000D03*
X440000Y1120000D03*
X460000D03*
Y1080000D03*
X420000Y1200000D03*
X440000D03*
X460000D03*
Y1160000D03*
Y1180000D03*
X440000Y1160000D03*
Y1180000D03*
X420000Y1160000D03*
Y1180000D03*
X405500Y1192000D03*
X420000Y1280000D03*
Y1240000D03*
X440000D03*
X460000D03*
Y1260000D03*
X440000D03*
X420000D03*
X460000Y1280000D03*
X440000D03*
X420743Y1215266D03*
X414274Y1223246D03*
X408300Y1237500D03*
X425500Y1215250D03*
Y1223250D03*
X420763Y1223185D03*
X420000Y1340000D03*
Y1320000D03*
X440000D03*
Y1340000D03*
X460000D03*
Y1320000D03*
X440000Y1300000D03*
X420000D03*
X460000D03*
X440000Y1420000D03*
X420000D03*
Y1400000D03*
Y1380000D03*
Y1360000D03*
X440000Y1400000D03*
Y1360000D03*
Y1380000D03*
X460000D03*
Y1360000D03*
Y1420000D03*
Y1400000D03*
X440000Y1500000D03*
X420000Y1480000D03*
X440000D03*
Y1460000D03*
X420000D03*
Y1440000D03*
X440000D03*
X460000Y1500000D03*
Y1480000D03*
Y1460000D03*
Y1440000D03*
X420000Y1540000D03*
X460000Y1520000D03*
Y1580000D03*
X440000D03*
X420000D03*
Y1700000D03*
Y1680000D03*
Y1660000D03*
X440000Y1680000D03*
X460000D03*
Y1660000D03*
X421000Y1713750D03*
X414299Y1721750D03*
X425879Y1721724D03*
X425500Y1713750D03*
X420732Y1721757D03*
X420000Y1760000D03*
X406500Y1736500D03*
X440000Y1780000D03*
Y1760000D03*
X460000D03*
Y1780000D03*
X450000Y1803500D03*
X440000Y1860000D03*
X420000D03*
Y1840000D03*
X440000D03*
X420000Y1820000D03*
X460000Y1840000D03*
Y1860000D03*
Y1940000D03*
X440000D03*
X420000D03*
Y1900000D03*
Y1920000D03*
X440000D03*
Y1900000D03*
X460000Y1920000D03*
Y1900000D03*
X420000Y1880000D03*
X440000D03*
X460000D03*
X420000Y1980000D03*
Y1960000D03*
X440000Y1980000D03*
Y1960000D03*
X460000Y1980000D03*
Y1960000D03*
X472559Y1986626D03*
X452559D03*
X432559D03*
X412559D03*
X500000Y40000D03*
X480000D03*
X520000D03*
X530018Y5500D03*
X510018D03*
X490018D03*
X500000Y20000D03*
X480000D03*
X520000D03*
X540000Y40000D03*
Y20000D03*
Y100000D03*
X520000D03*
X500000D03*
X480000D03*
Y120000D03*
X500000D03*
X520000D03*
X480000Y60000D03*
Y80000D03*
X500000D03*
Y60000D03*
X520000D03*
Y80000D03*
X540000Y120000D03*
Y80000D03*
Y60000D03*
X480000Y140000D03*
Y160000D03*
X500000D03*
Y140000D03*
X520000D03*
Y160000D03*
Y180000D03*
X500000D03*
X480000D03*
X540000Y160000D03*
Y140000D03*
Y180000D03*
X520000Y260000D03*
X500000D03*
X520000Y240000D03*
X480000D03*
X500000D03*
Y220000D03*
X480000D03*
Y200000D03*
X500000D03*
X520000D03*
Y220000D03*
X540000Y260000D03*
Y220000D03*
Y240000D03*
Y200000D03*
X500000Y280000D03*
X520000D03*
X480000D03*
Y300000D03*
X500000D03*
X520000D03*
Y320000D03*
X500000D03*
X480000D03*
X540000Y280000D03*
Y300000D03*
Y320000D03*
X500000Y400000D03*
X520000D03*
Y380000D03*
X540000Y400000D03*
Y380000D03*
Y360000D03*
Y340000D03*
X480000Y400000D03*
Y340000D03*
X500000D03*
X520000D03*
Y360000D03*
X500000D03*
X480000D03*
Y380000D03*
Y440000D03*
X500000D03*
X480000Y420000D03*
X500000D03*
X520000D03*
X540000D03*
X520000Y480000D03*
X500000D03*
X480000D03*
Y460000D03*
X500000D03*
X520000D03*
Y440000D03*
X540000Y460000D03*
Y440000D03*
X500000Y500000D03*
X480000D03*
X520000Y520000D03*
X500000Y540000D03*
X540000D03*
X520000Y560000D03*
X540000D03*
Y580000D03*
X500000D03*
Y600000D03*
X520000D03*
X540000D03*
X520000Y580000D03*
X480000Y560000D03*
X540000Y700000D03*
X520000D03*
X500000D03*
X480000D03*
X540000Y680000D03*
X520000D03*
X500000D03*
X480000D03*
X540000Y660000D03*
X520000D03*
X500000D03*
X480000D03*
Y640000D03*
X500000D03*
X520000D03*
X540000D03*
X520000Y720000D03*
X500000D03*
X480000D03*
X540000Y740000D03*
X480000Y760000D03*
X500000D03*
X520000D03*
X540000D03*
X520000Y780000D03*
X500000D03*
X480000D03*
Y800000D03*
X500000D03*
X520000D03*
X480000Y820000D03*
X500000D03*
X520000D03*
X480000Y840000D03*
X500000D03*
X520000D03*
X540000D03*
Y780000D03*
Y800000D03*
Y820000D03*
X520000Y900000D03*
Y920000D03*
X500000D03*
X480000D03*
X520000Y860000D03*
X500000D03*
X480000D03*
Y880000D03*
X500000D03*
X520000D03*
X480000Y900000D03*
X500000D03*
X540000Y920000D03*
Y860000D03*
Y880000D03*
Y900000D03*
X520000Y980000D03*
X500000D03*
X480000D03*
X520000Y940000D03*
X500000D03*
X480000D03*
Y960000D03*
X500000D03*
X520000D03*
X540000Y980000D03*
Y940000D03*
Y960000D03*
X520000Y1060000D03*
X500000D03*
X480000D03*
Y1000000D03*
X500000Y1040000D03*
X520000D03*
X540000Y1060000D03*
Y1040000D03*
X480000Y1080000D03*
X500000D03*
X520000D03*
Y1120000D03*
X500000D03*
X480000D03*
X540000D03*
Y1100000D03*
X520000Y1200000D03*
X500000D03*
X480000D03*
Y1180000D03*
Y1160000D03*
X500000Y1180000D03*
Y1160000D03*
X520000Y1180000D03*
Y1160000D03*
X540000Y1180000D03*
Y1160000D03*
Y1200000D03*
X480000Y1280000D03*
X500000D03*
X520000D03*
X480000Y1260000D03*
X500000D03*
X520000D03*
X500000Y1240000D03*
X480000D03*
X540000Y1280000D03*
Y1220000D03*
X500000Y1340000D03*
X520000D03*
X480000D03*
Y1320000D03*
X500000D03*
X520000D03*
X480000Y1300000D03*
X500000D03*
X520000D03*
X540000Y1340000D03*
Y1320000D03*
Y1300000D03*
X520000Y1420000D03*
X500000D03*
X480000D03*
X520000Y1380000D03*
Y1400000D03*
X500000Y1380000D03*
Y1400000D03*
X480000Y1380000D03*
Y1400000D03*
X500000Y1360000D03*
X520000D03*
X480000D03*
X540000Y1420000D03*
Y1380000D03*
Y1400000D03*
Y1360000D03*
X520000Y1500000D03*
X500000D03*
X480000D03*
X520000Y1440000D03*
Y1460000D03*
Y1480000D03*
X500000Y1440000D03*
Y1460000D03*
Y1480000D03*
X480000Y1440000D03*
Y1460000D03*
Y1480000D03*
X540000Y1500000D03*
Y1440000D03*
Y1460000D03*
Y1480000D03*
X500000Y1560000D03*
X480000Y1520000D03*
X500000D03*
X520000D03*
X540000D03*
X547659Y1560537D03*
X542159D03*
Y1566037D03*
X547659D03*
X480000Y1580000D03*
X540000Y1680000D03*
X520000D03*
X500000D03*
X480000D03*
Y1700000D03*
Y1660000D03*
Y1720000D03*
X500000D03*
X520000D03*
Y1700000D03*
X500000D03*
X520000Y1660000D03*
X500000D03*
X540000Y1700000D03*
Y1720000D03*
Y1660000D03*
Y1780000D03*
X520000Y1760000D03*
X480000Y1780000D03*
X500000D03*
X520000D03*
X480000Y1760000D03*
X500000D03*
X520000Y1740000D03*
X500000D03*
X480000D03*
X540000Y1760000D03*
Y1740000D03*
Y1820000D03*
Y1840000D03*
Y1860000D03*
X520000D03*
X480000D03*
X500000Y1840000D03*
X520000D03*
X500000Y1820000D03*
X480000D03*
X520000D03*
X540000Y1940000D03*
X500000D03*
X520000D03*
X480000D03*
X520000Y1920000D03*
X500000D03*
X480000D03*
X520000Y1900000D03*
X500000D03*
X480000D03*
Y1880000D03*
X500000D03*
X520000D03*
X540000Y1900000D03*
Y1880000D03*
Y1920000D03*
X492559Y1986626D03*
X512559D03*
X532559D03*
X520000Y1960000D03*
Y1980000D03*
X500000Y1960000D03*
Y1980000D03*
X480000Y1960000D03*
Y1980000D03*
X540000Y1960000D03*
Y1980000D03*
X580000Y40000D03*
X560000D03*
X600000D03*
X590018Y5500D03*
X570018D03*
X550018D03*
X580000Y20000D03*
X560000D03*
X600000D03*
X620000Y40000D03*
X610018Y5500D03*
X620000Y20000D03*
Y100000D03*
X600000D03*
X580000D03*
X560000D03*
Y120000D03*
X580000D03*
X600000D03*
X560000Y60000D03*
Y80000D03*
X580000D03*
Y60000D03*
X600000D03*
Y80000D03*
X620000Y120000D03*
Y80000D03*
Y60000D03*
X560000Y140000D03*
Y160000D03*
X580000D03*
Y140000D03*
X600000D03*
Y160000D03*
Y180000D03*
X580000D03*
X560000D03*
X620000Y160000D03*
Y140000D03*
Y180000D03*
X580000Y260000D03*
X600000D03*
X620000D03*
X560000D03*
X600000Y200000D03*
Y220000D03*
X580000D03*
Y200000D03*
X560000D03*
Y220000D03*
Y240000D03*
X580000D03*
X600000D03*
X620000D03*
Y220000D03*
Y200000D03*
X560000Y320000D03*
X580000D03*
X600000D03*
X620000D03*
X560000Y300000D03*
X580000D03*
X600000D03*
X620000D03*
X580000Y280000D03*
X600000D03*
X620000D03*
X560000D03*
X620000Y400000D03*
X600000D03*
X580000D03*
X560000D03*
Y380000D03*
X580000D03*
X600000D03*
X620000D03*
X560000Y360000D03*
X580000D03*
X600000D03*
X620000D03*
X560000Y340000D03*
X580000D03*
X600000D03*
X620000D03*
X600000Y480000D03*
X620000D03*
Y460000D03*
X580000Y440000D03*
X560000D03*
X620000Y420000D03*
X600000D03*
X580000D03*
X560000D03*
Y460000D03*
X620000Y520000D03*
X600000D03*
X580000D03*
Y500000D03*
X600000Y540000D03*
Y500000D03*
X620000D03*
X580000Y540000D03*
X560000D03*
X620000D03*
Y560000D03*
X580000D03*
X600000D03*
X560000D03*
Y580000D03*
X600000D03*
X620000Y600000D03*
X600000D03*
X580000D03*
Y580000D03*
X620000D03*
Y640000D03*
X600000D03*
X580000D03*
X560000D03*
X620000Y700000D03*
X600000D03*
X580000D03*
X560000D03*
X620000Y680000D03*
X600000D03*
X580000D03*
X560000D03*
X620000Y660000D03*
X600000D03*
X580000D03*
X560000D03*
Y740000D03*
X580000D03*
X600000D03*
X620000D03*
X580000Y760000D03*
X600000D03*
X620000D03*
X560000D03*
X580000Y780000D03*
X600000D03*
X620000D03*
X580000Y800000D03*
X600000D03*
X620000D03*
X580000Y820000D03*
X600000D03*
X620000D03*
X560000Y840000D03*
X580000D03*
X600000D03*
X560000Y780000D03*
Y800000D03*
X620000Y840000D03*
X600000Y920000D03*
X580000D03*
X560000D03*
X600000Y860000D03*
X580000D03*
X560000D03*
Y900000D03*
Y880000D03*
X580000D03*
Y900000D03*
X600000D03*
Y880000D03*
X620000Y920000D03*
Y880000D03*
Y900000D03*
Y860000D03*
X600000Y980000D03*
X580000D03*
X560000D03*
X580000Y940000D03*
X560000D03*
Y960000D03*
X580000D03*
X600000D03*
Y940000D03*
X620000D03*
Y960000D03*
Y980000D03*
X600000Y1060000D03*
X580000D03*
X560000D03*
Y1040000D03*
X580000D03*
X600000D03*
X620000D03*
Y1060000D03*
X560000Y1100000D03*
X580000D03*
X600000D03*
Y1120000D03*
X580000D03*
X560000D03*
X620000D03*
Y1100000D03*
X560000Y1180000D03*
X580000D03*
Y1160000D03*
X600000Y1180000D03*
Y1160000D03*
Y1200000D03*
X580000D03*
X560000D03*
X620000D03*
Y1160000D03*
Y1180000D03*
X580000Y1260000D03*
Y1240000D03*
X560000D03*
X600000Y1220000D03*
X580000D03*
X560000D03*
X600000Y1260000D03*
Y1240000D03*
X620000Y1280000D03*
Y1220000D03*
Y1240000D03*
Y1260000D03*
X560000Y1340000D03*
X580000D03*
X600000D03*
X560000Y1320000D03*
X580000D03*
X560000Y1300000D03*
X620000D03*
X600000Y1420000D03*
X580000D03*
X560000D03*
X600000Y1400000D03*
X580000Y1380000D03*
Y1400000D03*
X560000Y1380000D03*
Y1400000D03*
X580000Y1360000D03*
X600000D03*
X620000Y1420000D03*
Y1400000D03*
Y1380000D03*
Y1360000D03*
X600000Y1500000D03*
X580000D03*
X560000D03*
X600000Y1440000D03*
Y1460000D03*
Y1480000D03*
X580000Y1440000D03*
Y1460000D03*
Y1480000D03*
X560000Y1440000D03*
Y1460000D03*
Y1480000D03*
X620000Y1500000D03*
Y1480000D03*
Y1460000D03*
Y1440000D03*
X560000Y1520000D03*
X580000D03*
X620000Y1680000D03*
X560000D03*
X580000D03*
X600000D03*
Y1700000D03*
Y1720000D03*
X580000D03*
Y1700000D03*
X560000D03*
Y1720000D03*
X600000Y1660000D03*
X580000D03*
X560000D03*
X620000Y1700000D03*
Y1720000D03*
Y1660000D03*
Y1780000D03*
X600000D03*
X580000D03*
X560000D03*
X620000Y1760000D03*
X600000D03*
X580000D03*
X560000D03*
X620000Y1740000D03*
X600000D03*
X580000D03*
X560000D03*
Y1840000D03*
Y1860000D03*
X620000Y1800000D03*
X600000D03*
X580000D03*
X560000D03*
X620000Y1840000D03*
X600000D03*
X580000D03*
X620000Y1860000D03*
X600000D03*
X580000D03*
X560000Y1940000D03*
X580000D03*
X600000D03*
X620000D03*
X560000Y1880000D03*
X620000D03*
X600000D03*
X580000D03*
X620000Y1900000D03*
X600000D03*
X580000D03*
X620000Y1920000D03*
X600000D03*
X580000D03*
X560000D03*
Y1900000D03*
X620000Y1960000D03*
X600000D03*
X580000D03*
X552559Y1986626D03*
X572559D03*
X592559D03*
X600000Y1980000D03*
X580000D03*
X560000D03*
Y1960000D03*
X612559Y1986626D03*
X620000Y1980000D03*
X660000Y40000D03*
X640000D03*
X670018Y5500D03*
X650018D03*
X630018D03*
X660000Y20000D03*
X640000D03*
X680000D03*
Y40000D03*
X690018Y5500D03*
X680000Y100000D03*
X660000D03*
X640000D03*
Y120000D03*
X660000D03*
X640000Y60000D03*
Y80000D03*
X660000D03*
Y60000D03*
X680000Y120000D03*
Y60000D03*
Y80000D03*
X640000Y140000D03*
Y160000D03*
X660000D03*
Y140000D03*
Y180000D03*
X640000D03*
X680000Y140000D03*
Y160000D03*
Y180000D03*
X660000Y260000D03*
X640000D03*
Y240000D03*
X660000D03*
Y220000D03*
Y200000D03*
X640000Y220000D03*
Y200000D03*
X680000Y260000D03*
Y240000D03*
Y220000D03*
Y200000D03*
X640000Y320000D03*
X660000D03*
X680000D03*
X640000Y300000D03*
X660000D03*
X680000D03*
X640000Y280000D03*
X660000D03*
X680000D03*
X640000Y400000D03*
Y380000D03*
X660000D03*
X640000Y360000D03*
X660000D03*
X680000D03*
X640000Y340000D03*
X660000D03*
X680000D03*
Y480000D03*
Y460000D03*
Y440000D03*
X640000Y480000D03*
X660000D03*
Y460000D03*
X640000D03*
X660000Y440000D03*
X640000D03*
X680000Y420000D03*
X660000Y520000D03*
X640000D03*
X680000D03*
Y500000D03*
X640000D03*
X660000D03*
X640000Y540000D03*
X660000D03*
X680000D03*
X663000Y535500D03*
X680000Y560000D03*
X660000D03*
X640000D03*
X680000Y600000D03*
X660000D03*
X640000D03*
Y580000D03*
X660000D03*
X680000D03*
Y660000D03*
Y680000D03*
X640000Y640000D03*
Y700000D03*
X660000Y680000D03*
X640000D03*
X660000Y660000D03*
X640000D03*
X660000Y640000D03*
X680000D03*
X661500Y650500D03*
X640000Y720000D03*
X660000D03*
X680000D03*
X640000Y740000D03*
X660000D03*
X680000D03*
X640000Y760000D03*
X660000D03*
X680000D03*
X640000Y780000D03*
X660000D03*
X680000D03*
X640000Y800000D03*
X660000D03*
X680000D03*
X640000Y820000D03*
X660000D03*
X680000D03*
X640000Y840000D03*
X660000D03*
X680000D03*
X662000Y826600D03*
X640000Y920000D03*
X660000D03*
X640000Y900000D03*
X660000D03*
X640000Y880000D03*
X660000D03*
X640000Y860000D03*
X660000D03*
X680000Y920000D03*
Y900000D03*
Y880000D03*
Y860000D03*
X640000Y940000D03*
Y960000D03*
X660000D03*
Y980000D03*
X640000D03*
X680000D03*
Y960000D03*
X665000Y937000D03*
X660000Y1040000D03*
X640000D03*
Y1060000D03*
X680000Y1040000D03*
X660000Y1053500D03*
X640000Y1100000D03*
Y1120000D03*
X660000D03*
Y1100000D03*
X680000D03*
Y1120000D03*
Y1080000D03*
X640000Y1200000D03*
X660000D03*
Y1160000D03*
X640000D03*
Y1180000D03*
X680000Y1160000D03*
Y1200000D03*
X662000Y1183500D03*
X640000Y1280000D03*
X660000D03*
Y1220000D03*
X640000D03*
Y1240000D03*
X660000D03*
X640000Y1260000D03*
X660000D03*
X680000Y1240000D03*
Y1260000D03*
Y1280000D03*
Y1220000D03*
X660000Y1340000D03*
X640000Y1300000D03*
X660000D03*
Y1320000D03*
X640000D03*
X680000Y1340000D03*
Y1300000D03*
Y1320000D03*
X657000Y1331500D03*
X660000Y1420000D03*
X640000D03*
Y1400000D03*
X660000D03*
X640000Y1380000D03*
X680000Y1420000D03*
Y1360000D03*
X660000Y1500000D03*
X640000D03*
X660000Y1480000D03*
X640000D03*
Y1460000D03*
Y1440000D03*
X660000D03*
X680000Y1500000D03*
Y1480000D03*
Y1440000D03*
X662000Y1459000D03*
X634200Y1561200D03*
Y1565700D03*
X639700Y1561200D03*
Y1565700D03*
X646200Y1561200D03*
Y1565700D03*
X651700Y1561200D03*
Y1565700D03*
X640000Y1680000D03*
X660000D03*
X680000D03*
Y1720000D03*
X640000Y1700000D03*
X660000D03*
Y1720000D03*
X640000D03*
Y1660000D03*
X660000D03*
X680000Y1780000D03*
X660000D03*
X640000D03*
X680000Y1760000D03*
X660000D03*
X640000D03*
X680000Y1740000D03*
X660000D03*
X640000D03*
X680000Y1820000D03*
X660000D03*
X680000Y1800000D03*
X660000D03*
X640000D03*
X680000Y1860000D03*
X660000Y1840000D03*
X640000D03*
Y1860000D03*
X660000D03*
X680000Y1880000D03*
Y1900000D03*
Y1920000D03*
X660000Y1880000D03*
X640000D03*
X660000Y1900000D03*
X640000D03*
X660000Y1920000D03*
X640000D03*
Y1940000D03*
X660000D03*
X680000Y1960000D03*
X660000D03*
X640000D03*
X632559Y1986626D03*
X652559D03*
X672559D03*
X660000Y1980000D03*
X640000D03*
X680000D03*
X692559Y1986626D03*
X700000Y20000D03*
X740000Y40000D03*
X750018Y5500D03*
X730018D03*
X710018D03*
X740000Y20000D03*
X720000D03*
X760000Y40000D03*
Y20000D03*
X700000Y120000D03*
X720000D03*
X740000D03*
X700000Y80000D03*
Y60000D03*
Y100000D03*
X720000D03*
Y60000D03*
X740000D03*
Y80000D03*
X720000D03*
X740000Y100000D03*
X760000Y120000D03*
Y100000D03*
Y80000D03*
Y60000D03*
X700000Y180000D03*
X740000D03*
X720000D03*
Y140000D03*
Y160000D03*
X760000D03*
X740000D03*
X700000D03*
Y140000D03*
X740000D03*
X760000D03*
Y180000D03*
X700000Y260000D03*
Y240000D03*
Y220000D03*
Y200000D03*
X720000Y260000D03*
Y240000D03*
Y220000D03*
Y200000D03*
X740000Y260000D03*
Y200000D03*
Y220000D03*
Y240000D03*
X760000Y260000D03*
Y200000D03*
Y220000D03*
Y240000D03*
Y320000D03*
X700000D03*
Y300000D03*
Y280000D03*
X720000Y320000D03*
Y300000D03*
Y280000D03*
X740000D03*
Y300000D03*
X760000Y280000D03*
X740000Y400000D03*
X720000D03*
X700000D03*
X740000Y380000D03*
X720000D03*
X760000Y400000D03*
Y360000D03*
Y380000D03*
Y460000D03*
Y480000D03*
X740000D03*
X720000D03*
X700000D03*
Y420000D03*
X720000D03*
X740000D03*
Y440000D03*
X720000D03*
X700000D03*
Y460000D03*
X720000D03*
X740000D03*
X760000Y420000D03*
Y440000D03*
X720000Y520000D03*
X700000D03*
X740000Y500000D03*
X720000D03*
X740000Y520000D03*
X700000Y500000D03*
Y540000D03*
X740000D03*
X720000D03*
X760000D03*
Y520000D03*
Y500000D03*
Y560000D03*
X720000D03*
X740000D03*
X700000D03*
X740000Y600000D03*
Y580000D03*
X720000D03*
X740000Y620000D03*
X720000D03*
X700000Y580000D03*
Y600000D03*
X720000D03*
X760000Y620000D03*
Y600000D03*
Y580000D03*
Y680000D03*
Y640000D03*
X740000D03*
Y680000D03*
X720000D03*
X700000D03*
Y660000D03*
X720000D03*
X740000D03*
X700000Y640000D03*
X720000D03*
X700000Y720000D03*
X720000D03*
X740000D03*
Y760000D03*
X720000D03*
X700000D03*
Y740000D03*
X720000D03*
X740000D03*
X760000Y760000D03*
Y740000D03*
Y720000D03*
X740000Y840000D03*
X700000D03*
X720000D03*
X740000Y800000D03*
X720000D03*
X700000D03*
Y820000D03*
X720000D03*
X740000D03*
X700000Y780000D03*
X720000D03*
X740000D03*
X760000Y840000D03*
Y800000D03*
Y820000D03*
Y780000D03*
X740000Y920000D03*
X700000D03*
X720000D03*
X740000Y900000D03*
Y880000D03*
Y860000D03*
X700000Y900000D03*
X720000D03*
X700000Y880000D03*
X720000D03*
X700000Y860000D03*
X720000D03*
X760000Y920000D03*
Y900000D03*
Y880000D03*
Y860000D03*
X700000Y980000D03*
X720000D03*
X740000D03*
X700000Y960000D03*
X720000D03*
X740000D03*
X760000Y980000D03*
Y960000D03*
X740000Y1040000D03*
X720000D03*
X700000D03*
X760000D03*
X700000Y1120000D03*
Y1100000D03*
X720000Y1120000D03*
X740000D03*
Y1080000D03*
X700000D03*
X760000Y1120000D03*
X740000Y1160000D03*
X720000D03*
X700000D03*
Y1200000D03*
X720000D03*
X740000D03*
X760000Y1160000D03*
Y1200000D03*
X700000Y1240000D03*
X740000Y1260000D03*
X720000D03*
X700000D03*
X740000Y1280000D03*
X720000D03*
X700000D03*
Y1220000D03*
X720000D03*
X740000D03*
Y1240000D03*
X720000D03*
X760000D03*
Y1260000D03*
Y1280000D03*
Y1220000D03*
X740000Y1340000D03*
X720000D03*
X700000D03*
X740000Y1300000D03*
X720000D03*
X700000D03*
Y1320000D03*
X740000D03*
X720000D03*
X760000Y1340000D03*
Y1300000D03*
Y1320000D03*
X740000Y1420000D03*
X720000D03*
X740000Y1380000D03*
Y1360000D03*
X720000Y1380000D03*
Y1360000D03*
X700000Y1380000D03*
Y1360000D03*
X760000Y1420000D03*
Y1380000D03*
Y1360000D03*
X700000Y1500000D03*
X740000Y1440000D03*
X720000D03*
X700000D03*
X740000Y1480000D03*
X720000D03*
X700000D03*
X760000Y1440000D03*
Y1480000D03*
X740000Y1520000D03*
X720000D03*
X760000D03*
X700000Y1680000D03*
X740000Y1700000D03*
X720000D03*
Y1720000D03*
X740000D03*
Y1680000D03*
X720000D03*
X760000Y1720000D03*
X753500Y1662000D03*
Y1666500D03*
X759000Y1662000D03*
Y1666500D03*
X765500Y1662000D03*
Y1666500D03*
X700000Y1780000D03*
Y1760000D03*
Y1740000D03*
X720000Y1780000D03*
X740000Y1740000D03*
X760000Y1780000D03*
Y1740000D03*
X758000Y1756000D03*
X759700Y1817500D03*
X700000Y1820000D03*
Y1800000D03*
Y1860000D03*
X720000D03*
X740000D03*
X720000Y1800000D03*
X740000D03*
Y1820000D03*
X720000D03*
X759700Y1837500D03*
X720000Y1880000D03*
X740000Y1900000D03*
Y1880000D03*
X700000D03*
Y1900000D03*
Y1920000D03*
X720000Y1940000D03*
Y1900000D03*
Y1920000D03*
X700000Y1940000D03*
X760000Y1880000D03*
Y1940000D03*
X728700Y1933100D03*
X720000Y1960000D03*
X700000D03*
X720000Y1980000D03*
X700000D03*
X712559Y1986626D03*
X732559D03*
X740000Y1960000D03*
Y1980000D03*
X752559Y1986626D03*
X759900Y1959200D03*
X760000Y1980000D03*
X755995Y1968282D03*
X800000Y40000D03*
X820000D03*
X840000D03*
X780000D03*
X810018Y5500D03*
X790018D03*
X770018D03*
X780000Y20000D03*
X800000D03*
X820000D03*
X830018Y5500D03*
X840000Y20000D03*
X800000Y120000D03*
X820000D03*
X840000D03*
X800000Y100000D03*
X820000D03*
X840000D03*
X800000Y80000D03*
X820000D03*
X840000D03*
X800000Y60000D03*
X820000D03*
X840000D03*
X780000Y120000D03*
Y60000D03*
Y80000D03*
Y100000D03*
Y160000D03*
X840000Y140000D03*
X820000D03*
X800000D03*
X816000Y187000D03*
X780000Y140000D03*
Y180000D03*
X828500Y171000D03*
X840000Y174250D03*
X820500Y171000D03*
X792343Y193599D03*
X832500Y171000D03*
X824500D03*
X816500D03*
X820000Y260000D03*
X780000Y200000D03*
Y220000D03*
Y240000D03*
X800000Y220000D03*
Y240000D03*
X820000Y220000D03*
X840000Y240000D03*
X828000Y203000D03*
X792343Y197402D03*
X780000Y300000D03*
X800000Y280000D03*
Y340000D03*
X780000D03*
Y380000D03*
Y360000D03*
Y400000D03*
X820000D03*
X800000D03*
Y380000D03*
Y360000D03*
X840000Y400000D03*
X824335Y365915D03*
X815375Y362750D03*
X836500Y362500D03*
X833000D03*
X840000Y366000D03*
Y362500D03*
X833000Y366000D03*
X836500D03*
X813350Y369250D03*
X780000Y440000D03*
Y420000D03*
Y460000D03*
X800000Y480000D03*
X820000Y420000D03*
Y440000D03*
Y460000D03*
X800000D03*
Y440000D03*
Y420000D03*
X820000Y480000D03*
X780000D03*
X840000D03*
Y420000D03*
Y440000D03*
Y460000D03*
X780000Y540000D03*
X800000D03*
X820000D03*
X780000Y500000D03*
X820000D03*
Y520000D03*
X800000Y500000D03*
Y520000D03*
X780000D03*
X840000Y500000D03*
Y520000D03*
Y540000D03*
X780000Y580000D03*
Y560000D03*
X800000Y600000D03*
Y580000D03*
Y560000D03*
X780000Y620000D03*
X800000D03*
X820000D03*
X780000Y600000D03*
X820000Y580000D03*
Y560000D03*
Y600000D03*
X840000Y620000D03*
Y580000D03*
Y560000D03*
Y600000D03*
X820000Y700000D03*
X780000D03*
X778400Y659800D03*
X800000Y640000D03*
X780000D03*
X820000Y660000D03*
X798400Y659800D03*
X840000Y640000D03*
Y680000D03*
Y660000D03*
Y700000D03*
X782500Y648000D03*
X820000Y720000D03*
X800000Y760000D03*
X780000D03*
Y740000D03*
X800000D03*
Y720000D03*
X780000D03*
X840000D03*
X824335Y771415D03*
X815375Y768250D03*
X840000Y771500D03*
X833000D03*
X836500D03*
X840000Y768000D03*
X836500D03*
X833000D03*
X780000Y840000D03*
X800000D03*
X820000D03*
Y820000D03*
X780000Y800000D03*
Y780000D03*
X800000D03*
X840000Y840000D03*
Y800000D03*
Y820000D03*
X780000Y920000D03*
X800000D03*
X820000D03*
X780000Y900000D03*
X800000D03*
X820000D03*
X780000Y880000D03*
X800000D03*
X820000D03*
X780000Y860000D03*
X800000D03*
X820000D03*
X840000Y920000D03*
Y860000D03*
Y880000D03*
Y900000D03*
X780000Y980000D03*
X800000D03*
X820000D03*
X780000Y960000D03*
X800000D03*
X820000D03*
X840000D03*
Y980000D03*
X800000Y1060000D03*
X820000D03*
X780000D03*
X820000Y1040000D03*
X840000Y1060000D03*
Y1040000D03*
X780000Y1120000D03*
X800000D03*
Y1080000D03*
Y1100000D03*
X820000Y1120000D03*
X800000Y1200000D03*
X820000D03*
X780000Y1160000D03*
X800000D03*
X780000Y1200000D03*
X840000D03*
X824335Y1176915D03*
X815375Y1173750D03*
X836500Y1177000D03*
X833000D03*
X840000D03*
X820000Y1220000D03*
Y1240000D03*
X800000D03*
X780000D03*
X820000Y1260000D03*
X800000D03*
X780000D03*
X820000Y1280000D03*
X800000D03*
X780000D03*
Y1220000D03*
X800000D03*
X840000Y1280000D03*
Y1220000D03*
Y1240000D03*
Y1260000D03*
X820000Y1340000D03*
X800000D03*
X780000D03*
X820000Y1300000D03*
X800000D03*
X780000D03*
Y1320000D03*
X820000D03*
X800000D03*
X840000Y1340000D03*
Y1300000D03*
Y1320000D03*
X820000Y1420000D03*
X800000D03*
X780000D03*
X820000Y1380000D03*
Y1360000D03*
X800000Y1380000D03*
Y1360000D03*
X780000Y1380000D03*
Y1360000D03*
X840000Y1420000D03*
Y1360000D03*
Y1380000D03*
X820000Y1440000D03*
X800000D03*
X780000D03*
X820000Y1480000D03*
X800000D03*
X780000D03*
X840000Y1440000D03*
Y1480000D03*
X800000Y1560000D03*
X780000Y1520000D03*
X840000Y1640000D03*
Y1600000D03*
X824335Y1582415D03*
X816625Y1579250D03*
X840000Y1582500D03*
X833000D03*
X836500D03*
X840000Y1579000D03*
X836500D03*
X833000D03*
X813000Y1585750D03*
X808500Y1621500D03*
X814000D03*
Y1626000D03*
X808500D03*
X814000Y1630500D03*
X808500D03*
X820000Y1680000D03*
X829388Y1695500D03*
X825388D03*
X833388D03*
X837388D03*
X840000Y1680000D03*
Y1660000D03*
X771000Y1662000D03*
Y1666500D03*
X780000Y1780000D03*
X800000D03*
Y1740000D03*
X780000D03*
X795500Y1755000D03*
X825388Y1739500D03*
X829388D03*
X833388D03*
X837388D03*
X837500Y1785000D03*
X829500D03*
X819000D03*
X815000D03*
X816000Y1801000D03*
X780000Y1800000D03*
X800000D03*
X780000Y1840000D03*
X800000Y1820000D03*
X820000D03*
X828000Y1862000D03*
X827500Y1817000D03*
X834750Y1823285D03*
X819000Y1839000D03*
X800000Y1920000D03*
X820000D03*
X780000D03*
X796339Y1937007D03*
X820000Y1980000D03*
X772559Y1986626D03*
X792559D03*
X812559D03*
X769239Y1955776D03*
X780000Y1980000D03*
X800000D03*
X823400Y1973400D03*
X827900D03*
X835900Y1973500D03*
X839400D03*
X832559Y1986626D03*
X840000Y1980000D03*
X799205Y1960532D03*
X774989Y1955708D03*
X780214Y1953257D03*
X796339Y1940507D03*
X804239Y1953307D03*
Y1956807D03*
X800739D03*
Y1953307D03*
X797239D03*
Y1956807D03*
X785239Y1960907D03*
X860000Y40000D03*
X880000D03*
X890018Y5500D03*
X870018D03*
X850018D03*
X880000Y20000D03*
X860000D03*
X900000Y40000D03*
X910018Y5500D03*
X900000Y20000D03*
X860000Y120000D03*
X880000D03*
X860000Y100000D03*
X880000D03*
X860000Y80000D03*
X880000D03*
X860000Y60000D03*
X880000D03*
X900000Y120000D03*
Y60000D03*
Y100000D03*
Y80000D03*
X860000Y140000D03*
X908493Y136513D03*
X880000Y180000D03*
X869250Y144750D03*
X885993Y134893D03*
X885531Y164804D03*
X896441Y147203D03*
X844000Y190000D03*
X866961Y162539D03*
X896547Y150803D03*
X890469Y164804D03*
X864975Y148875D03*
X863441Y219890D03*
X876441Y262165D03*
Y255866D03*
X863307Y264102D03*
X860000Y260000D03*
X876441Y246417D03*
Y236968D03*
Y230669D03*
Y221220D03*
Y211771D03*
X863441Y213102D03*
X860000Y240000D03*
X899941Y233917D03*
Y218917D03*
Y203917D03*
X908654Y231105D03*
X904838D03*
X872500Y241500D03*
X876500Y251000D03*
X901441Y244842D03*
X908346Y235394D03*
X905146D03*
X872941Y223745D03*
Y228145D03*
X867441Y214896D03*
Y218096D03*
Y265290D03*
X901600Y249800D03*
X863307Y269678D03*
X863441Y288972D03*
X863346Y301768D03*
X860100Y336500D03*
X873600Y332200D03*
X860100Y333000D03*
X876441Y318858D03*
Y309409D03*
Y299960D03*
Y290511D03*
Y281063D03*
Y271614D03*
X863346Y307602D03*
X863441Y282602D03*
X901500Y312500D03*
X899941Y283917D03*
Y278917D03*
X856200Y337300D03*
X844050D03*
X872941Y274138D03*
Y278538D03*
Y293036D03*
Y297436D03*
Y311934D03*
Y316334D03*
X867441Y268490D03*
Y284187D03*
Y287387D03*
Y303085D03*
Y306285D03*
X899941Y308917D03*
X865000Y371000D03*
X868500D03*
X876000D03*
X872500D03*
X879600Y385200D03*
X860000Y400000D03*
X880000D03*
X900000D03*
X899900Y382300D03*
X850966Y370025D03*
X843500Y366000D03*
Y362500D03*
X880000Y480000D03*
X860000D03*
X880000Y420000D03*
X860000D03*
X880000Y440000D03*
X860000D03*
X880000Y460000D03*
X860000D03*
X900000Y480000D03*
Y420000D03*
Y440000D03*
Y460000D03*
X907493Y542025D03*
X880000Y500000D03*
X860000D03*
X880000Y520000D03*
X860000D03*
X900000Y500000D03*
Y520000D03*
X872875Y535275D03*
X891250Y537500D03*
X895547Y552715D03*
X857735Y553465D03*
X895547Y556315D03*
X865125Y544000D03*
X863441Y625402D03*
X876441Y626732D03*
Y617283D03*
X863441Y618614D03*
X860000Y580000D03*
Y560000D03*
X880000Y580000D03*
Y600000D03*
X860000D03*
X899941Y624429D03*
Y609429D03*
X900000Y600000D03*
X883781Y564519D03*
X872941Y629257D03*
X867441Y620408D03*
Y623608D03*
X888719Y564519D03*
X863441Y694484D03*
X863287Y669690D03*
X876441Y661378D03*
Y651929D03*
Y642480D03*
Y636181D03*
X863287Y675114D03*
X863441Y688114D03*
X876441Y696023D03*
Y686575D03*
Y677126D03*
Y667677D03*
X899941Y684429D03*
Y639429D03*
X908654Y636613D03*
X904838D03*
X899941Y689429D03*
X868500Y654000D03*
X876500Y648000D03*
X901441Y650354D03*
X908346Y640906D03*
X905146D03*
X872941Y633657D03*
Y679650D03*
Y684050D03*
Y698548D03*
Y702948D03*
X867441Y670802D03*
Y674002D03*
Y689699D03*
Y692899D03*
X901200Y655100D03*
X863397Y713280D03*
X859500Y741800D03*
X876441Y724370D03*
Y714921D03*
Y705472D03*
X863397Y707114D03*
X873400Y738400D03*
X859500Y738300D03*
X901500Y718000D03*
X856100Y743300D03*
X850966Y775525D03*
X843500Y771500D03*
Y768000D03*
X846200Y743300D03*
X872941Y717446D03*
Y721846D03*
X867441Y708597D03*
Y711797D03*
X899941Y714429D03*
X860000Y840000D03*
X880000D03*
X864500Y776500D03*
X868000D03*
X872000D03*
X875500D03*
X860000Y800000D03*
X880000D03*
X860000Y820000D03*
X880000D03*
X900000Y840000D03*
Y800000D03*
Y820000D03*
X860000Y920000D03*
X880000D03*
X860000Y860000D03*
X880000D03*
X860000Y880000D03*
X880000D03*
X860000Y900000D03*
X880000D03*
X900000Y920000D03*
Y860000D03*
Y880000D03*
Y900000D03*
X907493Y947537D03*
X860000Y980000D03*
X886517Y945917D03*
X872875Y940925D03*
X883781Y970031D03*
X895547Y958227D03*
X857623Y958977D03*
X895547Y961827D03*
X888719Y970031D03*
X865125Y949600D03*
X863441Y1030914D03*
X876441Y1066890D03*
Y1057441D03*
Y1047992D03*
Y1041693D03*
Y1032244D03*
Y1022795D03*
X863441Y1024126D03*
X880000Y1000000D03*
X860000Y1040000D03*
X899941Y1044941D03*
Y1029941D03*
Y1014941D03*
X908654Y1042129D03*
X904838D03*
X900000Y1000000D03*
Y1040000D03*
Y1020000D03*
X868500Y1059500D03*
X901441Y1055866D03*
X876500Y1053500D03*
X908346Y1046418D03*
X905146D03*
X872941Y1034769D03*
Y1039169D03*
X867441Y1025920D03*
Y1029120D03*
X901300Y1060700D03*
X863346Y1112792D03*
X863441Y1099996D03*
X863308Y1080702D03*
X876441Y1129882D03*
Y1120433D03*
Y1110984D03*
Y1101535D03*
Y1092087D03*
Y1082638D03*
Y1073189D03*
X863308Y1075126D03*
X863441Y1093626D03*
X863346Y1118626D03*
X899941Y1094941D03*
Y1089941D03*
X900000Y1080000D03*
X901500Y1123500D03*
X872941Y1085162D03*
Y1089562D03*
Y1104060D03*
Y1108460D03*
Y1122958D03*
Y1127358D03*
X867441Y1076314D03*
Y1079514D03*
Y1095211D03*
Y1098411D03*
Y1114109D03*
Y1117309D03*
X899941Y1119941D03*
X859500Y1147600D03*
X874200Y1144000D03*
X859500Y1144100D03*
X864000Y1181900D03*
X867500D03*
X872200D03*
X875700D03*
X860000Y1200000D03*
X880000D03*
X900000D03*
X854500Y1148700D03*
X850600Y1181025D03*
X843500Y1177000D03*
X844600Y1148700D03*
X860000Y1280000D03*
X880000D03*
X860000Y1220000D03*
Y1240000D03*
Y1260000D03*
X880000Y1220000D03*
Y1240000D03*
Y1260000D03*
X900000Y1280000D03*
Y1220000D03*
Y1240000D03*
Y1260000D03*
X907493Y1353048D03*
X880000Y1340000D03*
X860000D03*
Y1300000D03*
Y1320000D03*
X880000D03*
Y1300000D03*
X900000Y1320000D03*
Y1300000D03*
X872875Y1346488D03*
X891250Y1348500D03*
X865125Y1346488D03*
X876441Y1428307D03*
X863441Y1429638D03*
X860000Y1420000D03*
Y1380000D03*
X899941Y1420453D03*
X883219Y1373504D03*
X895647Y1363738D03*
X857688Y1364488D03*
X895647Y1367338D03*
X887438Y1373374D03*
X863286Y1480714D03*
X863441Y1436426D03*
X876441Y1478701D03*
Y1472402D03*
Y1462953D03*
Y1453504D03*
Y1447205D03*
Y1437756D03*
X860000Y1440000D03*
X876441Y1497599D03*
Y1488150D03*
X863286Y1486138D03*
X863441Y1499138D03*
X899941Y1450453D03*
Y1435453D03*
X908654Y1447641D03*
X904838D03*
X899941Y1500453D03*
Y1495453D03*
X868500Y1465000D03*
X901441Y1461378D03*
X876500Y1459000D03*
X908346Y1451930D03*
X905146D03*
X872941Y1440281D03*
Y1444681D03*
Y1490674D03*
Y1495074D03*
X867441Y1431432D03*
Y1434632D03*
Y1481826D03*
Y1485026D03*
Y1500723D03*
X901400Y1466100D03*
X863347Y1518304D03*
X863441Y1505508D03*
X859500Y1553200D03*
X876441Y1535394D03*
Y1525945D03*
Y1516496D03*
Y1507047D03*
X863347Y1524138D03*
X873300Y1549100D03*
X859500Y1549700D03*
X901500Y1529000D03*
X855500Y1554300D03*
X845600D03*
X872941Y1509572D03*
Y1513972D03*
Y1528470D03*
Y1532870D03*
X867441Y1503923D03*
Y1519621D03*
Y1522821D03*
X899941Y1525453D03*
X860000Y1640000D03*
Y1580000D03*
X865500Y1589000D03*
X869000D03*
X873000D03*
X876500D03*
X880000Y1599000D03*
X900000Y1600000D03*
X850966Y1586525D03*
X843500Y1582500D03*
Y1579000D03*
X891500Y1712000D03*
X895500D03*
Y1708000D03*
X841388Y1695500D03*
X873962Y1672000D03*
Y1676500D03*
Y1681500D03*
Y1685500D03*
X860000Y1660000D03*
X906000Y1713500D03*
X885750Y1701500D03*
X891500Y1708000D03*
X891000Y1720000D03*
X901500Y1681500D03*
X881353Y1650749D03*
X877853D03*
Y1654249D03*
X881353D03*
X896500Y1681000D03*
X859500Y1696000D03*
X886600Y1756100D03*
X872875Y1751600D03*
X906500Y1734100D03*
X907493Y1758560D03*
X898500Y1734000D03*
X910500Y1734600D03*
X895547Y1769250D03*
X883781Y1781054D03*
X895547Y1772850D03*
X888719Y1781054D03*
X865125Y1751800D03*
X902500Y1734000D03*
X910500Y1724700D03*
X863441Y1841938D03*
X876441Y1859016D03*
Y1852717D03*
X860000Y1860000D03*
X876441Y1843268D03*
Y1833819D03*
X863441Y1835150D03*
X899941Y1855965D03*
X908654Y1853153D03*
X904838D03*
X899941Y1840965D03*
Y1825965D03*
X876000Y1864000D03*
X901441Y1866890D03*
X908346Y1857442D03*
X905146D03*
X872941Y1845793D03*
Y1850193D03*
X867441Y1836944D03*
Y1840144D03*
X863346Y1923816D03*
X863441Y1911020D03*
X863287Y1886226D03*
X876441Y1912559D03*
Y1903111D03*
Y1893662D03*
Y1884213D03*
Y1877914D03*
Y1868465D03*
X863287Y1891650D03*
X863441Y1904650D03*
X860000Y1880000D03*
X876441Y1931457D03*
Y1922008D03*
X863346Y1929650D03*
X901500Y1934500D03*
X899941Y1905965D03*
Y1900965D03*
X867500Y1870000D03*
X872941Y1896186D03*
Y1900586D03*
Y1915084D03*
Y1919484D03*
Y1933982D03*
Y1938382D03*
X867441Y1887338D03*
Y1890538D03*
Y1906235D03*
Y1909435D03*
Y1925133D03*
Y1928333D03*
X899941Y1930965D03*
X901200Y1871600D03*
X876441Y1940906D03*
X843500Y1973500D03*
X847000D03*
X852559Y1986626D03*
X872559D03*
X896546Y1986566D03*
X860000Y1980000D03*
X912559Y1986626D03*
X844800Y1949700D03*
X858800Y1951300D03*
X879500Y1970000D03*
X880000Y1955500D03*
X862000Y1969900D03*
Y1960500D03*
X844700Y1945200D03*
X960000Y40000D03*
X940000D03*
X920000D03*
X950018Y5500D03*
X930018D03*
X920000Y20000D03*
X940000D03*
X960000D03*
X980000Y40000D03*
X970018Y5500D03*
X980000Y20000D03*
X960000Y120000D03*
X940000D03*
X920000D03*
Y60000D03*
X940000D03*
X960000D03*
X920000Y100000D03*
X940000D03*
X960000D03*
Y80000D03*
X940000D03*
X920000D03*
X980000Y120000D03*
Y60000D03*
Y100000D03*
Y80000D03*
X960000Y140000D03*
X940000D03*
X960000Y160000D03*
X940000D03*
Y180000D03*
X960000D03*
X980000D03*
X926347Y155500D03*
Y160000D03*
Y164453D03*
X921400Y235002D03*
Y245200D03*
X940000Y200000D03*
X960000D03*
Y220000D03*
X940000D03*
Y240000D03*
X960000D03*
Y260000D03*
X940000D03*
X980000Y240000D03*
Y260000D03*
Y200000D03*
Y220000D03*
X918846Y238501D03*
Y241701D03*
X940000Y280000D03*
X920000D03*
X960000D03*
X920000Y300000D03*
X940000D03*
X960000D03*
X920000Y320000D03*
X940000D03*
X960000D03*
X980000Y280000D03*
Y300000D03*
Y320000D03*
X960000Y400000D03*
X940000D03*
X920000D03*
X960000Y340000D03*
X940000D03*
X920000D03*
Y360000D03*
X940000D03*
X960000D03*
Y380000D03*
X940000D03*
X920000D03*
X980000Y400000D03*
Y340000D03*
Y360000D03*
Y380000D03*
X920000Y480000D03*
X940000D03*
X960000D03*
X920000Y420000D03*
X940000D03*
X960000D03*
X920000Y440000D03*
X940000D03*
X960000D03*
X920000Y460000D03*
X940000D03*
X960000D03*
X980000Y480000D03*
Y420000D03*
Y440000D03*
Y460000D03*
X920000Y500000D03*
X940000D03*
X960000D03*
X920000Y520000D03*
X940000D03*
X960000D03*
Y540000D03*
X980000Y500000D03*
Y520000D03*
Y540000D03*
X940000Y620000D03*
X960000D03*
Y560000D03*
Y580000D03*
Y600000D03*
X940000Y580000D03*
Y600000D03*
X920000Y580000D03*
Y600000D03*
X980000Y620000D03*
Y560000D03*
Y580000D03*
Y600000D03*
X926365Y561000D03*
Y569965D03*
Y565500D03*
X919000Y639715D03*
X920000Y700000D03*
X919000Y651511D03*
X940000Y640000D03*
X960000D03*
X920000Y680000D03*
X940000D03*
X960000D03*
Y660000D03*
X940000D03*
X920000D03*
X940000Y700000D03*
X960000D03*
X980000Y640000D03*
Y660000D03*
Y700000D03*
X918846Y644013D03*
Y647213D03*
X940000Y760000D03*
X960000D03*
X920000D03*
Y740000D03*
Y720000D03*
X940000D03*
X960000D03*
X940000Y740000D03*
X960000D03*
X980000Y760000D03*
Y720000D03*
Y740000D03*
X940000Y840000D03*
X960000D03*
X920000D03*
X940000Y780000D03*
X960000D03*
X940000Y800000D03*
X960000D03*
X940000Y820000D03*
X960000D03*
X920000Y800000D03*
Y820000D03*
Y780000D03*
X980000Y840000D03*
Y780000D03*
Y800000D03*
Y820000D03*
X940000Y920000D03*
X960000D03*
X920000D03*
X940000Y860000D03*
X960000D03*
X940000Y880000D03*
X960000D03*
X940000Y900000D03*
X960000D03*
X920000Y860000D03*
Y880000D03*
Y900000D03*
X980000Y920000D03*
Y860000D03*
Y880000D03*
Y900000D03*
X960000Y980000D03*
Y940000D03*
X940000D03*
X960000Y960000D03*
X980000Y980000D03*
Y940000D03*
Y960000D03*
X926477Y966500D03*
Y971000D03*
Y975477D03*
X922900Y1048050D03*
Y1054200D03*
X920000Y1060000D03*
X940000D03*
X960000D03*
Y1000000D03*
X940000D03*
X920000D03*
Y1020000D03*
X940000D03*
X960000D03*
Y1040000D03*
X940000D03*
X920000D03*
X980000Y1000000D03*
Y1020000D03*
Y1040000D03*
X918846Y1049525D03*
Y1052725D03*
X940000Y1140000D03*
X960000D03*
X920000Y1080000D03*
X940000D03*
X960000D03*
Y1100000D03*
X940000D03*
X920000Y1120000D03*
X940000D03*
X960000D03*
X920000Y1140000D03*
X980000D03*
Y1100000D03*
X979962Y1075211D03*
X980000Y1120000D03*
X923000Y1160200D03*
X940000Y1160000D03*
X960000D03*
Y1180000D03*
X940000D03*
X923000Y1180200D03*
X960000Y1200000D03*
X940000D03*
X920000D03*
X980000Y1160000D03*
Y1180000D03*
Y1200000D03*
X960000Y1280000D03*
X940000D03*
X920000D03*
X960000Y1220000D03*
X940000D03*
X960000Y1240000D03*
X940000D03*
X960000Y1260000D03*
X940000D03*
X920000Y1220000D03*
Y1240000D03*
Y1260000D03*
X980000Y1220000D03*
Y1240000D03*
Y1260000D03*
Y1280000D03*
X960000Y1340000D03*
X940000D03*
X920000D03*
X960000Y1300000D03*
X940000D03*
X960000Y1320000D03*
X940000D03*
X920000Y1300000D03*
Y1320000D03*
X980000Y1340000D03*
Y1300000D03*
Y1320000D03*
X981700Y1409000D03*
X954300Y1412600D03*
X960000Y1360000D03*
Y1380000D03*
Y1400000D03*
X940000D03*
X920000D03*
X963500Y1409000D03*
X973000D03*
X968000D03*
X977500D03*
X980000Y1360000D03*
Y1380000D03*
Y1400000D03*
X926300Y1372000D03*
Y1380988D03*
Y1376500D03*
X919000Y1450734D03*
Y1462540D03*
X920000Y1480000D03*
Y1440000D03*
X918846Y1455037D03*
Y1458237D03*
X920000Y1520000D03*
Y1540000D03*
X923800Y1559300D03*
X923500Y1579800D03*
X920000Y1600000D03*
X959000Y1631000D03*
X943500Y1646989D03*
X973000Y1641500D03*
X931000Y1659000D03*
X960000Y1700000D03*
Y1720000D03*
X933000Y1704000D03*
X951500Y1658000D03*
X952000Y1678000D03*
X980000Y1700000D03*
Y1720000D03*
X963500Y1675000D03*
Y1657000D03*
X959000D03*
Y1675000D03*
X926500Y1660000D03*
X941000Y1653000D03*
X934825Y1682285D03*
X947000Y1654500D03*
X915250Y1687500D03*
X919250Y1711500D03*
X960000Y1740000D03*
Y1760000D03*
X940000D03*
X933000Y1736500D03*
X925500Y1738000D03*
X960000Y1780000D03*
X980000D03*
Y1740000D03*
Y1760000D03*
X916500Y1729500D03*
X926400Y1777500D03*
Y1782000D03*
Y1786500D03*
X921900Y1722400D03*
X919000Y1856251D03*
X960000Y1860000D03*
X940000D03*
X960000Y1800000D03*
X940000D03*
X920000D03*
X940000Y1820000D03*
X960000D03*
X940000Y1840000D03*
X960000D03*
X920000D03*
X980000Y1860000D03*
Y1800000D03*
Y1820000D03*
Y1840000D03*
X918846Y1860549D03*
Y1863749D03*
X920000Y1920000D03*
X940000D03*
X960000D03*
Y1940000D03*
X940000D03*
X920000D03*
X919000Y1868047D03*
X960000Y1880000D03*
X940000D03*
X920000D03*
X960000Y1900000D03*
X940000D03*
X920000D03*
X980000Y1920000D03*
Y1940000D03*
X980018Y1897856D03*
X932559Y1986626D03*
X952559D03*
X960000Y1960000D03*
X940000D03*
X920000D03*
Y1980000D03*
X940000D03*
X960000D03*
X972559Y1986626D03*
X980000Y1960000D03*
Y1980000D03*
X1031902Y43616D03*
X1020000Y40000D03*
X1000000D03*
X1031902Y23616D03*
X1030018Y5500D03*
X1010018D03*
X990018D03*
X1000000Y20000D03*
X1020000D03*
Y120000D03*
X1000000D03*
X1031902Y63616D03*
Y103616D03*
Y83616D03*
X1000000Y60000D03*
X1020000D03*
X1000000Y100000D03*
X1020000D03*
Y80000D03*
X1000000D03*
X1031902Y143616D03*
Y123616D03*
Y163616D03*
X1020000Y140000D03*
Y160000D03*
Y180000D03*
X1031902Y183616D03*
X1000000Y240000D03*
X1020000D03*
X1031902Y263616D03*
X1020000Y260000D03*
X1000000D03*
X1031902Y223616D03*
Y203616D03*
Y243616D03*
X1000000Y200000D03*
X1020000D03*
Y220000D03*
X1000000D03*
X1031902Y303616D03*
Y283616D03*
Y323616D03*
X1000000Y280000D03*
X1020000D03*
X1000000Y300000D03*
X1020000D03*
X1000000Y320000D03*
X1020000D03*
X1031902Y403616D03*
X1020000Y400000D03*
X1000000D03*
X1031902Y383616D03*
Y363616D03*
Y343616D03*
X1020000Y340000D03*
X1000000D03*
Y360000D03*
X1020000D03*
Y380000D03*
X1000000D03*
X1031902Y483616D03*
X1000000Y480000D03*
X1020000D03*
X1031902Y443616D03*
Y423616D03*
Y463616D03*
X1000000Y420000D03*
X1020000D03*
X1000000Y440000D03*
X1020000D03*
X1000000Y460000D03*
X1020000D03*
X1031902Y523616D03*
Y503616D03*
Y543616D03*
X1000000Y500000D03*
X1020000D03*
X1000000Y520000D03*
X1020000D03*
X1000000Y540000D03*
X1020000D03*
X1031902Y623616D03*
X1000000Y620000D03*
X1020000D03*
X1031902Y603616D03*
Y583616D03*
Y563616D03*
X1020000Y560000D03*
X1000000D03*
X1020000Y580000D03*
X1000000D03*
X1020000Y600000D03*
X1000000D03*
X1031902Y683616D03*
Y663616D03*
Y643616D03*
X1000000Y640000D03*
X1020000D03*
Y660000D03*
Y680000D03*
Y700000D03*
X1000000Y740000D03*
X1020000D03*
X1000000Y760000D03*
X1020000D03*
X1031902Y763616D03*
Y743616D03*
Y723616D03*
Y703616D03*
X1000000Y720000D03*
X1020000D03*
X1031902Y843616D03*
X1000000Y840000D03*
X1020000D03*
X1031902Y823616D03*
Y803616D03*
Y783616D03*
X1000000Y780000D03*
X1020000D03*
X1000000Y800000D03*
X1020000D03*
X1000000Y820000D03*
X1020000D03*
X1000000Y920000D03*
X1020000D03*
X1031902Y903616D03*
Y883616D03*
Y863616D03*
X1000000Y860000D03*
X1020000D03*
X1000000Y880000D03*
X1020000D03*
X1000000Y900000D03*
X1020000D03*
X1031902Y983616D03*
X1000000Y980000D03*
X1020000D03*
X1031902Y963616D03*
Y943616D03*
Y923616D03*
X1020000Y940000D03*
X1000000D03*
Y960000D03*
X1020000D03*
X1031902Y1063616D03*
X1020000Y1060000D03*
X1031902Y1043616D03*
Y1023616D03*
Y1003616D03*
X1020000Y1000000D03*
X1000000D03*
Y1020000D03*
X1020000D03*
Y1040000D03*
X1000000D03*
X1031902Y1123616D03*
X1000000Y1140000D03*
X1020000D03*
X1031902Y1103616D03*
Y1083616D03*
X1020000Y1080000D03*
Y1100000D03*
X999922Y1102598D03*
X1000000Y1120000D03*
X1020000D03*
X1031902Y1143616D03*
Y1183616D03*
Y1163616D03*
X1000000Y1160000D03*
X1020000D03*
Y1180000D03*
X1000000D03*
X1031902Y1203616D03*
X1020000Y1200000D03*
X1000000D03*
Y1220000D03*
X1020000Y1240000D03*
X1000000D03*
X1020000Y1260000D03*
X1000000D03*
X1031902Y1283616D03*
X1020000Y1280000D03*
X1000000D03*
X1031902Y1263616D03*
Y1243616D03*
Y1223616D03*
X1020000Y1220000D03*
X1031902Y1343616D03*
X1020000Y1340000D03*
X1000000D03*
X1031902Y1323616D03*
Y1303616D03*
X1020000Y1300000D03*
X1000000D03*
X1020000Y1320000D03*
X1000000D03*
X986200Y1409000D03*
X994600Y1414100D03*
X990300Y1412500D03*
X1031902Y1363616D03*
Y1383616D03*
X1020000Y1360000D03*
X1000000D03*
Y1380000D03*
X1020000D03*
Y1400000D03*
X1000000D03*
X994898Y1646102D03*
X992500Y1636000D03*
X991602Y1622500D03*
X1000000Y1700000D03*
X1020000Y1720000D03*
X1000000D03*
X995102Y1676102D03*
X995000Y1656102D03*
Y1666102D03*
X1031902Y1785969D03*
X1000000Y1780000D03*
X1020000D03*
X1031902Y1745969D03*
Y1725969D03*
Y1765969D03*
X1000000Y1740000D03*
X1020000D03*
Y1760000D03*
X1000000D03*
X1031902Y1865969D03*
Y1845969D03*
X1020000Y1860000D03*
X1000000D03*
X1031902Y1805969D03*
Y1825969D03*
X1020000Y1800000D03*
X1000000D03*
Y1820000D03*
X1020000D03*
X1000000Y1840000D03*
X1020000D03*
X1031902Y1925969D03*
X999469Y1923465D03*
X1020000Y1920000D03*
Y1940000D03*
X1000000D03*
X1031902Y1885969D03*
Y1905969D03*
X1020000Y1880000D03*
Y1900000D03*
X1031902Y1965969D03*
Y1945969D03*
X992559Y1986626D03*
X1012559D03*
X1031902Y1985969D03*
X1020000Y1960000D03*
X1000000D03*
Y1980000D03*
X1020000D03*
G54D31*
X33375Y1970275D03*
X85475Y377775D03*
Y783275D03*
X63495Y1012436D03*
X85475Y1188775D03*
X64140Y1417910D03*
X92800Y1497000D03*
Y1492000D03*
X109100Y1543700D03*
X84400Y1840600D03*
X94400Y1839900D03*
X84400Y1836300D03*
X84900Y1867400D03*
X144700Y426600D03*
X115800Y454500D03*
Y449500D03*
X167300Y556330D03*
X167295Y560416D03*
X144700Y832100D03*
X115800Y860000D03*
Y855000D03*
X166217Y960000D03*
X164830Y979729D03*
X145000Y1237600D03*
X115800Y1265500D03*
Y1260500D03*
X151259Y1352302D03*
Y1347802D03*
X146200Y1643100D03*
X115800Y1671000D03*
Y1666000D03*
X119000Y1943900D03*
X193300Y52500D03*
X190300Y135000D03*
X200300Y569000D03*
X191454Y1346488D03*
X324800Y408500D03*
Y404400D03*
Y421000D03*
Y417000D03*
Y425000D03*
X325800Y609000D03*
Y597000D03*
X276800Y573000D03*
Y565000D03*
Y585000D03*
Y577000D03*
Y597000D03*
Y589000D03*
X325800D03*
X324800Y838500D03*
Y847000D03*
Y834400D03*
Y851000D03*
Y855000D03*
Y1210000D03*
Y1205800D03*
Y1222500D03*
Y1218500D03*
Y1226500D03*
X276800Y1419500D03*
Y1411500D03*
Y1423500D03*
Y1403500D03*
Y1431500D03*
X324800Y1721000D03*
Y1708500D03*
Y1717000D03*
Y1704300D03*
X268800Y1722000D03*
X324800Y1725000D03*
X363800Y58000D03*
X330800Y377000D03*
X334800Y389000D03*
X330800Y381000D03*
Y385000D03*
X387300Y459000D03*
X351800D03*
X379300D03*
X343800D03*
X330800Y807000D03*
X402300Y820000D03*
Y805000D03*
Y824000D03*
Y809000D03*
X334800Y819000D03*
X330800Y815000D03*
Y811000D03*
X387300Y889000D03*
X351800D03*
X379300D03*
X343800D03*
X334800Y1190500D03*
X402300Y1207500D03*
Y1211500D03*
X330800Y1178500D03*
Y1182500D03*
Y1186500D03*
X387300Y1260500D03*
X351800D03*
X402300Y1222500D03*
Y1226500D03*
X379300Y1260500D03*
X343800D03*
X330800Y1677000D03*
X334800Y1691000D03*
X402300Y1721000D03*
Y1706000D03*
Y1710000D03*
X330800Y1681000D03*
Y1685000D03*
X351800Y1759000D03*
X402300Y1725000D03*
X343800Y1759000D03*
X760214Y1968282D03*
X799300Y193000D03*
Y198000D03*
X811975Y377775D03*
Y783275D03*
Y1188775D03*
Y1594275D03*
X799300Y1812000D03*
Y1807000D03*
X886300Y157000D03*
Y161000D03*
X895275Y154724D03*
X887116Y168354D03*
X861800Y553465D03*
X884550Y556715D03*
Y560715D03*
X893541Y560408D03*
X861800Y958977D03*
X884550Y962227D03*
Y966227D03*
X893774Y965913D03*
X861800Y1364488D03*
X883988Y1365200D03*
Y1369700D03*
X893385Y1371351D03*
X884550Y1773250D03*
X861800Y1770000D03*
X884550Y1777250D03*
X893700Y1776900D03*
X847900Y1945200D03*
X919800Y129953D03*
Y535465D03*
Y940977D03*
Y1346488D03*
X951300Y1668500D03*
Y1663500D03*
X915800Y1715000D03*
X919800Y1752000D03*
G54D22*
X29400Y1778850D03*
Y1775350D03*
X76587Y1854268D03*
X177200Y553500D03*
X124700Y1502000D03*
X357200Y120500D03*
Y117000D03*
X363700Y76500D03*
X387200Y447500D03*
X351700D03*
X379200D03*
X343700D03*
X387200Y877500D03*
X351700D03*
X379200D03*
X343700D03*
X387200Y1249000D03*
X351700D03*
X379200D03*
X343700D03*
X351700Y1747500D03*
X343700D03*
X831200Y203000D03*
Y1817000D03*
X911700Y1691000D03*
Y1699000D03*
X885700Y1698000D03*
G54D40*
X63500Y245215D03*
X59625Y237715D03*
X67375D03*
X63500Y650727D03*
X59625Y643227D03*
X67375D03*
X67000Y1058250D03*
X63125Y1050750D03*
X70875D03*
X63500Y1461750D03*
X59625Y1454250D03*
X67375D03*
X101300Y1860650D03*
X97425Y1853150D03*
X105175D03*
X73100Y1867150D03*
X69225Y1859650D03*
X76975D03*
X136500Y156250D03*
X132625Y148750D03*
X140375D03*
X144525Y412850D03*
X152275D03*
X148400Y420350D03*
X121625Y556250D03*
X129375D03*
X125500Y563750D03*
X148400Y825850D03*
X144525Y818350D03*
X152275D03*
X151500Y971250D03*
X147625Y963750D03*
X155375D03*
X148700Y1231350D03*
X144825Y1223850D03*
X152575D03*
X140500Y1371785D03*
X136625Y1364285D03*
X144375D03*
X149900Y1636850D03*
X146025Y1629350D03*
X153775D03*
X197000Y46250D03*
X193125Y38750D03*
X200875D03*
X876161Y163411D03*
X880036Y155911D03*
X872286D03*
X869000Y547215D03*
X872875Y539715D03*
X865125D03*
X878375Y555715D03*
X870625D03*
X874500Y563215D03*
X869000Y952727D03*
X872875Y945227D03*
X865125D03*
X874500Y968727D03*
X878375Y961227D03*
X870625D03*
X869000Y1358238D03*
X872875Y1350738D03*
X865125D03*
X874500Y1374238D03*
X878375Y1366738D03*
X870625D03*
X869000Y1763750D03*
X865125Y1756250D03*
X872875D03*
X874500Y1779750D03*
X870625Y1772250D03*
X878375D03*
G54D13*
X23426Y281496D03*
X24764Y286496D03*
X28426Y290197D03*
X38465D03*
X42166Y286496D03*
X11615Y1922835D03*
X12953Y1927835D03*
X16615Y1931536D03*
X26654D03*
X30355Y1927835D03*
X31693Y1922835D03*
X43504Y281496D03*
X123819Y17717D03*
X125157Y22717D03*
X128819Y26418D03*
X138858D03*
X142559Y22717D03*
X143897Y17717D03*
X265552Y279528D03*
X266890Y284528D03*
X270552Y288229D03*
X280591D03*
X284292Y284528D03*
X285630Y279528D03*
X265552Y685030D03*
X266890Y690030D03*
X270552Y693731D03*
X280591D03*
X284292Y690030D03*
X285630Y685030D03*
X265552Y1088573D03*
X266890Y1093573D03*
X270552Y1097274D03*
X280591D03*
X284292Y1093573D03*
X285630Y1088573D03*
X265552Y1903534D03*
X266890Y1908534D03*
X270552Y1912235D03*
X280591D03*
X284292Y1908534D03*
X285630Y1903534D03*
X987992Y163376D03*
Y686998D03*
Y1082667D03*
Y1903534D03*
X989330Y168376D03*
X992992Y172077D03*
X1003031D03*
X1006732Y168376D03*
X1008070Y163376D03*
X989330Y691998D03*
X992992Y695699D03*
X1003031D03*
X1006732Y691998D03*
X1008070Y686998D03*
X989330Y1087667D03*
X992992Y1091368D03*
X1003031D03*
X1006732Y1087667D03*
X1008070Y1082667D03*
X989330Y1908534D03*
X992992Y1912235D03*
X1003031D03*
X1006732Y1908534D03*
X1008070Y1903534D03*
G54D50*
X107750Y373900D03*
X100250Y377775D03*
Y370025D03*
Y775525D03*
X107750Y779400D03*
X100250Y783275D03*
X107750Y1184900D03*
X100250Y1188775D03*
Y1181025D03*
X109125Y1588650D03*
Y1580900D03*
X97125Y1584775D03*
X89625Y1588650D03*
Y1580900D03*
X74450Y1965200D03*
X66950Y1969075D03*
Y1961325D03*
X55350Y1965300D03*
X47850Y1969175D03*
Y1961425D03*
X127250Y373900D03*
X119750Y377775D03*
Y370025D03*
Y775525D03*
X127250Y779400D03*
X119750Y783275D03*
X127250Y1184900D03*
X119750Y1188775D03*
Y1181025D03*
X116625Y1584775D03*
X834250Y373900D03*
X826750Y370025D03*
Y377775D03*
Y775525D03*
X834250Y779400D03*
X826750Y783275D03*
X834250Y1184900D03*
X826750Y1181025D03*
Y1188775D03*
X834250Y1590400D03*
X826750Y1586525D03*
Y1594275D03*
X782489Y1964407D03*
X774989Y1960532D03*
Y1968282D03*
X801989Y1964407D03*
X794489Y1960532D03*
Y1968282D03*
X876750Y145000D03*
X869250Y141125D03*
Y148875D03*
X853750Y373900D03*
X846250Y370025D03*
Y377775D03*
Y775525D03*
X853750Y779400D03*
X846250Y783275D03*
X853750Y1184900D03*
X846250Y1181025D03*
Y1188775D03*
X853750Y1590400D03*
X846250Y1586525D03*
Y1594275D03*
G54D14*
X8858Y629693D03*
Y626544D03*
Y623394D03*
Y620245D03*
Y617095D03*
Y613945D03*
Y610796D03*
Y607646D03*
Y604496D03*
Y601347D03*
Y598197D03*
Y702134D03*
Y698985D03*
Y695835D03*
Y692685D03*
Y689536D03*
Y686386D03*
Y683237D03*
Y680087D03*
Y676937D03*
Y673788D03*
Y670638D03*
Y667489D03*
Y664339D03*
Y661189D03*
Y658040D03*
Y654890D03*
Y651741D03*
Y648591D03*
Y645441D03*
Y642292D03*
Y639142D03*
Y635993D03*
Y632843D03*
Y774575D03*
Y771426D03*
Y768276D03*
Y765126D03*
Y761977D03*
Y758827D03*
Y755678D03*
Y752528D03*
Y749378D03*
Y733630D03*
Y730481D03*
Y727331D03*
Y724182D03*
Y721032D03*
Y717882D03*
Y714733D03*
Y711583D03*
Y708433D03*
Y705284D03*
Y847016D03*
Y843867D03*
Y840717D03*
Y837567D03*
Y834418D03*
Y831268D03*
Y828119D03*
Y824969D03*
Y821819D03*
Y818670D03*
Y815520D03*
Y812371D03*
Y809221D03*
Y806071D03*
Y802922D03*
Y799772D03*
Y796622D03*
Y793473D03*
Y790323D03*
Y787174D03*
Y784024D03*
Y780874D03*
Y777725D03*
Y919457D03*
Y916308D03*
Y913158D03*
Y910008D03*
Y906859D03*
Y903709D03*
Y900559D03*
Y897410D03*
Y894260D03*
Y891111D03*
Y887961D03*
Y884811D03*
Y881662D03*
Y878512D03*
Y875363D03*
Y872213D03*
Y869063D03*
Y865914D03*
Y862764D03*
Y859615D03*
Y856465D03*
Y853315D03*
Y850166D03*
Y922607D03*
Y1138355D03*
Y1135205D03*
Y1132056D03*
Y1128906D03*
Y1125756D03*
Y1122607D03*
Y1119457D03*
Y1116308D03*
Y1113158D03*
Y1110008D03*
Y1106859D03*
Y1103709D03*
Y1100559D03*
Y1097410D03*
Y1094260D03*
Y1210796D03*
Y1207646D03*
Y1204496D03*
Y1201347D03*
Y1198197D03*
Y1195048D03*
Y1191898D03*
Y1188748D03*
Y1185599D03*
Y1182449D03*
Y1179300D03*
Y1176150D03*
Y1173000D03*
Y1169851D03*
Y1166701D03*
Y1163552D03*
Y1160402D03*
Y1157252D03*
Y1154103D03*
Y1150953D03*
Y1147804D03*
Y1144654D03*
Y1141504D03*
Y1283237D03*
Y1280087D03*
Y1276937D03*
Y1273788D03*
Y1270638D03*
Y1267489D03*
Y1264339D03*
Y1261189D03*
Y1258040D03*
Y1254890D03*
Y1251741D03*
Y1248591D03*
Y1245441D03*
Y1229693D03*
Y1226544D03*
Y1223394D03*
Y1220245D03*
Y1217095D03*
Y1213945D03*
Y1355678D03*
Y1352528D03*
Y1349378D03*
Y1346229D03*
Y1343079D03*
Y1339930D03*
Y1336780D03*
Y1333630D03*
Y1330481D03*
Y1327331D03*
Y1324182D03*
Y1321032D03*
Y1317882D03*
Y1314733D03*
Y1311583D03*
Y1308434D03*
Y1305284D03*
Y1302134D03*
Y1298985D03*
Y1295835D03*
Y1292685D03*
Y1289536D03*
Y1286386D03*
Y1418670D03*
Y1415520D03*
Y1412371D03*
Y1409221D03*
Y1406071D03*
Y1402922D03*
Y1399772D03*
Y1396622D03*
Y1393473D03*
Y1390323D03*
Y1387174D03*
Y1384024D03*
Y1380874D03*
Y1377725D03*
Y1374575D03*
Y1371426D03*
Y1368276D03*
Y1365126D03*
Y1361977D03*
Y1358827D03*
Y1574574D03*
Y1571425D03*
Y1568275D03*
Y1565126D03*
Y1561976D03*
Y1558826D03*
Y1555677D03*
Y1552527D03*
Y1549378D03*
Y1546228D03*
Y1543078D03*
Y1539929D03*
Y1536779D03*
Y1533630D03*
Y1530480D03*
Y1527330D03*
Y1524181D03*
Y1521031D03*
Y1517881D03*
Y1514732D03*
Y1511582D03*
Y1647015D03*
Y1643866D03*
Y1640716D03*
Y1637567D03*
Y1634417D03*
Y1631267D03*
Y1628118D03*
Y1624968D03*
Y1621818D03*
Y1618669D03*
Y1615519D03*
Y1612370D03*
Y1609220D03*
Y1606070D03*
Y1602921D03*
Y1599771D03*
Y1596622D03*
Y1593472D03*
Y1590322D03*
Y1587173D03*
Y1584023D03*
Y1580874D03*
Y1577724D03*
Y1719456D03*
Y1716307D03*
Y1713157D03*
Y1710007D03*
Y1706858D03*
Y1703708D03*
Y1700559D03*
Y1697409D03*
Y1694259D03*
Y1691110D03*
Y1687960D03*
Y1684811D03*
Y1681661D03*
Y1678511D03*
Y1675362D03*
Y1672212D03*
Y1669063D03*
Y1665913D03*
Y1662763D03*
Y1791897D03*
Y1788748D03*
Y1785598D03*
Y1782448D03*
Y1779299D03*
Y1776149D03*
Y1773000D03*
Y1769850D03*
Y1766700D03*
Y1763551D03*
Y1760401D03*
Y1757252D03*
Y1754102D03*
Y1750952D03*
Y1747803D03*
Y1744653D03*
Y1741504D03*
Y1738354D03*
Y1735204D03*
Y1732055D03*
Y1728905D03*
Y1725756D03*
Y1722606D03*
Y1835992D03*
Y1832842D03*
Y1829693D03*
Y1826543D03*
Y1823393D03*
Y1820244D03*
Y1817094D03*
Y1813944D03*
Y1810795D03*
Y1807645D03*
Y1804496D03*
Y1801346D03*
Y1798196D03*
Y1795047D03*
G54D32*
X89764Y41771D03*
Y44921D03*
Y48070D03*
Y51220D03*
Y54370D03*
Y57519D03*
Y60669D03*
Y63818D03*
Y66968D03*
Y70118D03*
Y73267D03*
Y76417D03*
Y79567D03*
Y82716D03*
Y85866D03*
Y89015D03*
Y92165D03*
Y95315D03*
Y98464D03*
Y101614D03*
Y104763D03*
Y107913D03*
Y111063D03*
Y114212D03*
Y117362D03*
Y120511D03*
X77205Y115787D03*
Y118937D03*
X89764Y123661D03*
Y126811D03*
Y129960D03*
Y133110D03*
Y136259D03*
Y139409D03*
Y142559D03*
Y145708D03*
Y148858D03*
Y152007D03*
Y155157D03*
Y158307D03*
Y161456D03*
Y164606D03*
X77205Y122086D03*
Y125236D03*
Y128385D03*
Y131535D03*
X89764Y447283D03*
Y450433D03*
Y453582D03*
Y456732D03*
Y459882D03*
Y463031D03*
Y466181D03*
Y469330D03*
Y472480D03*
Y475630D03*
Y478779D03*
Y481929D03*
Y485079D03*
Y488228D03*
Y491378D03*
Y494527D03*
Y497677D03*
Y500827D03*
Y503976D03*
Y507126D03*
Y510275D03*
Y513425D03*
Y516575D03*
Y519724D03*
Y522874D03*
Y526023D03*
Y529173D03*
Y532323D03*
Y535472D03*
Y538622D03*
Y541771D03*
Y544921D03*
Y548071D03*
Y551220D03*
Y554370D03*
Y557519D03*
X77205Y521299D03*
Y524449D03*
Y527598D03*
Y530748D03*
Y533897D03*
Y537047D03*
X89764Y560669D03*
Y563819D03*
Y566968D03*
Y570118D03*
Y852795D03*
Y855945D03*
Y859094D03*
Y862244D03*
Y865394D03*
Y868543D03*
Y871693D03*
Y874842D03*
Y877992D03*
Y881142D03*
Y884291D03*
Y887441D03*
Y890591D03*
Y893740D03*
Y896890D03*
Y900039D03*
Y903189D03*
Y906339D03*
Y909488D03*
Y912638D03*
Y915787D03*
Y918937D03*
Y922087D03*
Y925236D03*
Y928386D03*
Y931535D03*
Y934685D03*
Y937835D03*
Y940984D03*
Y944134D03*
Y947283D03*
Y950433D03*
Y953583D03*
Y956732D03*
Y959882D03*
Y963031D03*
Y966181D03*
Y969331D03*
Y972480D03*
Y975630D03*
X77205Y926811D03*
Y929961D03*
Y933110D03*
Y936260D03*
Y939409D03*
Y942559D03*
X89764Y1258307D03*
Y1261457D03*
Y1264606D03*
Y1267756D03*
Y1270906D03*
Y1274055D03*
Y1277205D03*
Y1280354D03*
Y1283504D03*
Y1286654D03*
Y1289803D03*
Y1292953D03*
Y1296103D03*
Y1299252D03*
Y1302402D03*
Y1305551D03*
Y1308701D03*
Y1311851D03*
Y1315000D03*
Y1318150D03*
Y1321299D03*
Y1324449D03*
Y1327599D03*
Y1330748D03*
Y1333898D03*
Y1337047D03*
Y1340197D03*
Y1343347D03*
Y1346496D03*
Y1349646D03*
Y1352795D03*
Y1355945D03*
X77205Y1332323D03*
Y1335473D03*
Y1338622D03*
Y1341772D03*
Y1344921D03*
Y1348071D03*
X89764Y1359095D03*
Y1362244D03*
Y1365394D03*
Y1368543D03*
Y1371693D03*
Y1374843D03*
Y1377992D03*
Y1381142D03*
Y1663819D03*
Y1666969D03*
Y1670118D03*
Y1673268D03*
Y1676418D03*
Y1679567D03*
Y1682717D03*
Y1685866D03*
Y1689016D03*
Y1692166D03*
Y1695315D03*
Y1698465D03*
Y1701615D03*
Y1704764D03*
Y1707914D03*
Y1711063D03*
Y1714213D03*
Y1717363D03*
Y1720512D03*
Y1723662D03*
Y1726811D03*
Y1729961D03*
Y1733111D03*
Y1736260D03*
Y1739410D03*
Y1742559D03*
Y1745709D03*
Y1748859D03*
Y1752008D03*
Y1755158D03*
Y1758307D03*
Y1761457D03*
Y1764607D03*
Y1767756D03*
Y1770906D03*
Y1774055D03*
Y1777205D03*
Y1780355D03*
Y1783504D03*
Y1786654D03*
X77205Y1737835D03*
Y1740985D03*
Y1744134D03*
Y1747284D03*
Y1750433D03*
Y1753583D03*
X154331Y265315D03*
Y262165D03*
Y259015D03*
Y255866D03*
Y252716D03*
Y249567D03*
Y246417D03*
Y243267D03*
Y240118D03*
Y236968D03*
Y233819D03*
Y230669D03*
Y227519D03*
Y224370D03*
Y221220D03*
Y218071D03*
Y214921D03*
Y211771D03*
Y208622D03*
Y205472D03*
X166890Y254291D03*
Y251141D03*
Y247992D03*
Y244842D03*
Y241693D03*
Y238543D03*
X154331Y328307D03*
Y325157D03*
Y322008D03*
Y318858D03*
Y315708D03*
Y312559D03*
Y309409D03*
Y306260D03*
Y303110D03*
Y299960D03*
Y296811D03*
Y293661D03*
Y290511D03*
Y287362D03*
Y284212D03*
Y281063D03*
Y277913D03*
Y274763D03*
Y271614D03*
Y268464D03*
Y629882D03*
Y626732D03*
Y623583D03*
Y620433D03*
Y617283D03*
Y614134D03*
Y610984D03*
Y702323D03*
Y699173D03*
Y696023D03*
Y692874D03*
Y689724D03*
Y686575D03*
Y683425D03*
Y680275D03*
Y677126D03*
Y673976D03*
Y670827D03*
Y667677D03*
Y664527D03*
Y661378D03*
Y658228D03*
Y655079D03*
Y651929D03*
Y648779D03*
Y645630D03*
Y642480D03*
Y639331D03*
Y636181D03*
Y633031D03*
X166890Y659803D03*
Y656653D03*
Y653504D03*
Y650354D03*
Y647205D03*
Y644055D03*
X154331Y733819D03*
Y730669D03*
Y727520D03*
Y724370D03*
Y721220D03*
Y718071D03*
Y714921D03*
Y711772D03*
Y708622D03*
Y705472D03*
Y1063740D03*
Y1060591D03*
Y1057441D03*
Y1054291D03*
Y1051142D03*
Y1047992D03*
Y1044843D03*
Y1041693D03*
Y1038543D03*
Y1035394D03*
Y1032244D03*
Y1029095D03*
Y1025945D03*
Y1022795D03*
Y1019646D03*
Y1016496D03*
X166890Y1065315D03*
Y1062165D03*
Y1059016D03*
Y1055866D03*
Y1052717D03*
Y1049567D03*
X154331Y1139331D03*
Y1136181D03*
Y1133032D03*
Y1129882D03*
Y1126732D03*
Y1123583D03*
Y1120433D03*
Y1117284D03*
Y1114134D03*
Y1110984D03*
Y1107835D03*
Y1104685D03*
Y1101535D03*
Y1098386D03*
Y1095236D03*
Y1092087D03*
Y1088937D03*
Y1085787D03*
Y1082638D03*
Y1079488D03*
Y1076339D03*
Y1073189D03*
Y1070039D03*
Y1066890D03*
Y1428307D03*
Y1425158D03*
Y1422008D03*
Y1500748D03*
Y1497599D03*
Y1494449D03*
Y1491299D03*
Y1488150D03*
Y1485000D03*
Y1481851D03*
Y1478701D03*
Y1475551D03*
Y1472402D03*
Y1469252D03*
Y1466103D03*
Y1462953D03*
Y1459803D03*
Y1456654D03*
Y1453504D03*
Y1450355D03*
Y1447205D03*
Y1444055D03*
Y1440906D03*
Y1437756D03*
Y1434607D03*
Y1431457D03*
X166890Y1470827D03*
Y1467677D03*
Y1464528D03*
Y1461378D03*
Y1458229D03*
Y1455079D03*
X154331Y1544843D03*
Y1541693D03*
Y1538544D03*
Y1535394D03*
Y1532244D03*
Y1529095D03*
Y1525945D03*
Y1522796D03*
Y1519646D03*
Y1516496D03*
Y1513347D03*
Y1510197D03*
Y1507047D03*
Y1503898D03*
Y1865315D03*
Y1862166D03*
Y1859016D03*
Y1855867D03*
Y1852717D03*
Y1849567D03*
Y1846418D03*
Y1843268D03*
Y1840119D03*
Y1836969D03*
Y1833819D03*
Y1830670D03*
Y1827520D03*
X166890Y1866890D03*
Y1863741D03*
Y1860591D03*
X154331Y1937756D03*
Y1934607D03*
Y1931457D03*
Y1928308D03*
Y1925158D03*
Y1922008D03*
Y1918859D03*
Y1915709D03*
Y1912559D03*
Y1909410D03*
Y1906260D03*
Y1903111D03*
Y1899961D03*
Y1896811D03*
Y1893662D03*
Y1890512D03*
Y1887363D03*
Y1884213D03*
Y1881063D03*
Y1877914D03*
Y1874764D03*
Y1871615D03*
Y1868465D03*
X166890Y1876339D03*
Y1873189D03*
Y1870040D03*
X154331Y1950355D03*
Y1947205D03*
Y1944056D03*
Y1940906D03*
X882677Y265315D03*
Y262165D03*
Y259015D03*
Y255866D03*
Y252716D03*
Y249567D03*
Y246417D03*
Y243267D03*
Y240118D03*
Y236968D03*
Y233819D03*
Y230669D03*
Y227519D03*
Y224370D03*
Y221220D03*
Y218071D03*
Y214921D03*
Y211771D03*
Y208622D03*
Y205472D03*
X895236Y254291D03*
Y251141D03*
Y247992D03*
Y244842D03*
Y241693D03*
Y238543D03*
X882677Y328307D03*
Y325157D03*
Y322008D03*
Y318858D03*
Y315708D03*
Y312559D03*
Y309409D03*
Y306260D03*
Y303110D03*
Y299960D03*
Y296811D03*
Y293661D03*
Y290511D03*
Y287362D03*
Y284212D03*
Y281063D03*
Y277913D03*
Y274763D03*
Y271614D03*
Y268464D03*
Y629882D03*
Y626732D03*
Y623583D03*
Y620433D03*
Y617283D03*
Y614134D03*
Y610984D03*
Y702323D03*
Y699173D03*
Y696023D03*
Y692874D03*
Y689724D03*
Y686575D03*
Y683425D03*
Y680275D03*
Y677126D03*
Y673976D03*
Y670827D03*
Y667677D03*
Y664527D03*
Y661378D03*
Y658228D03*
Y655079D03*
Y651929D03*
Y648779D03*
Y645630D03*
Y642480D03*
Y639331D03*
Y636181D03*
Y633031D03*
X895236Y659803D03*
Y656653D03*
Y653504D03*
Y650354D03*
Y647205D03*
Y644055D03*
X882677Y733819D03*
Y730669D03*
Y727520D03*
Y724370D03*
Y721220D03*
Y718071D03*
Y714921D03*
Y711772D03*
Y708622D03*
Y705472D03*
Y1063740D03*
Y1060591D03*
Y1057441D03*
Y1054291D03*
Y1051142D03*
Y1047992D03*
Y1044843D03*
Y1041693D03*
Y1038543D03*
Y1035394D03*
Y1032244D03*
Y1029095D03*
Y1025945D03*
Y1022795D03*
Y1019646D03*
Y1016496D03*
X895236Y1065315D03*
Y1062165D03*
Y1059016D03*
Y1055866D03*
Y1052717D03*
Y1049567D03*
X882677Y1139331D03*
Y1136181D03*
Y1133032D03*
Y1129882D03*
Y1126732D03*
Y1123583D03*
Y1120433D03*
Y1117284D03*
Y1114134D03*
Y1110984D03*
Y1107835D03*
Y1104685D03*
Y1101535D03*
Y1098386D03*
Y1095236D03*
Y1092087D03*
Y1088937D03*
Y1085787D03*
Y1082638D03*
Y1079488D03*
Y1076339D03*
Y1073189D03*
Y1070039D03*
Y1066890D03*
Y1428307D03*
Y1425158D03*
Y1422008D03*
Y1500748D03*
Y1497599D03*
Y1494449D03*
Y1491299D03*
Y1488150D03*
Y1485000D03*
Y1481851D03*
Y1478701D03*
Y1475551D03*
Y1472402D03*
Y1469252D03*
Y1466103D03*
Y1462953D03*
Y1459803D03*
Y1456654D03*
Y1453504D03*
Y1450355D03*
Y1447205D03*
Y1444055D03*
Y1440906D03*
Y1437756D03*
Y1434607D03*
Y1431457D03*
X895236Y1470827D03*
Y1467677D03*
Y1464528D03*
Y1461378D03*
Y1458229D03*
Y1455079D03*
X882677Y1544843D03*
Y1541693D03*
Y1538544D03*
Y1535394D03*
Y1532244D03*
Y1529095D03*
Y1525945D03*
Y1522796D03*
Y1519646D03*
Y1516496D03*
Y1513347D03*
Y1510197D03*
Y1507047D03*
Y1503898D03*
Y1865315D03*
Y1862166D03*
Y1859016D03*
Y1855867D03*
Y1852717D03*
Y1849567D03*
Y1846418D03*
Y1843268D03*
Y1840119D03*
Y1836969D03*
Y1833819D03*
Y1830670D03*
Y1827520D03*
X895236Y1866890D03*
Y1863741D03*
Y1860591D03*
X882677Y1937756D03*
Y1934607D03*
Y1931457D03*
Y1928308D03*
Y1925158D03*
Y1922008D03*
Y1918859D03*
Y1915709D03*
Y1912559D03*
Y1909410D03*
Y1906260D03*
Y1903111D03*
Y1899961D03*
Y1896811D03*
Y1893662D03*
Y1890512D03*
Y1887363D03*
Y1884213D03*
Y1881063D03*
Y1877914D03*
Y1874764D03*
Y1871615D03*
Y1868465D03*
X895236Y1876339D03*
Y1873189D03*
Y1870040D03*
X882677Y1950355D03*
Y1947205D03*
Y1944056D03*
Y1940906D03*
G54D23*
X32600Y1823200D03*
Y1819700D03*
X151700Y569500D03*
X344700Y352500D03*
X380200D03*
X352700D03*
X388200D03*
X373700Y782500D03*
X381700D03*
X388200Y806500D03*
X380200Y1154000D03*
X388200D03*
X344700Y1652500D03*
X352700D03*
X385200Y1676500D03*
X386200Y1723500D03*
X914700Y1719000D03*
G54D41*
X92800Y210000D03*
X77300Y253465D03*
X92800Y214465D03*
X78550Y239715D03*
X92800Y201000D03*
Y205500D03*
X96000Y349000D03*
X92800Y615500D03*
Y619977D03*
Y611000D03*
X77300Y658977D03*
X78550Y645227D03*
X96000Y754500D03*
X92800Y1021000D03*
X77300Y1064488D03*
X92800Y1025488D03*
Y1016500D03*
X96000Y1160400D03*
X92800Y1426500D03*
Y1417500D03*
Y1422000D03*
X77300Y1470000D03*
X92800Y1431000D03*
X95300Y1556500D03*
X109100Y1548200D03*
X93800Y1830000D03*
X101900Y1839900D03*
X93800Y1821500D03*
X68275Y1823331D03*
X70110Y1837270D03*
X93787Y1825915D03*
X65800Y1940500D03*
X177954Y147453D03*
X132675Y162475D03*
X167656Y168811D03*
X124800Y321000D03*
Y326000D03*
X154750Y397350D03*
X181800Y531000D03*
Y527000D03*
X124800Y726500D03*
Y731500D03*
X176800Y963500D03*
X157046Y976999D03*
X124800Y1132000D03*
Y1137000D03*
X155125Y1208725D03*
X177954Y1362488D03*
X136675Y1378010D03*
X167674Y1385323D03*
X124800Y1537500D03*
Y1542500D03*
X155125Y1614225D03*
X181646Y1774500D03*
X167492Y1790692D03*
X123100Y1934100D03*
Y1939100D03*
X205625Y23725D03*
X192300Y167000D03*
Y158000D03*
Y162500D03*
X191800Y573500D03*
X209300Y569000D03*
X191800Y564500D03*
Y569000D03*
X192300Y978500D03*
X203900Y960977D03*
X192300Y969500D03*
X203900Y965477D03*
X192300Y974000D03*
X186800Y1382000D03*
Y1373000D03*
Y1377500D03*
X191300Y1790500D03*
X216000Y1772100D03*
X244900Y1769900D03*
X191300Y1781500D03*
X216000Y1776200D03*
X191300Y1786000D03*
X324800Y413000D03*
X329300Y570580D03*
Y578600D03*
X325800Y605000D03*
Y593000D03*
X320300Y572500D03*
Y576500D03*
X325800Y601000D03*
X324800Y843000D03*
Y1214500D03*
X276800Y1407500D03*
X319800Y1429700D03*
Y1417500D03*
Y1425700D03*
Y1405400D03*
Y1413500D03*
Y1437700D03*
X324800Y1713000D03*
X276800Y1722000D03*
X363800Y68500D03*
X344800Y341000D03*
X380300D03*
X334800Y393000D03*
X330800Y373000D03*
X352800Y341000D03*
X388300D03*
X373800Y771000D03*
X381800D03*
X334800Y823000D03*
X330800Y803000D03*
X397300Y840500D03*
X380300Y1142500D03*
X330800Y1174500D03*
X334800Y1194500D03*
X398800Y1192000D03*
X388300Y1142500D03*
X344800Y1641000D03*
X352800D03*
X330800Y1673000D03*
X334800Y1695000D03*
X421300Y817500D03*
Y809500D03*
Y1212000D03*
Y1220000D03*
Y1718500D03*
Y1710500D03*
X824300Y349000D03*
Y754500D03*
Y1160000D03*
Y1565500D03*
X789139Y1939507D03*
X907300Y146453D03*
X852800Y321000D03*
Y326000D03*
X906300Y551965D03*
X895976Y574422D03*
X852800Y726500D03*
Y731500D03*
X906300Y957477D03*
X852800Y1132000D03*
Y1137000D03*
X906300Y1362988D03*
X852800Y1537500D03*
Y1542500D03*
X911800Y1695000D03*
Y1703000D03*
X906300Y1768500D03*
X895492Y1790816D03*
X851800Y1935800D03*
X847900Y1949700D03*
X851800Y1940800D03*
X919800Y164453D03*
Y155500D03*
Y160000D03*
Y569965D03*
Y561000D03*
Y565500D03*
Y975477D03*
Y966500D03*
Y971000D03*
Y1380988D03*
Y1372000D03*
Y1376500D03*
Y1786500D03*
Y1777500D03*
Y1782000D03*
G54D60*
X87200Y1960400D03*
Y1968000D03*
X129725Y1581125D03*
Y1588725D03*
X388000Y1728700D03*
Y1736300D03*
X835500Y1700200D03*
Y1707800D03*
X827500D03*
Y1700200D03*
X835500Y1734800D03*
Y1727200D03*
X827500D03*
Y1734800D03*
X815339Y1959407D03*
Y1967007D03*
X884500Y1730800D03*
Y1723200D03*
G54D51*
X105025Y401025D03*
X97425D03*
X105200Y805700D03*
X97600D03*
X105100Y1211800D03*
X97500D03*
X105000Y1616700D03*
X97400D03*
X160400Y36600D03*
X152800D03*
X139000Y375300D03*
X146600D03*
X139100Y780600D03*
X146700D03*
X137700Y1185900D03*
X145300D03*
X315200Y422600D03*
X307600D03*
X315500Y853100D03*
X307900D03*
X314800Y1224000D03*
X307200D03*
X315300Y1722100D03*
X307700D03*
X398700Y420500D03*
Y850500D03*
X400700Y1232500D03*
X406300Y420500D03*
Y850500D03*
X408300Y1232500D03*
X866800Y376400D03*
X874400D03*
X866300Y781900D03*
X873900D03*
X866300Y1187400D03*
X873900D03*
X866300Y1594400D03*
X873900D03*
G54D33*
X78839Y41161D03*
Y46161D03*
Y51161D03*
Y56161D03*
Y61161D03*
Y66161D03*
Y71161D03*
Y76161D03*
Y81161D03*
Y86161D03*
Y91161D03*
Y96161D03*
Y101161D03*
Y106161D03*
Y111161D03*
Y136161D03*
Y141161D03*
Y146161D03*
Y151161D03*
Y156161D03*
Y161161D03*
Y166161D03*
Y446673D03*
Y451673D03*
Y456673D03*
Y461673D03*
Y466673D03*
Y471673D03*
Y476673D03*
Y481673D03*
Y486673D03*
Y491673D03*
Y496673D03*
Y501673D03*
Y506673D03*
Y511673D03*
Y516673D03*
Y541673D03*
Y546673D03*
Y551673D03*
Y556673D03*
Y561673D03*
Y566673D03*
Y571673D03*
Y852185D03*
Y857185D03*
Y862185D03*
Y867185D03*
Y872185D03*
Y877185D03*
Y882185D03*
Y887185D03*
Y892185D03*
Y897185D03*
Y902185D03*
Y907185D03*
Y912185D03*
Y917185D03*
Y922185D03*
Y947185D03*
Y952185D03*
Y957185D03*
Y962185D03*
Y967185D03*
Y972185D03*
Y977185D03*
Y1257697D03*
Y1262697D03*
Y1267697D03*
Y1272697D03*
Y1277697D03*
Y1282697D03*
Y1287697D03*
Y1292697D03*
Y1297697D03*
Y1302697D03*
Y1307697D03*
Y1312697D03*
Y1317697D03*
Y1322697D03*
Y1327697D03*
Y1352697D03*
Y1357697D03*
Y1362697D03*
Y1367697D03*
Y1372697D03*
Y1377697D03*
Y1382697D03*
Y1663209D03*
Y1668209D03*
Y1673209D03*
Y1678209D03*
Y1683209D03*
Y1688209D03*
Y1693209D03*
Y1698209D03*
Y1703209D03*
Y1708209D03*
Y1713209D03*
Y1718209D03*
Y1723209D03*
Y1728209D03*
Y1733209D03*
Y1758209D03*
Y1763209D03*
Y1768209D03*
Y1773209D03*
Y1778209D03*
Y1783209D03*
Y1788209D03*
X165256Y263917D03*
Y258917D03*
Y233917D03*
Y228917D03*
Y223917D03*
Y218917D03*
Y213917D03*
Y208917D03*
Y203917D03*
Y328917D03*
Y323917D03*
Y318917D03*
Y313917D03*
Y308917D03*
Y303917D03*
Y298917D03*
Y293917D03*
Y288917D03*
Y283917D03*
Y278917D03*
Y273917D03*
Y268917D03*
Y629429D03*
Y624429D03*
Y619429D03*
Y614429D03*
Y609429D03*
Y699429D03*
Y694429D03*
Y689429D03*
Y684429D03*
Y679429D03*
Y674429D03*
Y669429D03*
Y664429D03*
Y639429D03*
Y634429D03*
Y734429D03*
Y729429D03*
Y724429D03*
Y719429D03*
Y714429D03*
Y709429D03*
Y704429D03*
Y1044941D03*
Y1039941D03*
Y1034941D03*
Y1029941D03*
Y1024941D03*
Y1019941D03*
Y1014941D03*
Y1134941D03*
Y1129941D03*
Y1124941D03*
Y1119941D03*
Y1114941D03*
Y1109941D03*
Y1104941D03*
Y1099941D03*
Y1094941D03*
Y1089941D03*
Y1084941D03*
Y1079941D03*
Y1074941D03*
Y1069941D03*
Y1139941D03*
Y1430453D03*
Y1425453D03*
Y1420453D03*
Y1500453D03*
Y1495453D03*
Y1490453D03*
Y1485453D03*
Y1480453D03*
Y1475453D03*
Y1450453D03*
Y1445453D03*
Y1440453D03*
Y1435453D03*
Y1545453D03*
Y1540453D03*
Y1535453D03*
Y1530453D03*
Y1525453D03*
Y1520453D03*
Y1515453D03*
Y1510453D03*
Y1505453D03*
Y1855965D03*
Y1850965D03*
Y1845965D03*
Y1840965D03*
Y1835965D03*
Y1830965D03*
Y1825965D03*
Y1935965D03*
Y1930965D03*
Y1925965D03*
Y1920965D03*
Y1915965D03*
Y1910965D03*
Y1905965D03*
Y1900965D03*
Y1895965D03*
Y1890965D03*
Y1885965D03*
Y1880965D03*
Y1950965D03*
Y1945965D03*
Y1940965D03*
X893602Y263917D03*
Y258917D03*
Y233917D03*
Y228917D03*
Y223917D03*
Y218917D03*
Y213917D03*
Y208917D03*
Y203917D03*
Y328917D03*
Y323917D03*
Y318917D03*
Y313917D03*
Y308917D03*
Y303917D03*
Y298917D03*
Y293917D03*
Y288917D03*
Y283917D03*
Y278917D03*
Y273917D03*
Y268917D03*
Y629429D03*
Y624429D03*
Y619429D03*
Y614429D03*
Y609429D03*
Y699429D03*
Y694429D03*
Y689429D03*
Y684429D03*
Y679429D03*
Y674429D03*
Y669429D03*
Y664429D03*
Y639429D03*
Y634429D03*
Y734429D03*
Y729429D03*
Y724429D03*
Y719429D03*
Y714429D03*
Y709429D03*
Y704429D03*
Y1044941D03*
Y1039941D03*
Y1034941D03*
Y1029941D03*
Y1024941D03*
Y1019941D03*
Y1014941D03*
Y1134941D03*
Y1129941D03*
Y1124941D03*
Y1119941D03*
Y1114941D03*
Y1109941D03*
Y1104941D03*
Y1099941D03*
Y1094941D03*
Y1089941D03*
Y1084941D03*
Y1079941D03*
Y1074941D03*
Y1069941D03*
Y1139941D03*
Y1430453D03*
Y1425453D03*
Y1420453D03*
Y1500453D03*
Y1495453D03*
Y1490453D03*
Y1485453D03*
Y1480453D03*
Y1475453D03*
Y1450453D03*
Y1445453D03*
Y1440453D03*
Y1435453D03*
Y1545453D03*
Y1540453D03*
Y1535453D03*
Y1530453D03*
Y1525453D03*
Y1520453D03*
Y1515453D03*
Y1510453D03*
Y1505453D03*
Y1855965D03*
Y1850965D03*
Y1845965D03*
Y1840965D03*
Y1835965D03*
Y1830965D03*
Y1825965D03*
Y1935965D03*
Y1930965D03*
Y1925965D03*
Y1920965D03*
Y1915965D03*
Y1910965D03*
Y1905965D03*
Y1900965D03*
Y1895965D03*
Y1890965D03*
Y1885965D03*
Y1880965D03*
Y1950965D03*
Y1945965D03*
Y1940965D03*
G54D42*
X96200Y210000D03*
X80700Y253465D03*
X96200Y214465D03*
X81950Y239715D03*
X96200Y201000D03*
Y205500D03*
X99400Y349000D03*
X96200Y615500D03*
Y619977D03*
Y611000D03*
X80700Y658977D03*
X81950Y645227D03*
X99400Y754500D03*
X96200Y1021000D03*
X80700Y1064488D03*
X96200Y1025488D03*
Y1016500D03*
X99400Y1160400D03*
X96200Y1426500D03*
Y1417500D03*
Y1422000D03*
X80700Y1470000D03*
X96200Y1431000D03*
X98700Y1556500D03*
X97200Y1830000D03*
X105300Y1839900D03*
X97200Y1821500D03*
X71675Y1823331D03*
X73510Y1837270D03*
X97187Y1825915D03*
X69200Y1940500D03*
X181354Y147453D03*
X136075Y162475D03*
X171056Y168811D03*
X128200Y321000D03*
Y326000D03*
X158150Y397350D03*
X128200Y726500D03*
Y731500D03*
X180200Y963500D03*
X160446Y976999D03*
X128200Y1132000D03*
Y1137000D03*
X158525Y1208725D03*
X181354Y1362488D03*
X140075Y1378010D03*
X171074Y1385323D03*
X128200Y1537500D03*
Y1542500D03*
X112500Y1548200D03*
X158525Y1614225D03*
X170892Y1790692D03*
X126500Y1934100D03*
Y1939100D03*
X209025Y23725D03*
X195700Y167000D03*
Y158000D03*
Y162500D03*
X185200Y531000D03*
Y527000D03*
X195200Y573500D03*
X212700Y569000D03*
X195200Y564500D03*
Y569000D03*
X195700Y978500D03*
X207300Y960977D03*
X195700Y969500D03*
X207300Y965477D03*
X195700Y974000D03*
X190200Y1382000D03*
Y1373000D03*
Y1377500D03*
X194700Y1790500D03*
X185046Y1774500D03*
X219400Y1772100D03*
X248300Y1769900D03*
X194700Y1781500D03*
X219400Y1776200D03*
X194700Y1786000D03*
X328200Y413000D03*
X329200Y605000D03*
Y593000D03*
X323700Y572500D03*
Y576500D03*
X329200Y601000D03*
X328200Y843000D03*
Y1214500D03*
X280200Y1407500D03*
X323200Y1429700D03*
Y1417500D03*
Y1425700D03*
Y1405400D03*
Y1413500D03*
Y1437700D03*
X328200Y1713000D03*
X280200Y1722000D03*
X367200Y68500D03*
X348200Y341000D03*
X383700D03*
X338200Y393000D03*
X334200Y373000D03*
X356200Y341000D03*
X391700D03*
X332700Y570580D03*
Y578600D03*
X377200Y771000D03*
X385200D03*
X338200Y823000D03*
X334200Y803000D03*
X400700Y840500D03*
X383700Y1142500D03*
X334200Y1174500D03*
X338200Y1194500D03*
X402200Y1192000D03*
X391700Y1142500D03*
X348200Y1641000D03*
X356200D03*
X334200Y1673000D03*
X338200Y1695000D03*
X424700Y817500D03*
Y809500D03*
Y1212000D03*
Y1220000D03*
Y1718500D03*
Y1710500D03*
X827700Y349000D03*
Y754500D03*
Y1160000D03*
Y1565500D03*
X792539Y1939507D03*
X910700Y146453D03*
X856200Y321000D03*
Y326000D03*
X909700Y551965D03*
X899376Y574422D03*
X856200Y726500D03*
Y731500D03*
X909700Y957477D03*
X856200Y1132000D03*
Y1137000D03*
X909700Y1362988D03*
X856200Y1537500D03*
Y1542500D03*
X909700Y1768500D03*
X898892Y1790816D03*
X855200Y1935800D03*
X851300Y1949700D03*
X855200Y1940800D03*
X923200Y164453D03*
Y155500D03*
Y160000D03*
Y569965D03*
Y561000D03*
Y565500D03*
Y975477D03*
Y966500D03*
Y971000D03*
Y1380988D03*
Y1372000D03*
Y1376500D03*
X915200Y1695000D03*
Y1703000D03*
X923200Y1786500D03*
Y1777500D03*
Y1782000D03*
G54D24*
X36200Y1823200D03*
Y1819700D03*
X155300Y569500D03*
X348300Y352500D03*
X383800D03*
X356300D03*
X391800D03*
X377300Y782500D03*
X385300D03*
X391800Y806500D03*
X383800Y1154000D03*
X391800D03*
X348300Y1652500D03*
X356300D03*
X388800Y1676500D03*
X389800Y1723500D03*
X918300Y1719000D03*
G54D15*
X39086Y650614D03*
X37657Y1125065D03*
X38925Y1589682D03*
X37500Y1581000D03*
X38800Y1810100D03*
X22100Y1802800D03*
X38317Y1804491D03*
X34900Y1807200D03*
X35100Y1813000D03*
X26500Y1805200D03*
X26600Y1810600D03*
X26300Y1815000D03*
X30800Y1805300D03*
Y1810500D03*
X17500Y1801900D03*
X22000Y1814100D03*
Y1809100D03*
X17500Y1806900D03*
Y1811900D03*
Y1816500D03*
X7600Y1855000D03*
X17500Y1827500D03*
X22600Y1825200D03*
X17500Y1832500D03*
X22500Y1830000D03*
X17500Y1837500D03*
X22500Y1835000D03*
X17500Y1842500D03*
X22500Y1840000D03*
X17500Y1847500D03*
X22500Y1845000D03*
X17500Y1852500D03*
X22500Y1850000D03*
X17500Y1857500D03*
X22500Y1855000D03*
Y1865000D03*
X17500Y1867500D03*
X22500Y1860000D03*
X12500Y1845000D03*
Y1850000D03*
Y1855000D03*
Y1840000D03*
X17500Y1872500D03*
X22500Y1870000D03*
X12500D03*
X71200Y36900D03*
X98037Y14136D03*
X87500Y202000D03*
X74711Y246388D03*
X87589Y225909D03*
X56500Y216612D03*
X87600Y209868D03*
X111436Y260164D03*
X86000Y253465D03*
X72000D03*
X64734Y217647D03*
X59750Y223465D03*
X70819Y230822D03*
X97731Y234237D03*
X106782Y268794D03*
X80300Y397700D03*
X90800D03*
X85950Y341250D03*
X90700Y349600D03*
X110600Y396300D03*
X93825Y377775D03*
X65300Y396800D03*
X108000Y456012D03*
Y448512D03*
X86500Y608100D03*
X82962Y616638D03*
X64734Y623159D03*
X61523Y630374D03*
X74711Y651900D03*
X87589Y631421D03*
X86000Y658977D03*
X72000D03*
X70621Y636334D03*
X97731Y639749D03*
X41901Y716960D03*
X44576Y724360D03*
X85950Y746750D03*
X90700Y755100D03*
X81300Y803600D03*
X89800Y803500D03*
X43555Y776945D03*
X111200Y802054D03*
X93825Y783275D03*
X70150Y803150D03*
X108000Y861524D03*
Y854024D03*
X86000Y1014200D03*
X97812Y1066417D03*
X88000Y1037507D03*
X82962Y1022149D03*
X86000Y1064488D03*
X72000D03*
X64734Y1028670D03*
X64500Y1037500D03*
X70875Y1044000D03*
X97731Y1045260D03*
X41000Y1070000D03*
X42286Y1104286D03*
X41840Y1115552D03*
X45000Y1076500D03*
X83000Y1208600D03*
X90800D03*
X40097Y1154992D03*
X85950Y1152650D03*
X90700Y1161000D03*
X111000Y1207800D03*
X93825Y1188775D03*
X68150Y1208200D03*
X108000Y1267036D03*
Y1259536D03*
X87500Y1420500D03*
X82962Y1427661D03*
X82137Y1476495D03*
X104000Y1490500D03*
Y1498500D03*
X87589Y1442444D03*
X86000Y1470000D03*
X72000D03*
X64734Y1434182D03*
X62000Y1441800D03*
X70273Y1447357D03*
X97731Y1450772D03*
X85250Y1548750D03*
X90300Y1557100D03*
X42855Y1554900D03*
X39800Y1547400D03*
X78100Y1614500D03*
X86500Y1614700D03*
X47254Y1587961D03*
X51718Y1595562D03*
X111000Y1613200D03*
X103025Y1589654D03*
X83200Y1588650D03*
X63200Y1613300D03*
X108000Y1672548D03*
Y1665048D03*
X88100Y1825000D03*
X79500Y1841400D03*
X82964Y1831400D03*
X90749Y1860311D03*
X93200Y1867400D03*
X65100Y1838100D03*
X62900Y1826400D03*
X105350Y1846300D03*
X83467Y1862457D03*
X109100Y1936300D03*
X83911Y1886506D03*
X55750Y1932750D03*
X109500Y1947700D03*
X60500Y1941100D03*
X60600Y1970300D03*
X80600Y1964000D03*
X41700Y1969400D03*
X136100Y41200D03*
X130500Y45400D03*
X146000Y41900D03*
X180850Y22721D03*
X165700Y37800D03*
X113200Y59950D03*
X120700D03*
X112800Y49200D03*
X181387Y158953D03*
X175400Y152000D03*
X118832Y152559D03*
X141500Y140500D03*
X182582Y135000D03*
X158497Y163411D03*
X181404Y142546D03*
X155421Y142657D03*
X136795Y319578D03*
Y327078D03*
X120370Y331567D03*
X152300Y370400D03*
X164300Y377200D03*
X129975Y396346D03*
X113650Y378779D03*
X133100Y379700D03*
X149800Y397350D03*
X158150Y434350D03*
X153400Y426000D03*
X115800Y444600D03*
X141321Y541250D03*
X169000Y533500D03*
X176657Y531625D03*
X144750Y549500D03*
X181387Y564465D03*
X162300Y558100D03*
X135000Y570000D03*
X152500Y774500D03*
X136395Y725090D03*
Y732590D03*
X127500Y737100D03*
X153200Y783600D03*
X158150Y839850D03*
X153400Y831100D03*
X130350Y802221D03*
X113650Y784279D03*
X132900Y783900D03*
X150175Y803225D03*
X117000Y849400D03*
X183838Y968275D03*
X172705Y952750D03*
X171477Y965000D03*
X150000Y955000D03*
X161226Y971250D03*
X161512Y963755D03*
X135895Y1130602D03*
Y1138102D03*
X153400Y1189700D03*
X166100Y1189800D03*
X127500Y1142500D03*
X130350Y1207721D03*
X113650Y1189779D03*
X133100Y1191700D03*
X150175Y1208725D03*
X158450Y1245350D03*
X153700Y1237000D03*
X116300Y1255500D03*
X144375Y1357194D03*
X181404Y1357558D03*
X155000Y1357835D03*
X181300Y1374800D03*
X175554Y1367159D03*
X181500Y1382400D03*
X158497Y1379946D03*
X169100Y1371600D03*
X114000Y1482000D03*
X122000D03*
X130000D03*
X135695Y1536114D03*
Y1543614D03*
X122500Y1547400D03*
X155000Y1583800D03*
X154900Y1591300D03*
Y1642500D03*
X130350Y1613221D03*
X123042Y1583449D03*
X150175Y1614225D03*
X159650Y1650850D03*
X121950Y1661250D03*
X181387Y1781000D03*
X175000Y1774500D03*
X171506Y1763994D03*
X165000Y1774000D03*
X131795Y1932826D03*
Y1940326D03*
X138100Y1946000D03*
X143450Y1975664D03*
X200675Y23725D03*
X206750Y60250D03*
X201600Y51900D03*
X186487Y164453D03*
X203154Y139453D03*
X187608Y154749D03*
X186400Y368300D03*
X193750Y535250D03*
X194000Y527750D03*
Y555125D03*
X191500Y543500D03*
X186487Y569965D03*
X187500Y559000D03*
X217200Y565700D03*
X187800Y775400D03*
X212300Y961000D03*
X186487Y975477D03*
X191000Y964300D03*
X191500Y942500D03*
X188000Y1179500D03*
X186100Y1346600D03*
X199900Y1346488D03*
X186700Y1585700D03*
X201447Y1751500D03*
X228181Y1772100D03*
X186400Y1786700D03*
X190266Y1776603D03*
X194750Y1762000D03*
X210500Y1761400D03*
X287951Y93246D03*
X315100Y403400D03*
X291955Y505017D03*
X315400Y598400D03*
X314000Y587000D03*
X320900Y593000D03*
X306500Y568400D03*
X315000Y571000D03*
Y578500D03*
X314000Y834000D03*
X314600Y1204800D03*
X313500Y1406300D03*
X301500Y1407500D03*
X307400Y1400800D03*
X285100Y1412200D03*
X285700Y1404100D03*
X293200Y1406100D03*
X272722Y1584801D03*
X276500Y1709400D03*
X269000Y1709516D03*
X315200Y1704900D03*
X287500Y1783000D03*
X279500D03*
X271500D03*
X276500Y1740000D03*
X271000Y1745500D03*
X282000D03*
X352500Y81500D03*
X348500Y118500D03*
X355000Y112000D03*
X363500Y81500D03*
X367250Y63000D03*
X368800Y88300D03*
X368350Y104650D03*
X380250Y336100D03*
X344750D03*
X388250Y336000D03*
X352750D03*
X381500Y357500D03*
X346000D03*
X343500Y393000D03*
X345900Y376000D03*
X333300Y403400D03*
X339000Y379000D03*
X343000Y385500D03*
X355250Y463900D03*
X390750D03*
X354000Y442500D03*
X389500D03*
X347250Y464000D03*
X382750D03*
X333500Y421000D03*
Y413000D03*
X340500Y425000D03*
X373750Y766100D03*
X381750Y766000D03*
X375100Y787700D03*
X333500Y843000D03*
X343500Y823000D03*
X345300Y804400D03*
X379600Y795300D03*
X333800Y833000D03*
X339000Y809000D03*
X343000Y815500D03*
X355250Y893900D03*
X390750D03*
X354000Y872500D03*
X389500D03*
X347250Y894000D03*
X382750D03*
X333500Y851000D03*
X340500Y855000D03*
X348861Y1070104D03*
X380250Y1137600D03*
X388250Y1137500D03*
X381500Y1159000D03*
X343500Y1194500D03*
X345600Y1176100D03*
X385900Y1166100D03*
X334500Y1204250D03*
X339000Y1180500D03*
X343000Y1187000D03*
X355029Y1265402D03*
X390750Y1265400D03*
X354000Y1244000D03*
X389500D03*
X347250Y1265500D03*
X382750D03*
X333500Y1222500D03*
Y1214500D03*
X340500Y1226500D03*
X344750Y1636100D03*
X352750Y1636000D03*
X346000Y1657500D03*
X333500Y1721000D03*
Y1713000D03*
X344000Y1693600D03*
X346000Y1676500D03*
X333600Y1703500D03*
X339100Y1679600D03*
X342700Y1686200D03*
X355250Y1763900D03*
X354000Y1742500D03*
X347250Y1764000D03*
X340500Y1725000D03*
X406000Y399000D03*
X474300Y423688D03*
X433900Y809250D03*
X412500Y810500D03*
X434000Y817250D03*
X433900Y1211750D03*
X412500Y1213000D03*
X434000Y1219750D03*
X433900Y1710250D03*
X412500Y1711500D03*
X434000Y1718250D03*
X486363Y932790D03*
X668643Y131315D03*
X763200Y1698600D03*
X820500Y183000D03*
X828500D03*
X836500D03*
X810500Y191500D03*
Y199500D03*
X814250Y341250D03*
X819000Y349600D03*
X820325Y377775D03*
X814250Y746750D03*
X819000Y755100D03*
X820325Y783275D03*
X814250Y1152250D03*
X819000Y1160600D03*
X820325Y1188775D03*
X814250Y1557750D03*
X819200Y1566100D03*
X820325Y1594275D03*
X826888Y1714000D03*
X835888Y1716500D03*
X829888Y1721000D03*
X819000Y1797000D03*
X829500D03*
X837500D03*
X810500Y1805500D03*
Y1813500D03*
X779089Y1931757D03*
X783939Y1940107D03*
X835800Y1948500D03*
X835000Y1941000D03*
X788389Y1969286D03*
X808339Y1962507D03*
X768564Y1968282D03*
X909733Y158953D03*
X904728Y151181D03*
X883412Y149000D03*
X909881Y131990D03*
X879000Y169500D03*
X910750Y141223D03*
X884000Y140013D03*
X863941Y319578D03*
Y327078D03*
X850125Y330750D03*
X882500Y367000D03*
X894900Y377300D03*
X840150Y378779D03*
X861890Y383014D03*
X903728Y556693D03*
X881500Y548965D03*
X907492Y536837D03*
X909750Y546735D03*
X880636Y541514D03*
X909733Y564465D03*
X886843Y568923D03*
X882000Y773000D03*
X863841Y725090D03*
Y732590D03*
X851150Y736750D03*
X894800Y783900D03*
X840150Y784279D03*
X859737Y789667D03*
X909733Y969977D03*
X903728Y962205D03*
X881500Y954477D03*
X890550Y957450D03*
X908177Y942729D03*
X879800Y975800D03*
X909750Y952247D03*
X880636Y947026D03*
X864241Y1130602D03*
Y1138102D03*
X880500Y1178500D03*
X886400Y1185000D03*
X849550Y1142150D03*
X840150Y1189779D03*
X860272Y1194370D03*
X852898Y1249029D03*
X908530Y1348458D03*
X909750Y1357758D03*
X880636Y1352537D03*
X909733Y1375488D03*
X903900Y1367659D03*
X881500Y1359988D03*
X880100Y1380100D03*
X864441Y1536114D03*
Y1543614D03*
X850550Y1547750D03*
X883000Y1582500D03*
X885300Y1590300D03*
X840150Y1595279D03*
X858185Y1601013D03*
X911800Y1684000D03*
X909700Y1719000D03*
X879100Y1715100D03*
X896500Y1696300D03*
X906000Y1703400D03*
X889600Y1691900D03*
X904276Y1696100D03*
X903728Y1773228D03*
X881500Y1765500D03*
X909733Y1781000D03*
X898089Y1745256D03*
X894484Y1722200D03*
X886843Y1785458D03*
X909750Y1763270D03*
X881636Y1757549D03*
X862241Y1934326D03*
Y1941826D03*
X856900Y1947600D03*
X871750Y1975500D03*
X914833Y164453D03*
X931500Y139453D03*
X915037Y153502D03*
X915900Y368600D03*
X931500Y544965D03*
X916600Y556600D03*
X914833Y569965D03*
X915800Y774600D03*
X914833Y975477D03*
X931500Y950477D03*
X914646Y964214D03*
X919100Y1180600D03*
X931500Y1355988D03*
X935000Y1425000D03*
X984900Y1430400D03*
X953800Y1424900D03*
X945000Y1425000D03*
X914833Y1380988D03*
X915037Y1370037D03*
X935000Y1455000D03*
Y1475000D03*
Y1445000D03*
Y1465000D03*
Y1435000D03*
X945000Y1475000D03*
X955000D03*
X965000D03*
X945000Y1465000D03*
X955000D03*
X965000D03*
X945000Y1455000D03*
X955000D03*
X965000D03*
X945000Y1445000D03*
X955000D03*
X965000D03*
X945000Y1435000D03*
X955000D03*
X965000D03*
Y1495000D03*
X955000D03*
X935000Y1485000D03*
Y1495000D03*
X945000D03*
Y1485000D03*
X955000D03*
X965000D03*
X975000Y1495000D03*
Y1485000D03*
Y1475000D03*
Y1465000D03*
Y1455000D03*
Y1445000D03*
Y1435000D03*
X965000Y1525000D03*
X955000D03*
X945000D03*
Y1516000D03*
X955000D03*
X965000D03*
X935000Y1555000D03*
X945000D03*
X955000D03*
X965000D03*
X935000Y1575000D03*
Y1565000D03*
X945000Y1575000D03*
X955000D03*
X965000D03*
Y1565000D03*
X955000D03*
X945000D03*
X935000Y1545000D03*
Y1535000D03*
Y1525000D03*
Y1516000D03*
X965000Y1545000D03*
X955000D03*
X945000D03*
Y1535000D03*
X955000D03*
X965000D03*
X975000Y1565000D03*
Y1575000D03*
Y1525000D03*
Y1535000D03*
Y1545000D03*
Y1555000D03*
X935000Y1505000D03*
X955000D03*
X945000D03*
X965000D03*
X969000Y1641500D03*
X976000Y1636000D03*
X965000Y1605000D03*
X935000Y1595000D03*
Y1585000D03*
X945000Y1595000D03*
X955000D03*
X965000D03*
Y1585000D03*
X955000D03*
X945000D03*
X975000Y1595000D03*
Y1605000D03*
Y1585000D03*
X918600Y1584600D03*
X969500Y1676500D03*
X916200Y1708700D03*
X914833Y1786500D03*
X913923Y1752000D03*
X931500Y1761500D03*
X916100Y1773800D03*
X990600Y1427100D03*
X995000Y1425000D03*
X1005000D03*
G54D61*
X308100Y416200D03*
Y846700D03*
X308200Y1217500D03*
X309200Y1715700D03*
X963700Y1661000D03*
Y1671000D03*
X919700Y1695000D03*
G54D43*
X59859Y204971D03*
X91200Y341300D03*
X94500Y369300D03*
X67414Y628262D03*
X91200Y746800D03*
X94500Y774800D03*
X77750Y1049436D03*
X91200Y1152700D03*
X94500Y1180300D03*
X76750Y1455150D03*
X90500Y1548800D03*
X83875Y1580175D03*
X77100Y1846200D03*
X61000Y1932800D03*
X56000Y1880800D03*
X41800Y1960600D03*
X180850Y27650D03*
X125700Y47900D03*
X146400Y136300D03*
X150557D03*
X114295Y331617D03*
X153625Y402425D03*
X129975Y401275D03*
X148400Y430900D03*
X120800Y441100D03*
X122025Y569675D03*
X117945Y737217D03*
X148400Y836400D03*
X154000Y808300D03*
X158500Y804300D03*
X130350Y807150D03*
X122251Y845546D03*
X178000Y952800D03*
X117900Y1142600D03*
X148700Y1241900D03*
X154000Y1213800D03*
X130350Y1212650D03*
X121500Y1252100D03*
X130000Y1473300D03*
X122000D03*
X114000D03*
X149900Y1647400D03*
X154000Y1619300D03*
X130350Y1619150D03*
X117000Y1657800D03*
X170080Y1773528D03*
X204500Y28800D03*
X197000Y56800D03*
X203000Y535300D03*
Y542800D03*
Y527800D03*
X194750Y1753050D03*
X200198Y1758800D03*
X305100Y393100D03*
X309300Y400600D03*
X313000Y562300D03*
X292000Y605300D03*
X284000D03*
X304000D03*
X296000D03*
X316000D03*
X308000D03*
X304500Y822600D03*
X308600Y830100D03*
X305200Y1194050D03*
X309300Y1201550D03*
X303500Y1392300D03*
X311500D03*
X287600Y1441300D03*
X279650D03*
X299600D03*
X291600D03*
X311600D03*
X303600D03*
X306200Y1692550D03*
X310300Y1700050D03*
X291500Y1788300D03*
X283500D03*
X275500D03*
X280500Y1731300D03*
X276500D03*
X272500D03*
X352500Y71800D03*
X378100Y84700D03*
X377500Y101300D03*
X344500Y364300D03*
X359500D03*
X340500D03*
X380000D03*
X395000D03*
X355500D03*
X376000D03*
X391000D03*
X398000Y406800D03*
X382500Y451300D03*
X347000D03*
X390500D03*
X355000D03*
X384500Y794300D03*
X388500D03*
X369500D03*
X373500D03*
X382500Y881300D03*
X347000D03*
X390500D03*
X355000D03*
X380000Y1165800D03*
X391000D03*
X395000D03*
X376000D03*
X382500Y1252800D03*
X347000D03*
X390500D03*
X355000D03*
X355500Y1664300D03*
X340500D03*
X359500D03*
X344500D03*
X379000Y1729300D03*
X347000Y1751300D03*
X355000D03*
X429000Y809300D03*
Y817300D03*
Y1211800D03*
Y1219800D03*
Y1710300D03*
Y1718300D03*
X836500Y174300D03*
X828500D03*
X820500D03*
X819500Y341300D03*
X821000Y369300D03*
X819500Y746800D03*
X821000Y774800D03*
X819500Y1152300D03*
X821000Y1180300D03*
X819500Y1557800D03*
X821000Y1585800D03*
X837500Y1788300D03*
X829500D03*
X819000D03*
X784339Y1931807D03*
X769239Y1959807D03*
X866961Y155961D03*
X844050Y330800D03*
X846200Y736800D03*
X844600Y1142200D03*
X845600Y1547800D03*
X906000Y1687800D03*
X859500Y1699300D03*
X902500Y1727300D03*
X898500D03*
X910500Y1727800D03*
X959000Y1668300D03*
G54D52*
X107200Y342500D03*
Y347500D03*
Y352500D03*
Y357500D03*
Y748000D03*
Y753000D03*
Y758000D03*
Y763000D03*
Y1153900D03*
Y1158900D03*
Y1163900D03*
Y1168900D03*
X106700Y1554100D03*
Y1559100D03*
Y1564100D03*
Y1569100D03*
X99500Y1939000D03*
Y1934000D03*
X79500D03*
Y1939000D03*
X99500Y1949000D03*
Y1944000D03*
X79500D03*
Y1949000D03*
X165500Y44000D03*
X185500D03*
X165500Y49000D03*
Y54000D03*
Y59000D03*
X185500D03*
Y54000D03*
Y49000D03*
X127200Y357500D03*
Y352500D03*
Y347500D03*
Y342500D03*
X116900Y418100D03*
Y423100D03*
Y428100D03*
Y433100D03*
X136900D03*
Y428100D03*
Y423100D03*
Y418100D03*
X127200Y763000D03*
Y758000D03*
Y753000D03*
Y748000D03*
X116900Y823600D03*
Y828600D03*
Y833600D03*
Y838600D03*
X136900D03*
Y833600D03*
Y828600D03*
Y823600D03*
X127200Y1168900D03*
Y1163900D03*
Y1158900D03*
Y1153900D03*
X117200Y1229100D03*
Y1234100D03*
Y1239100D03*
Y1244100D03*
X137200D03*
Y1239100D03*
Y1234100D03*
Y1229100D03*
X126700Y1569100D03*
Y1564100D03*
Y1559100D03*
Y1554100D03*
X118400Y1634600D03*
Y1639600D03*
Y1644600D03*
X138400D03*
Y1639600D03*
Y1634600D03*
X118400Y1649600D03*
X138400D03*
X835500Y357500D03*
Y352500D03*
Y347500D03*
Y342500D03*
Y763000D03*
Y758000D03*
Y753000D03*
Y748000D03*
Y1168500D03*
Y1163500D03*
Y1158500D03*
Y1153500D03*
Y1574000D03*
Y1569000D03*
Y1564000D03*
Y1559000D03*
X802439Y1939107D03*
Y1934107D03*
X822439D03*
Y1939107D03*
X802439Y1949107D03*
Y1944107D03*
X822439D03*
Y1949107D03*
X855500Y342500D03*
Y347500D03*
Y352500D03*
Y357500D03*
Y748000D03*
Y753000D03*
Y758000D03*
Y763000D03*
Y1153500D03*
Y1158500D03*
Y1163500D03*
Y1168500D03*
Y1559000D03*
Y1564000D03*
Y1569000D03*
Y1574000D03*
G54D70*
X302953Y1413700D03*
X300984D03*
X299016D03*
X297047D03*
Y1429300D03*
X299016D03*
X300984D03*
X302953D03*
G54D25*
X37100Y1832100D03*
Y1827300D03*
X325900Y583400D03*
G54D16*
X25000Y988000D03*
X27825Y995000D03*
X78675Y380704D03*
X47500Y660500D03*
X45000Y1057000D03*
X77607Y1565391D03*
X183344Y808200D03*
X126221Y861250D03*
Y853750D03*
X163170Y1210999D03*
X117387Y1536250D03*
Y1543750D03*
X122844Y1672400D03*
X130344D03*
X213244Y23725D03*
X243156Y382060D03*
X235656D03*
X228156Y438500D03*
X220656D03*
X206700Y575000D03*
X190844Y808200D03*
X242700Y1266656D03*
Y1259156D03*
X232344Y1740000D03*
X239844D03*
X284000Y541344D03*
Y548844D03*
X317156Y1193440D03*
X324656D03*
X276344Y1183060D03*
X268844D03*
X401500Y395500D03*
X393500Y422000D03*
X401500Y830000D03*
X393500Y852000D03*
X402000Y1196500D03*
X396637Y1176000D03*
X358156Y1411000D03*
X350656D03*
X402000Y1695000D03*
X379500Y1673750D03*
X427500Y297156D03*
Y304656D03*
X412500Y1130750D03*
Y1138250D03*
X438656Y1669000D03*
X431156D03*
X458156Y1743000D03*
X450656D03*
X512656Y623500D03*
X520156D03*
X555000Y524344D03*
Y531844D03*
X807756Y377775D03*
X808256Y783275D03*
X807756Y1188775D03*
Y1594275D03*
X979500Y1669750D03*
Y1662250D03*
G54D34*
X72835Y17047D03*
Y190275D03*
Y422559D03*
Y595787D03*
Y828071D03*
Y1001299D03*
Y1233583D03*
Y1406811D03*
Y1639095D03*
Y1812323D03*
X171260Y179803D03*
Y353031D03*
Y585315D03*
Y758543D03*
Y990827D03*
Y1164055D03*
Y1396339D03*
Y1569567D03*
Y1801851D03*
Y1975079D03*
X899606Y179803D03*
Y353031D03*
Y585315D03*
Y758543D03*
Y990827D03*
Y1164055D03*
Y1396339D03*
Y1569567D03*
Y1801851D03*
Y1975079D03*
G54D44*
X59859Y208371D03*
X91200Y344700D03*
X94500Y372700D03*
X67414Y631662D03*
X91200Y750200D03*
X94500Y778200D03*
X77750Y1052836D03*
X91200Y1156100D03*
X94500Y1183700D03*
X76750Y1458550D03*
X90500Y1552200D03*
X83875Y1583575D03*
X77100Y1849600D03*
X61000Y1936200D03*
X56000Y1884200D03*
X41800Y1964000D03*
X180850Y31050D03*
X125700Y51300D03*
X146400Y139700D03*
X150557D03*
X114295Y335017D03*
X153625Y405825D03*
X129975Y404675D03*
X148400Y434300D03*
X120800Y444500D03*
X122025Y573075D03*
X117945Y740617D03*
X148400Y839800D03*
X154000Y811700D03*
X158500Y807700D03*
X130350Y810550D03*
X122251Y848946D03*
X178000Y956200D03*
X117900Y1146000D03*
X148700Y1245300D03*
X154000Y1217200D03*
X130350Y1216050D03*
X121500Y1255500D03*
X130000Y1476700D03*
X122000D03*
X114000D03*
X154000Y1622700D03*
X130350Y1622550D03*
X149900Y1650800D03*
X117000Y1661200D03*
X170080Y1776928D03*
X204500Y32200D03*
X197000Y60200D03*
X203000Y538700D03*
Y546200D03*
Y531200D03*
X194750Y1756450D03*
X200198Y1762200D03*
X305100Y396500D03*
X309300Y404000D03*
X313000Y565700D03*
X292000Y608700D03*
X284000D03*
X304000D03*
X296000D03*
X316000D03*
X308000D03*
X304500Y826000D03*
X308600Y833500D03*
X305200Y1197450D03*
X309300Y1204950D03*
X303500Y1395700D03*
X311500D03*
X287600Y1444700D03*
X279650D03*
X299600D03*
X291600D03*
X311600D03*
X303600D03*
X306200Y1695950D03*
X310300Y1703450D03*
X291500Y1791700D03*
X283500D03*
X275500D03*
X280500Y1734700D03*
X276500D03*
X272500D03*
X352500Y75200D03*
X378100Y88100D03*
X377500Y104700D03*
X344500Y367700D03*
X359500D03*
X340500D03*
X380000D03*
X395000D03*
X355500D03*
X376000D03*
X391000D03*
X398000Y410200D03*
X382500Y454700D03*
X347000D03*
X390500D03*
X355000D03*
X384500Y797700D03*
X388500D03*
X369500D03*
X373500D03*
X382500Y884700D03*
X347000D03*
X390500D03*
X355000D03*
X380000Y1169200D03*
X391000D03*
X395000D03*
X376000D03*
X382500Y1256200D03*
X347000D03*
X390500D03*
X355000D03*
X355500Y1667700D03*
X340500D03*
X359500D03*
X344500D03*
X379000Y1732700D03*
X347000Y1754700D03*
X355000D03*
X429000Y812700D03*
Y820700D03*
Y1215200D03*
Y1223200D03*
Y1713700D03*
Y1721700D03*
X836500Y177700D03*
X828500D03*
X820500D03*
X819500Y344700D03*
X821000Y372700D03*
X819500Y750200D03*
X821000Y778200D03*
X819500Y1155700D03*
X821000Y1183700D03*
X819500Y1561200D03*
X821000Y1589200D03*
X837500Y1791700D03*
X829500D03*
X819000D03*
X784339Y1935207D03*
X769239Y1963207D03*
X866961Y159361D03*
X844050Y334200D03*
X846200Y740200D03*
X844600Y1145600D03*
X845600Y1551200D03*
X906000Y1691200D03*
X859500Y1702700D03*
X902500Y1730700D03*
X898500D03*
X910500Y1731200D03*
X959000Y1671700D03*
G54D71*
X292200Y1418547D03*
Y1420516D03*
Y1422484D03*
Y1424453D03*
X307800D03*
Y1422484D03*
Y1420516D03*
Y1418547D03*
G54D26*
X31500Y1832100D03*
Y1827300D03*
X320300Y583400D03*
G54D80*
X822500Y1729750D03*
Y1730250D03*
G54D17*
X31707Y1062791D03*
Y1081291D03*
X41100Y1633650D03*
Y1615150D03*
G54D53*
X86050Y407200D03*
X67550D03*
X88650Y813200D03*
X70150D03*
X86650Y1218700D03*
X68150D03*
X84950Y1624000D03*
X66450D03*
X160350Y368300D03*
X178850D03*
X160550Y775400D03*
X179050D03*
X160050Y1179500D03*
X178550D03*
X161150Y1585700D03*
X179650D03*
X124950Y1965200D03*
X143450D03*
X889750Y368600D03*
X908250D03*
X889450Y774600D03*
X907950D03*
X893550Y1180600D03*
X912050D03*
X892050Y1584600D03*
X910550D03*
X853250Y1965500D03*
X871750D03*
G54D35*
X105400Y42350D03*
Y23850D03*
G54D62*
X313700Y416200D03*
Y846700D03*
X313800Y1217500D03*
X314800Y1715700D03*
X969300Y1661000D03*
Y1671000D03*
X925300Y1695000D03*
G54D54*
X99600Y411016D03*
Y421984D03*
X106300Y441484D03*
Y430516D03*
X100200Y816216D03*
Y827184D03*
X106300Y846584D03*
Y835616D03*
X106400Y1221916D03*
Y1232884D03*
Y1252284D03*
Y1241316D03*
X107000Y1647016D03*
X100000Y1627416D03*
Y1638384D03*
X107000Y1657984D03*
X109900Y1968184D03*
Y1957216D03*
X97400Y1968184D03*
Y1957216D03*
X139600Y48316D03*
X152100D03*
X139600Y59284D03*
X152100D03*
X137800Y334416D03*
X137900Y365084D03*
Y354116D03*
X137800Y345384D03*
X137900Y770684D03*
Y759716D03*
X137800Y740116D03*
Y751084D03*
X140000Y1175484D03*
Y1164516D03*
X137800Y1145116D03*
Y1156084D03*
X145500Y1571016D03*
X137600Y1550816D03*
Y1561784D03*
X145500Y1581984D03*
X838000Y1967984D03*
Y1957016D03*
X825500Y1967984D03*
Y1957016D03*
X866300Y335016D03*
X874000Y365484D03*
Y354516D03*
X866300Y345984D03*
X874000Y770984D03*
Y760016D03*
X866100Y740316D03*
Y751284D03*
X866000Y1176484D03*
Y1165516D03*
X866200Y1146016D03*
Y1156984D03*
X874500Y1572016D03*
X866300Y1552216D03*
Y1563184D03*
X874500Y1582984D03*
X973200Y1414216D03*
Y1425184D03*
X960700Y1414216D03*
Y1425184D03*
G54D27*
X40184Y1865200D03*
X29216D03*
X40184Y1852900D03*
X29216D03*
X40184Y1840600D03*
X29216D03*
X40184Y1877500D03*
X29216D03*
X878859Y1671037D03*
X889827D03*
X878859Y1683500D03*
X889827D03*
G54D45*
X97731Y241863D03*
Y244423D03*
Y246983D03*
X91231D03*
Y241863D03*
X97731Y647375D03*
Y649935D03*
Y652495D03*
X91231D03*
Y647375D03*
X97731Y1052886D03*
Y1055446D03*
Y1058006D03*
X91231D03*
Y1052886D03*
X97731Y1458398D03*
Y1460958D03*
Y1463518D03*
X91231D03*
Y1458398D03*
X162904Y141013D03*
Y138453D03*
Y135893D03*
X169404D03*
Y141013D03*
X162904Y1356548D03*
Y1353988D03*
Y1351428D03*
X169404D03*
Y1356548D03*
X207596Y1769440D03*
Y1772000D03*
Y1774560D03*
X201096D03*
Y1769440D03*
X898750Y140013D03*
Y134893D03*
X892250D03*
Y137453D03*
Y140013D03*
X897750Y545525D03*
Y540405D03*
X891250D03*
Y542965D03*
Y545525D03*
X897750Y951037D03*
Y945917D03*
X891250D03*
Y948477D03*
Y951037D03*
X897750Y1356548D03*
Y1351428D03*
X891250D03*
Y1353988D03*
Y1356548D03*
Y1762060D03*
Y1759500D03*
Y1756940D03*
X897750D03*
Y1762060D03*
G54D18*
X33469Y1029523D03*
X269690Y1490152D03*
G54D72*
X328600Y1696950D03*
Y1699150D03*
X337800Y397500D03*
Y399700D03*
X336800Y826950D03*
Y829150D03*
X337500Y1198450D03*
Y1200650D03*
G54D63*
X308100Y590421D03*
Y580579D03*
X291900D03*
Y590421D03*
G54D81*
X887444Y1709016D03*
Y1710984D03*
X899556D03*
Y1709016D03*
G54D90*
X916500Y1723250D03*
G54D36*
X100000Y119200D03*
Y525200D03*
Y930200D03*
Y1335200D03*
Y1749700D03*
X131000Y51000D03*
X144000Y241700D03*
X146600Y357500D03*
X144000Y648200D03*
X146500Y762300D03*
X144000Y1053700D03*
X148500Y1168700D03*
X144000Y1458200D03*
X136700Y1574200D03*
X144000Y1864200D03*
X118500Y1961800D03*
X865500Y357200D03*
X872500Y648200D03*
X865000Y763100D03*
X872500Y1053700D03*
X874500Y1169200D03*
X872500Y1459200D03*
X866000Y1574700D03*
X910500Y1707700D03*
X855000Y1696700D03*
X878000Y1723200D03*
X871500Y1864200D03*
X846500Y1961700D03*
G54D19*
X30200Y1488300D03*
X26600D03*
X32850Y1510400D03*
X36350D03*
X82000Y243688D03*
X98400Y435600D03*
X82000Y649200D03*
X98400Y841100D03*
X83248Y1052836D03*
X98400Y1246600D03*
X82748Y1458348D03*
X98900Y1652500D03*
X54872Y1674748D03*
X58372D03*
X115700Y40000D03*
X144400Y430800D03*
Y836300D03*
X144700Y1241800D03*
X145900Y1647300D03*
X193000Y56700D03*
X194606Y1769390D03*
X395600Y398100D03*
X393500Y380200D03*
X341000Y402700D03*
X344500D03*
X368500Y429200D03*
X372000D03*
X341000Y832700D03*
X344500D03*
X393500Y829700D03*
X368500Y858200D03*
X372000D03*
X393500Y1177700D03*
X341000Y1204200D03*
X344500D03*
X395600Y1198700D03*
X368500Y1229700D03*
X372000D03*
X395700Y1697200D03*
X341000Y1702700D03*
X344500D03*
X369000Y1727700D03*
X372500D03*
X417500Y809200D03*
Y817200D03*
Y1211700D03*
Y1219700D03*
Y1710200D03*
Y1718200D03*
G54D37*
X100000Y124800D03*
Y530800D03*
Y935800D03*
Y1340800D03*
Y1755300D03*
X131000Y56600D03*
X144000Y247300D03*
X146600Y363100D03*
X144000Y653800D03*
X146500Y767900D03*
X144000Y1059300D03*
X148500Y1174300D03*
X144000Y1463800D03*
X136700Y1579800D03*
X144000Y1869800D03*
X118500Y1967400D03*
X865500Y362800D03*
X872500Y653800D03*
X865000Y768700D03*
X872500Y1059300D03*
X874500Y1174800D03*
X872500Y1464800D03*
X866000Y1580300D03*
X910500Y1713300D03*
X855000Y1702300D03*
X878000Y1728800D03*
X871500Y1869800D03*
X846500Y1967300D03*
G54D64*
X304921Y577400D03*
X295079D03*
Y593600D03*
X304921D03*
G54D82*
X894484Y1716056D03*
X892516D03*
Y1703944D03*
X894484D03*
G54D73*
X280840Y1752400D03*
X278280D03*
X275720D03*
X273160D03*
Y1774600D03*
X275720D03*
X278280D03*
X280840D03*
G54D55*
X84700Y357000D03*
Y348000D03*
Y762500D03*
Y753500D03*
Y1168400D03*
Y1159400D03*
X84000Y1564500D03*
Y1555500D03*
X54500Y1939500D03*
Y1948500D03*
X159400Y418600D03*
Y427600D03*
Y824100D03*
Y833100D03*
X159700Y1229600D03*
Y1238600D03*
X160900Y1635100D03*
Y1644100D03*
X208000Y44500D03*
Y53500D03*
X813000Y357000D03*
Y348000D03*
Y762500D03*
Y753500D03*
Y1168000D03*
Y1159000D03*
Y1573500D03*
Y1564500D03*
X777839Y1938507D03*
Y1947507D03*
G54D91*
X988745Y1447976D03*
Y1456976D03*
Y1460976D03*
Y1487976D03*
Y1496976D03*
Y1500976D03*
Y1526976D03*
Y1536976D03*
Y1540976D03*
Y1566976D03*
X1001544Y1605976D03*
X988745Y1577976D03*
Y1582976D03*
G54D46*
X99700Y344800D03*
Y750300D03*
Y1156200D03*
X99000Y1552300D03*
X69500Y1936300D03*
X175894Y141463D03*
X145700Y340200D03*
X145800Y745900D03*
X182000Y956300D03*
X145800Y1150400D03*
X175894Y1356598D03*
X145800Y1554100D03*
X133200Y1954500D03*
X373500Y104800D03*
X374300Y88200D03*
X372000Y371300D03*
X368500D03*
X393500Y418300D03*
X343000Y420300D03*
X346500D03*
X362000Y803800D03*
X393500Y848300D03*
X365500Y803800D03*
X343000Y850300D03*
X346500D03*
X367500Y1174800D03*
X371000D03*
X393500Y1225300D03*
X343000Y1221800D03*
X346500D03*
X376000Y1673800D03*
X343000Y1720300D03*
X346500D03*
X372500Y1673800D03*
X828000Y344800D03*
Y750300D03*
Y1155800D03*
Y1561300D03*
X792839Y1935307D03*
X905240Y140063D03*
X874200Y340300D03*
X904240Y545575D03*
X874100Y746800D03*
X904240Y951087D03*
X874100Y1151300D03*
X904240Y1356598D03*
X874200Y1557500D03*
X841500Y1702300D03*
X904240Y1762110D03*
X862500Y1955100D03*
X994600Y1421100D03*
G54D28*
X37300Y1964000D03*
X87589Y234415D03*
X76750Y234272D03*
X83589Y234415D03*
X63903Y212595D03*
X95700Y344700D03*
X90000Y372700D03*
X92500Y606700D03*
X63623Y614570D03*
X87589Y639927D03*
X76750Y639784D03*
X83589Y639927D03*
X95700Y750200D03*
X90000Y778200D03*
X45000Y1064200D03*
X41000D03*
X88000Y1046200D03*
X77750Y1044295D03*
X93000Y1012200D03*
X84000Y1046200D03*
X64040Y1023685D03*
X95700Y1156100D03*
X90000Y1183700D03*
X63797Y1429188D03*
X110000Y1476700D03*
X87589Y1450950D03*
X76750Y1450807D03*
X83589Y1450950D03*
X95000Y1552200D03*
X79375Y1583575D03*
X75256Y1587075D03*
X103025Y1584725D03*
X65500Y1936200D03*
X48000Y1884200D03*
X52000D03*
X61050Y1965250D03*
X114300Y69200D03*
X119300D03*
X121600Y51300D03*
X170402Y151153D03*
X163994Y154736D03*
X126445Y335017D03*
X113650Y373850D03*
X149125Y405825D03*
X152900Y434300D03*
X125300Y444500D03*
X150000Y544700D03*
X154500D03*
X162144Y575235D03*
X122445Y740617D03*
X152900Y839800D03*
X113650Y779350D03*
X149500Y811700D03*
X126800Y849000D03*
X113650Y1184850D03*
X122400Y1146000D03*
X153200Y1245300D03*
X149500Y1217200D03*
X126000Y1255500D03*
X170402Y1366688D03*
X164066Y1371527D03*
X126000Y1476700D03*
X118000D03*
X149500Y1622700D03*
X154400Y1650800D03*
X126900Y1661200D03*
X126500Y1947200D03*
X200000Y32200D03*
X201500Y60200D03*
X199000Y538700D03*
Y531200D03*
Y546200D03*
X229500Y953177D03*
X305100Y404000D03*
X309300Y396500D03*
X290580Y565700D03*
X298450D03*
X317500D03*
X304500Y833500D03*
X308600Y826000D03*
X305200Y1204950D03*
X309300Y1197450D03*
X293100Y1390200D03*
X284900D03*
X319500Y1395700D03*
X315500D03*
X287000Y1399200D03*
X291000D03*
X307500Y1395700D03*
X276500Y1717700D03*
X272500D03*
X306200Y1703450D03*
X310300Y1695950D03*
X287500Y1791700D03*
X279500D03*
X271500D03*
X358000Y70700D03*
X348500Y75200D03*
X382200Y88100D03*
X382000Y104700D03*
X348500Y127200D03*
X352500D03*
X353000Y348700D03*
X388500D03*
X345000D03*
X380500D03*
X344500Y435700D03*
X340500D03*
X359500D03*
X355500D03*
X395000D03*
X391000D03*
X376000D03*
X380000D03*
X382000Y778700D03*
X374000D03*
X355500Y865700D03*
X340500D03*
X344500D03*
X359500D03*
X380000D03*
X395000D03*
X376000D03*
X391000D03*
X388500Y1150200D03*
X380500D03*
X355500Y1237200D03*
X380000D03*
X376000D03*
X395000D03*
X391000D03*
X344500D03*
X340500D03*
X359500D03*
X353000Y1648700D03*
X345000D03*
X344500Y1735700D03*
X340500D03*
X359500D03*
X355500D03*
X764739Y1963207D03*
X832500Y177700D03*
X824500D03*
X816500D03*
X824000Y344700D03*
X816500Y372700D03*
X824000Y750200D03*
X816500Y778200D03*
X824000Y1155700D03*
X816500Y1183700D03*
X824000Y1561200D03*
X816500Y1589200D03*
X825500Y1791700D03*
X815000D03*
X788839Y1935207D03*
X788389Y1964357D03*
X899648Y150653D03*
X856200Y334200D03*
X840150Y373850D03*
X898754Y556165D03*
X856100Y740200D03*
X840150Y779350D03*
X898648Y961677D03*
X889909Y977307D03*
X840150Y1184850D03*
X854500Y1145600D03*
X898748Y1367188D03*
X890213Y1379896D03*
X855500Y1551200D03*
X840150Y1590350D03*
X881500Y1699700D03*
X898800Y1772700D03*
X906500Y1730700D03*
X890500D03*
X841500Y1791700D03*
X959000Y1663700D03*
G54D38*
X75710Y209868D03*
Y206668D03*
X69960Y209868D03*
Y206668D03*
X75710Y615380D03*
Y612180D03*
X69960Y615380D03*
Y612180D03*
X75710Y1020891D03*
Y1017691D03*
X69960Y1020891D03*
Y1017691D03*
X75710Y1426403D03*
Y1423203D03*
X69960Y1426403D03*
Y1423203D03*
X75710Y1831915D03*
Y1828715D03*
X69960Y1831915D03*
Y1828715D03*
X174135Y163411D03*
Y160211D03*
X168385Y163411D03*
Y160211D03*
X174135Y568923D03*
Y565723D03*
X168385Y568923D03*
Y565723D03*
X174135Y974435D03*
Y971235D03*
X168385Y974435D03*
Y971235D03*
X174135Y1379946D03*
Y1376746D03*
X168385Y1379946D03*
Y1376746D03*
X174135Y1785458D03*
Y1782258D03*
X168385Y1785458D03*
Y1782258D03*
X902481Y163411D03*
Y160211D03*
X896731Y163411D03*
Y160211D03*
X902481Y568923D03*
Y565723D03*
X896731Y568923D03*
Y565723D03*
X902481Y974435D03*
Y971235D03*
X896731Y974435D03*
Y971235D03*
X902481Y1379946D03*
Y1376746D03*
X896731Y1379946D03*
Y1376746D03*
X902481Y1785458D03*
Y1782258D03*
X896731Y1785458D03*
Y1782258D03*
G54D65*
X307800Y588453D03*
Y586484D03*
Y584516D03*
Y582547D03*
X292200D03*
Y584516D03*
Y586484D03*
Y588453D03*
G54D74*
X354565Y104650D03*
X356530D03*
X358500D03*
X360470D03*
X362435D03*
Y88350D03*
X360470D03*
X358500D03*
X356530D03*
X354565D03*
G54D56*
X108400Y417600D03*
X108700Y823100D03*
X97600Y1229200D03*
X108600Y1633800D03*
X297600Y1401300D03*
X288000Y1751800D03*
X293000D03*
X872500Y250800D03*
X896500Y1690800D03*
X877000Y1700800D03*
X901500Y1690800D03*
X959000Y1627200D03*
X990500Y1422300D03*
G54D29*
X37300Y1960600D03*
X87589Y231015D03*
X76750Y230872D03*
X83589Y231015D03*
X63903Y209195D03*
X95700Y341300D03*
X90000Y369300D03*
X92500Y603300D03*
X63623Y611170D03*
X87589Y636527D03*
X76750Y636384D03*
X83589Y636527D03*
X95700Y746800D03*
X90000Y774800D03*
X45000Y1060800D03*
X41000D03*
X88000Y1042800D03*
X77750Y1040895D03*
X93000Y1008800D03*
X84000Y1042800D03*
X64040Y1020285D03*
X95700Y1152700D03*
X90000Y1180300D03*
X63797Y1425788D03*
X110000Y1473300D03*
X87589Y1447550D03*
X76750Y1447407D03*
X83589Y1447550D03*
X95000Y1548800D03*
X79375Y1580175D03*
X75256Y1583675D03*
X103025Y1581325D03*
X65500Y1932800D03*
X48000Y1880800D03*
X52000D03*
X61050Y1961850D03*
X121600Y47900D03*
X114300Y65800D03*
X119300D03*
X170402Y147753D03*
X163994Y151336D03*
X126445Y331617D03*
X113650Y370450D03*
X149125Y402425D03*
X152900Y430900D03*
X125300Y441100D03*
X150000Y541300D03*
X154500D03*
X162144Y571835D03*
X122445Y737217D03*
X152900Y836400D03*
X113650Y775950D03*
X149500Y808300D03*
X126800Y845600D03*
X113650Y1181450D03*
X122400Y1142600D03*
X153200Y1241900D03*
X149500Y1213800D03*
X126000Y1252100D03*
X170402Y1363288D03*
X164066Y1368127D03*
X126000Y1473300D03*
X118000D03*
X154400Y1647400D03*
X149500Y1619300D03*
X126900Y1657800D03*
X126500Y1943800D03*
X200000Y28800D03*
X201500Y56800D03*
X199000Y535300D03*
Y527800D03*
Y542800D03*
X229500Y949777D03*
X305100Y400600D03*
X309300Y393100D03*
X290580Y562300D03*
X298450D03*
X317500D03*
X304500Y830100D03*
X308600Y822600D03*
X305200Y1201550D03*
X309300Y1194050D03*
X293100Y1386800D03*
X284900D03*
X319500Y1392300D03*
X315500D03*
X287000Y1395800D03*
X291000D03*
X307500Y1392300D03*
X276500Y1714300D03*
X272500D03*
X306200Y1700050D03*
X310300Y1692550D03*
X287500Y1788300D03*
X279500D03*
X271500D03*
X358000Y67300D03*
X348500Y71800D03*
X382200Y84700D03*
X382000Y101300D03*
X348500Y123800D03*
X352500D03*
X353000Y345300D03*
X388500D03*
X345000D03*
X380500D03*
X344500Y432300D03*
X340500D03*
X359500D03*
X355500D03*
X395000D03*
X391000D03*
X376000D03*
X380000D03*
X382000Y775300D03*
X374000D03*
X355500Y862300D03*
X340500D03*
X344500D03*
X359500D03*
X380000D03*
X395000D03*
X376000D03*
X391000D03*
X388500Y1146800D03*
X380500D03*
X355500Y1233800D03*
X380000D03*
X376000D03*
X395000D03*
X391000D03*
X344500D03*
X340500D03*
X359500D03*
X353000Y1645300D03*
X345000D03*
X344500Y1732300D03*
X340500D03*
X359500D03*
X355500D03*
X764739Y1959807D03*
X832500Y174300D03*
X824500D03*
X816500D03*
X824000Y341300D03*
X816500Y369300D03*
X824000Y746800D03*
X816500Y774800D03*
X824000Y1152300D03*
X816500Y1180300D03*
X824000Y1557800D03*
X816500Y1585800D03*
X825500Y1788300D03*
X815000D03*
X788839Y1931807D03*
X788389Y1960957D03*
X899648Y147253D03*
X856200Y330800D03*
X840150Y370450D03*
X898754Y552765D03*
X856100Y736800D03*
X840150Y775950D03*
X898648Y958277D03*
X889909Y973907D03*
X840150Y1181450D03*
X854500Y1142200D03*
X898748Y1363788D03*
X890213Y1376496D03*
X855500Y1547800D03*
X840150Y1586950D03*
X881500Y1696300D03*
X898800Y1769300D03*
X906500Y1727300D03*
X890500D03*
X841500Y1788300D03*
X959000Y1660300D03*
G54D47*
X99700Y341200D03*
Y746700D03*
Y1152600D03*
X99000Y1548700D03*
X69500Y1932700D03*
X175894Y137863D03*
X145700Y336600D03*
X145800Y742300D03*
X182000Y952700D03*
X145800Y1146800D03*
X175894Y1352998D03*
X145800Y1550500D03*
X133200Y1950900D03*
X373500Y101200D03*
X374300Y84600D03*
X372000Y367700D03*
X368500D03*
X393500Y414700D03*
X343000Y416700D03*
X346500D03*
X362000Y800200D03*
X393500Y844700D03*
X365500Y800200D03*
X343000Y846700D03*
X346500D03*
X367500Y1171200D03*
X371000D03*
X393500Y1221700D03*
X343000Y1218200D03*
X346500D03*
X376000Y1670200D03*
X343000Y1716700D03*
X346500D03*
X372500Y1670200D03*
X828000Y341200D03*
Y746700D03*
Y1152200D03*
Y1557700D03*
X792839Y1931707D03*
X905240Y136463D03*
X874200Y336700D03*
X904240Y541975D03*
X874100Y743200D03*
X904240Y947487D03*
X874100Y1147700D03*
X904240Y1352998D03*
X874200Y1553900D03*
X841500Y1698700D03*
X904240Y1758510D03*
X862500Y1951500D03*
X994600Y1417500D03*
G54D83*
X893500Y1710000D03*
G54D92*
X1009744Y1646102D03*
Y1641102D03*
Y1636102D03*
Y1631102D03*
Y1626102D03*
Y1621102D03*
Y1676102D03*
Y1671102D03*
Y1666102D03*
Y1661102D03*
Y1656102D03*
Y1651102D03*
G54D93*
G01X292200Y586484D02*
X288000D01*
G01X320100Y583400D02*
X313700D01*
X312584Y584516D01*
X307800D01*
G01X300984Y1429300D02*
Y1433500D01*
G01X297600Y1401500D02*
Y1406900D01*
X299016Y1408316D01*
Y1413700D01*
G01X358500Y88350D02*
Y93500D01*
G01X360750Y117000D02*
Y112250D01*
X358500Y110000D01*
Y104650D01*
G01X360470Y88350D02*
Y84530D01*
X363500Y81500D01*
G01X362435Y88350D02*
X368750D01*
X368800Y88300D01*
G01X362435Y104650D02*
X368350D01*
G01X395600Y401650D02*
X391359D01*
X390694Y400985D01*
X387415D01*
G01X344500Y406250D02*
X345705D01*
X349000Y402955D01*
X352585D01*
G01X387917Y385235D02*
X392015D01*
X393500Y383750D01*
G01X367045Y382585D02*
Y388000D01*
X366045Y389000D01*
X365000D01*
G01X367045Y417415D02*
Y411455D01*
X367500Y411000D01*
X370000D01*
G01X395600Y398150D02*
X391506D01*
X390641Y399015D01*
X387415D01*
G01X368500Y371250D02*
Y374500D01*
X369015Y375015D01*
Y382585D01*
G01X384765Y382083D02*
X387167D01*
X389000Y380250D01*
X393500D01*
G01X372000Y371250D02*
Y374000D01*
X370985Y375015D01*
Y382585D01*
G01X352585Y400985D02*
X346265D01*
X344500Y402750D01*
G01X346500Y416750D02*
Y416250D01*
X349955Y412795D01*
X352585D01*
G01X387917Y414765D02*
X393485D01*
X393500Y414750D01*
G01X368500Y429250D02*
Y425500D01*
X369015Y424985D01*
Y417415D01*
G01X372000Y429250D02*
Y426000D01*
X371985D01*
X370985Y425000D01*
Y417415D01*
G01X393500Y418250D02*
X389750D01*
X389417Y417917D01*
X384765D01*
G01X346500Y420250D02*
X347250D01*
X349000Y418500D01*
Y417000D01*
X351235Y414765D01*
X352083D01*
G01X387917Y844765D02*
X393485D01*
X393500Y844750D01*
G01X344500Y836250D02*
X345705D01*
X349000Y832955D01*
X352585D01*
G01X346500Y846750D02*
Y846250D01*
X349955Y842795D01*
X352585D01*
G01X387415Y830985D02*
X390485D01*
X392750Y833250D01*
X393500D01*
G01X391750Y806500D02*
Y809250D01*
X387917Y813083D01*
Y815235D01*
G01X367045Y812585D02*
Y818000D01*
X366045Y819000D01*
X365000D01*
G01X367045Y847415D02*
Y841455D01*
X367500Y841000D01*
X370000D01*
G01X362000Y803750D02*
Y806000D01*
X364500Y808500D01*
X368000D01*
X369015Y809515D01*
Y812585D01*
G01X368500Y858250D02*
Y855500D01*
X369015Y854985D01*
Y847415D01*
G01X387415Y829015D02*
X392765D01*
X393500Y829750D01*
G01X365500Y803750D02*
Y805500D01*
X366750Y806750D01*
X369250D01*
X370985Y808485D01*
Y812585D01*
G01X384765Y812083D02*
Y811735D01*
X388250Y808250D01*
Y806500D01*
G01X372000Y858250D02*
Y856000D01*
X371985D01*
X370985Y855000D01*
Y847415D01*
G01X393500Y848250D02*
X389750D01*
X389417Y847917D01*
X384765D01*
G01X346500Y850250D02*
X347250D01*
X349000Y848500D01*
Y847000D01*
X351235Y844765D01*
X352083D01*
G01X344500Y832750D02*
X346265Y830985D01*
X352585D01*
G01Y1204455D02*
X349000D01*
X345705Y1207750D01*
X344500D01*
G01X393500Y1181250D02*
X391750D01*
X387917Y1185083D01*
Y1186735D01*
G01X367045Y1184085D02*
Y1189500D01*
X366045Y1190500D01*
X365000D01*
G01X387415Y1202485D02*
X395365D01*
X395600Y1202250D01*
G01X369015Y1184085D02*
Y1179015D01*
X367500Y1177500D01*
Y1174750D01*
G01X395600Y1198750D02*
X392250D01*
X390485Y1200515D01*
X387415D01*
G01X371000Y1174750D02*
X370985Y1174765D01*
Y1184085D01*
G01X384765Y1183583D02*
Y1182735D01*
X389750Y1177750D01*
X393500D01*
G01X352585Y1202485D02*
X346265D01*
X344500Y1204250D01*
G01X352585Y1214295D02*
X349955D01*
X346500Y1217750D01*
Y1218250D01*
G01X387917Y1216265D02*
Y1218917D01*
X390750Y1221750D01*
X393500D01*
G01X367045Y1218915D02*
Y1212955D01*
X367500Y1212500D01*
X370000D01*
G01X368500Y1229750D02*
Y1227000D01*
X369015Y1226485D01*
Y1218915D01*
G01X393500Y1225250D02*
X390598D01*
X384765Y1219417D01*
G01X372000Y1229750D02*
Y1227500D01*
X371985D01*
X370985Y1226500D01*
Y1218915D01*
G01X352083Y1216265D02*
X351235D01*
X349000Y1218500D01*
Y1220000D01*
X347250Y1221750D01*
X346500D01*
G01X352585Y1702955D02*
X349000D01*
X345705Y1706250D01*
X344500D01*
G01X352585Y1712795D02*
X349955D01*
X346500Y1716250D01*
Y1716750D01*
G01X389750Y1723500D02*
Y1720250D01*
X387917Y1718417D01*
Y1714765D01*
G01X388750Y1676500D02*
Y1679667D01*
X387917Y1680500D01*
Y1685235D01*
G01X367045Y1682585D02*
Y1688000D01*
X366045Y1689000D01*
X365000D01*
G01X367045Y1717415D02*
Y1711455D01*
X367500Y1711000D01*
X370000D01*
G01X387415Y1700985D02*
X395465D01*
X395700Y1700750D01*
G01X369015Y1682585D02*
Y1678485D01*
X372500Y1675000D01*
Y1673750D01*
G01X369015Y1717415D02*
Y1727735D01*
X369000Y1727750D01*
G01X395700Y1697250D02*
X392250D01*
X390485Y1699015D01*
X387415D01*
G01X384765Y1717917D02*
Y1722015D01*
X386250Y1723500D01*
G01X384765Y1682083D02*
Y1676985D01*
X385250Y1676500D01*
G01X372500Y1727750D02*
Y1726500D01*
X372000Y1726000D01*
X371985D01*
X370985Y1725000D01*
Y1717415D01*
G01Y1682585D02*
Y1679515D01*
X376000Y1674500D01*
Y1673750D01*
G01X346500Y1720250D02*
X347250D01*
X349000Y1718500D01*
Y1717000D01*
X351235Y1714765D01*
X352083D01*
G01X352585Y1700985D02*
X346265D01*
X344500Y1702750D01*
G01X890547Y1716106D02*
Y1719547D01*
X891000Y1720000D01*
G01D02*
X892516Y1718484D01*
Y1716056D01*
G01X884223Y1705223D02*
X886047Y1707047D01*
X887394D01*
G01X896500Y1696300D02*
Y1699000D01*
X894484Y1701016D01*
Y1703944D01*
G01X905484Y1709016D02*
X899556D01*
G01X896453Y1716106D02*
Y1717953D01*
X898000Y1719500D01*
G54D75*
X370000Y400000D03*
Y830000D03*
Y1201500D03*
Y1700000D03*
G54D84*
X846557Y1720000D03*
X868443D03*
G54D66*
X302953Y577700D03*
X300984D03*
X299016D03*
X297047D03*
Y593300D03*
X299016D03*
X300984D03*
X302953D03*
G54D48*
X108400Y412000D03*
X108700Y817500D03*
X97600Y1223600D03*
X108600Y1628200D03*
X297600Y1395700D03*
X288000Y1746200D03*
X293000D03*
X872500Y245200D03*
X896500Y1685200D03*
X877000Y1695200D03*
X901500Y1685200D03*
X959000Y1621600D03*
X990500Y1416700D03*
G54D39*
X73208Y220484D03*
X80708Y216609D03*
Y224359D03*
X94250Y223965D03*
X101750Y220090D03*
Y227840D03*
X94250Y629477D03*
X101750Y625602D03*
X73208Y625996D03*
X80708Y622121D03*
Y629871D03*
X101750Y633352D03*
X94250Y1034988D03*
X101750Y1031113D03*
Y1038863D03*
X73208Y1031507D03*
X80708Y1027632D03*
Y1035382D03*
X94250Y1440500D03*
X101750Y1436625D03*
Y1444375D03*
X73208Y1437019D03*
X80708Y1433144D03*
Y1440894D03*
X167250Y27600D03*
X174750Y23725D03*
Y31475D03*
X116375Y401225D03*
X123875Y397350D03*
Y405100D03*
X135875Y401225D03*
X143375Y397350D03*
Y405100D03*
X116750Y807100D03*
X124250Y803225D03*
Y810975D03*
X136250Y807100D03*
X143750Y803225D03*
Y810975D03*
X116750Y1212600D03*
X124250Y1208725D03*
X136250Y1212600D03*
X143750Y1208725D03*
X124250Y1216475D03*
X143750D03*
X136250Y1618100D03*
X143750Y1614225D03*
Y1621975D03*
X116750Y1618100D03*
X124250Y1614225D03*
Y1621975D03*
X180596Y1763500D03*
X186750Y27600D03*
X194250Y23725D03*
Y31475D03*
X209750Y555125D03*
X202250Y559000D03*
X209750Y562875D03*
X188096Y1759625D03*
Y1767375D03*
G54D57*
G01X1009744Y1646102D02*
X994898D01*
G01X1009744Y1631102D02*
X994898D01*
G01D02*
Y1633602D01*
X992500Y1636000D01*
G01X1009744Y1626102D02*
X996898D01*
X994898Y1628102D01*
Y1631102D01*
G01X1009744Y1676102D02*
X995102D01*
X104000Y1482000D03*
X154500Y536000D03*
X358000Y76000D03*
X810500Y183000D03*
Y1797000D03*
G54D94*
G01X100000Y119000D02*
X101326D01*
X105808Y114518D01*
G01X872500Y648000D02*
X867900D01*
G54D49*
X95700Y355250D03*
X99575Y362750D03*
X91825D03*
X95700Y760750D03*
X99575Y768250D03*
X91825D03*
X95700Y1166650D03*
X99575Y1174150D03*
X91825D03*
X95000Y1562750D03*
X98875Y1570250D03*
X91125D03*
X67600Y1844650D03*
X71475Y1852150D03*
X63725D03*
X65500Y1946750D03*
X69375Y1954250D03*
X61625D03*
X151000Y148750D03*
X154875Y156250D03*
X147125D03*
X140000Y556250D03*
X143875Y563750D03*
X136125D03*
X155000Y1364285D03*
X158875Y1371785D03*
X151125D03*
X191500Y140750D03*
X195375Y148250D03*
X187625D03*
X205000Y945227D03*
X208875Y952727D03*
X201125D03*
X219500Y945227D03*
X223375Y952727D03*
X215625D03*
X192154Y1353738D03*
X196029Y1361238D03*
X188279D03*
X221000Y1756250D03*
X224875Y1763750D03*
X217125D03*
X235500Y1756250D03*
X239375Y1763750D03*
X231625D03*
X824000Y355250D03*
X820125Y362750D03*
X827875D03*
X824000Y760750D03*
X820125Y768250D03*
X827875D03*
X824000Y1166250D03*
X820125Y1173750D03*
X827875D03*
X824000Y1571750D03*
X820125Y1579250D03*
X827875D03*
X788839Y1945757D03*
X784964Y1953257D03*
X792714D03*
X920500Y137203D03*
X916625Y144703D03*
X924375D03*
X920500Y542715D03*
X916625Y550215D03*
X924375D03*
X920500Y948227D03*
X916625Y955727D03*
X924375D03*
X920500Y1353738D03*
X916625Y1361238D03*
X924375D03*
X920500Y1759250D03*
X924375Y1766750D03*
X916625D03*
G54D85*
X894500Y1730800D03*
Y1727200D03*
G54D76*
X352585Y410825D03*
Y408860D03*
Y406890D03*
Y404920D03*
Y402955D03*
Y400985D03*
Y399015D03*
Y397045D03*
Y395080D03*
Y393110D03*
Y391140D03*
Y389175D03*
Y387205D03*
X387415D03*
Y389175D03*
Y391140D03*
Y393110D03*
Y395080D03*
Y397045D03*
Y399015D03*
Y400985D03*
Y402955D03*
Y404920D03*
Y406890D03*
Y408860D03*
Y410825D03*
X352585Y412795D03*
X387415D03*
X352585Y842795D03*
Y840825D03*
Y838860D03*
Y836890D03*
Y834920D03*
Y832955D03*
Y830985D03*
Y829015D03*
Y827045D03*
Y825080D03*
Y823110D03*
Y821140D03*
Y819175D03*
Y817205D03*
X387415D03*
Y819175D03*
Y821140D03*
Y823110D03*
Y825080D03*
Y827045D03*
Y829015D03*
Y830985D03*
Y832955D03*
Y834920D03*
Y836890D03*
Y838860D03*
Y840825D03*
Y842795D03*
X352585Y1210360D03*
Y1208390D03*
Y1206420D03*
Y1204455D03*
Y1202485D03*
Y1200515D03*
Y1198545D03*
Y1196580D03*
Y1194610D03*
Y1192640D03*
Y1190675D03*
Y1188705D03*
X387415D03*
Y1190675D03*
Y1192640D03*
Y1194610D03*
Y1196580D03*
Y1198545D03*
Y1200515D03*
Y1202485D03*
Y1204455D03*
Y1206420D03*
Y1208390D03*
Y1210360D03*
X352585Y1214295D03*
Y1212325D03*
X387415D03*
Y1214295D03*
X352585Y1712795D03*
Y1710825D03*
Y1708860D03*
Y1706890D03*
Y1704920D03*
Y1702955D03*
Y1700985D03*
Y1699015D03*
Y1697045D03*
Y1695080D03*
Y1693110D03*
Y1691140D03*
Y1689175D03*
Y1687205D03*
X387415D03*
Y1689175D03*
Y1691140D03*
Y1693110D03*
Y1695080D03*
Y1697045D03*
Y1699015D03*
Y1700985D03*
Y1702955D03*
Y1704920D03*
Y1706890D03*
Y1708860D03*
Y1710825D03*
Y1712795D03*
G54D58*
X113957Y1488286D03*
Y1490846D03*
Y1493406D03*
Y1495966D03*
X181318Y547147D03*
Y544587D03*
Y542027D03*
Y539467D03*
X165138D03*
Y542027D03*
Y544587D03*
Y547147D03*
X130137Y1495966D03*
Y1493406D03*
Y1490846D03*
Y1488286D03*
X836830Y191633D03*
Y189073D03*
X820650D03*
Y191633D03*
X836830Y196753D03*
Y194193D03*
X820650D03*
Y196753D03*
X836830Y1810927D03*
Y1808367D03*
Y1805807D03*
Y1803247D03*
X820650D03*
Y1805807D03*
Y1808367D03*
Y1810927D03*
G54D67*
X300000Y585500D03*
Y1421500D03*
G54D95*
G01X109500Y1486000D02*
X111786Y1488286D01*
X113957D01*
G01X162904Y135893D02*
X158993D01*
X158300Y135200D01*
G01X165138Y539467D02*
Y536500D01*
G01X156060Y556750D02*
Y554340D01*
X157500Y552900D01*
Y551200D01*
G01X180750Y553500D02*
Y550568D01*
X181318Y550000D01*
Y547147D01*
G01X151750Y569500D02*
Y567501D01*
X150940Y566691D01*
Y563250D01*
G01X128250Y1502000D02*
Y1499750D01*
X130137Y1497863D01*
Y1495966D01*
G01X192560Y949750D02*
X195500D01*
G01X273160Y1774600D02*
X268800D01*
G01X280840Y1752400D02*
X287600D01*
X288000Y1752000D01*
G01X820650Y189073D02*
X818073D01*
X816000Y187000D01*
G01X836830Y196753D02*
Y198670D01*
X834750Y200750D01*
Y203000D01*
G01X820650Y1803247D02*
X818247D01*
X816000Y1801000D01*
G01X836830Y1810927D02*
Y1812670D01*
X834750Y1814750D01*
Y1817000D01*
G54D59*
X85640Y1847150D03*
X88200D03*
X90760D03*
Y1853650D03*
X85640D03*
X150940Y556750D03*
X153500D03*
X156060D03*
Y563250D03*
X150940D03*
X187440Y949750D03*
X190000D03*
X192560D03*
Y956250D03*
X187440D03*
G54D86*
X983800Y1414300D03*
Y1425300D03*
G54D77*
X357205Y382585D03*
X359175D03*
X361140D03*
X363110D03*
X365080D03*
X367045D03*
X369015D03*
X370985D03*
X372955D03*
X374920D03*
X376890D03*
X378860D03*
X380825D03*
X382795D03*
Y417415D03*
X380825D03*
X378860D03*
X376890D03*
X374920D03*
X372955D03*
X370985D03*
X369015D03*
X367045D03*
X365080D03*
X363110D03*
X361140D03*
X359175D03*
X357205D03*
Y812585D03*
X359175D03*
X361140D03*
X363110D03*
X365080D03*
X367045D03*
X369015D03*
X370985D03*
X372955D03*
X374920D03*
X376890D03*
X378860D03*
X380825D03*
X382795D03*
Y847415D03*
X380825D03*
X378860D03*
X376890D03*
X374920D03*
X372955D03*
X370985D03*
X369015D03*
X367045D03*
X365080D03*
X363110D03*
X361140D03*
X359175D03*
X357205D03*
Y1184085D03*
X359175D03*
X361140D03*
X363110D03*
X365080D03*
X367045D03*
X369015D03*
X370985D03*
X372955D03*
X374920D03*
X376890D03*
X378860D03*
X380825D03*
X382795D03*
Y1218915D03*
X380825D03*
X378860D03*
X376890D03*
X374920D03*
X372955D03*
X370985D03*
X369015D03*
X367045D03*
X365080D03*
X363110D03*
X361140D03*
X359175D03*
X357205D03*
Y1682585D03*
X359175D03*
X361140D03*
X363110D03*
X365080D03*
X367045D03*
X369015D03*
X370985D03*
X372955D03*
X374920D03*
X376890D03*
X378860D03*
X380825D03*
X382795D03*
Y1717415D03*
X380825D03*
X378860D03*
X376890D03*
X374920D03*
X372955D03*
X370985D03*
X369015D03*
X367045D03*
X365080D03*
X363110D03*
X361140D03*
X359175D03*
X357205D03*
G54D68*
X304921Y1413400D03*
X295079D03*
Y1429600D03*
X304921D03*
X355235Y382083D03*
X384765D03*
Y417917D03*
X355235D03*
Y812083D03*
X384765D03*
Y847917D03*
X355235D03*
Y1183583D03*
X384765D03*
Y1219417D03*
X355235D03*
Y1682083D03*
X384765D03*
Y1717917D03*
X355235D03*
X896453Y1703894D03*
X890547D03*
Y1716106D03*
X896453D03*
G54D96*
G01X97731Y1058006D02*
X102200D01*
X102403Y1058209D01*
G01X91231Y1052886D02*
X86498D01*
G01X91231Y1458398D02*
X85998D01*
G01X90760Y1847150D02*
X92550D01*
X93600Y1848200D01*
G01X175894Y141413D02*
X173419D01*
X173019Y141013D01*
X169404D01*
G01X182000Y956250D02*
X187440D01*
G01X169404Y1356548D02*
X175894D01*
G01X207596Y1774560D02*
Y1777496D01*
X207600Y1777500D01*
G01X194606Y1769440D02*
X201096D01*
G01X892250Y134893D02*
X885993D01*
G01X905240Y140013D02*
X905134D01*
G01D02*
X898750D01*
G01X891250Y540405D02*
Y537500D01*
G01X904240Y545525D02*
X897750D01*
G01X891250Y945917D02*
X886517D01*
G01X904240Y951037D02*
X897750D01*
G01X891250Y1351428D02*
Y1348500D01*
G01X897750Y1356548D02*
X904240D01*
G01X886600Y1756100D02*
X887440Y1756940D01*
X891250D01*
G01X904240Y1762060D02*
X897750D01*
G54D78*
X710500Y41500D03*
G54D69*
X291900Y1416579D03*
Y1426421D03*
X308100D03*
Y1416579D03*
X352083Y385235D03*
X387917D03*
X352083Y414765D03*
X387917D03*
X352083Y844765D03*
Y815235D03*
X387917D03*
Y844765D03*
X352083Y1186735D03*
X387917D03*
X352083Y1216265D03*
X387917D03*
X352083Y1714765D03*
Y1685235D03*
X387917D03*
Y1714765D03*
X887394Y1707047D03*
Y1712953D03*
X899606D03*
Y1707047D03*
G54D87*
X1001545Y1492322D03*
Y1452322D03*
Y1572322D03*
Y1532322D03*
G54D97*
G01X91231Y241863D02*
X87637D01*
X86500Y243000D01*
G01Y648500D02*
X87625Y647375D01*
X91231D01*
G01X80137Y1854268D02*
X82203D01*
X82821Y1853650D01*
X85640D01*
G54D88*
X1001544Y1602322D03*
G54D79*
X809000Y1723500D03*
X820000D03*
X809000Y1714500D03*
X820000D03*
X889853Y1660249D03*
X878853D03*
G54D98*
G01X-90900Y-277455D02*
Y-294955D01*
X-82166D01*
G01X-69033Y-283289D02*
Y-294955D01*
G01Y-278622D02*
X-69470Y-278330D01*
Y-277747D01*
X-69033Y-277455D01*
X-68596Y-277747D01*
Y-278330D01*
X-69033Y-278622D01*
G01X-54590Y-299330D02*
X-53061Y-300497D01*
X-51315Y-300788D01*
X-49787Y-300497D01*
X-48476Y-299039D01*
X-47603Y-296997D01*
Y-283289D01*
G01Y-285622D02*
X-48476Y-284455D01*
X-49787Y-283580D01*
X-51315Y-283289D01*
X-53061Y-283872D01*
X-54153Y-285038D01*
X-55027Y-287080D01*
X-55463Y-289122D01*
X-55245Y-290872D01*
X-54371Y-292914D01*
X-53061Y-294372D01*
X-51315Y-294955D01*
X-50005Y-294663D01*
X-48476Y-293497D01*
X-47603Y-292331D01*
G01X-37745Y-294955D02*
Y-277455D01*
G01Y-285913D02*
X-36653Y-284455D01*
X-35561Y-283580D01*
X-33815Y-283289D01*
X-32505Y-283580D01*
X-30976Y-284747D01*
X-30321Y-286497D01*
Y-294955D01*
G01X-16533Y-277455D02*
Y-294955D01*
G01X-19590Y-283289D02*
X-13476D01*
G01X-2745Y-294955D02*
Y-283289D01*
G01Y-286205D02*
X-1871Y-284747D01*
X-561Y-283580D01*
X1185Y-283289D01*
X2713Y-283580D01*
X4024Y-284747D01*
X4679Y-286788D01*
Y-294955D01*
G01X18467Y-283289D02*
Y-294955D01*
G01Y-278622D02*
X18030Y-278330D01*
Y-277747D01*
X18467Y-277455D01*
X18904Y-277747D01*
Y-278330D01*
X18467Y-278622D01*
G01X32255Y-294955D02*
Y-283289D01*
G01Y-286205D02*
X33129Y-284747D01*
X34439Y-283580D01*
X36185Y-283289D01*
X37713Y-283580D01*
X39024Y-284747D01*
X39679Y-286788D01*
Y-294955D01*
G01X50410Y-299330D02*
X51939Y-300497D01*
X53685Y-300788D01*
X55213Y-300497D01*
X56524Y-299039D01*
X57397Y-296997D01*
Y-283289D01*
G01Y-285622D02*
X56524Y-284455D01*
X55213Y-283580D01*
X53685Y-283289D01*
X51939Y-283872D01*
X50847Y-285038D01*
X49973Y-287080D01*
X49537Y-289122D01*
X49755Y-290872D01*
X50629Y-292914D01*
X51939Y-294372D01*
X53685Y-294955D01*
X54995Y-294663D01*
X56524Y-293497D01*
X57397Y-292331D01*
G01X84100Y-294955D02*
Y-277455D01*
X89340D01*
X91087Y-278330D01*
X92397Y-280372D01*
X92834Y-282705D01*
X92397Y-285038D01*
X91305Y-286788D01*
X89340Y-287664D01*
X84100D01*
G01X101164Y-294955D02*
Y-277455D01*
X105530D01*
X107277Y-278330D01*
X108587Y-279497D01*
X109679Y-281246D01*
X110552Y-283289D01*
X110770Y-286205D01*
X110552Y-289122D01*
X109679Y-291164D01*
X108587Y-292914D01*
X107277Y-294080D01*
X105530Y-294955D01*
X101164D01*
G01X119100D02*
Y-277455D01*
X124340D01*
X126087Y-278330D01*
X127397Y-280372D01*
X127834Y-282705D01*
X127397Y-285038D01*
X126305Y-286788D01*
X124340Y-287664D01*
X119100D01*
G01X142713Y-285622D02*
X143587Y-284747D01*
X144242Y-283289D01*
X144679Y-281246D01*
X144242Y-279497D01*
X143369Y-278330D01*
X141840Y-277455D01*
X135945D01*
Y-294955D01*
X143150D01*
X144679Y-293789D01*
X145552Y-292038D01*
X145989Y-289997D01*
X145552Y-287955D01*
X144242Y-286205D01*
X142713Y-285622D01*
X135945D01*
G01X171600Y-294955D02*
Y-277455D01*
X176840D01*
X178587Y-278330D01*
X179897Y-280372D01*
X180334Y-282705D01*
X179897Y-285038D01*
X178805Y-286788D01*
X176840Y-287664D01*
X171600D01*
G01X188008Y-277455D02*
X193467Y-294955D01*
X198926Y-277455D01*
G01X210967D02*
Y-294955D01*
G01X205945Y-277455D02*
X215989D01*
G01X21540Y-249955D02*
Y-232455D01*
X27217Y-247038D01*
X32894Y-232455D01*
Y-249955D01*
G01X44717D02*
X43407Y-249663D01*
X42097Y-248497D01*
X41223Y-246455D01*
X40787Y-244122D01*
X41223Y-241788D01*
X42097Y-239747D01*
X43407Y-238580D01*
X44717Y-238289D01*
X46027Y-238580D01*
X47337Y-239747D01*
X48210Y-241788D01*
X48429Y-244122D01*
X48210Y-246455D01*
X47337Y-248497D01*
X46027Y-249663D01*
X44717Y-249955D01*
G01X66147Y-232455D02*
Y-249955D01*
G01Y-247331D02*
X65274Y-248789D01*
X63963Y-249663D01*
X62435Y-249955D01*
X60689Y-249372D01*
X59379Y-247914D01*
X58505Y-246164D01*
X58287Y-244122D01*
X58505Y-242080D01*
X59379Y-240330D01*
X60689Y-238872D01*
X62435Y-238289D01*
X63963Y-238580D01*
X65055Y-239164D01*
X66147Y-240330D01*
G01X76442Y-242080D02*
X83429D01*
X82774Y-240038D01*
X81682Y-238872D01*
X80154Y-238289D01*
X78625Y-238580D01*
X77315Y-239455D01*
X76442Y-241497D01*
X76005Y-243247D01*
Y-244997D01*
X76442Y-246747D01*
X77534Y-248497D01*
X78844Y-249663D01*
X80372Y-249955D01*
X81900Y-249372D01*
X83429Y-247622D01*
G01X97217Y-249955D02*
Y-232455D01*
G01X252500Y-249955D02*
Y-232455D01*
X257740D01*
X259487Y-233330D01*
X260797Y-235372D01*
X261234Y-237705D01*
X260797Y-240038D01*
X259705Y-241788D01*
X257740Y-242664D01*
X252500D01*
G01X279170Y-233914D02*
X277860Y-233038D01*
X276332Y-232455D01*
X274585D01*
X272620Y-233330D01*
X271092Y-234788D01*
X270000Y-236539D01*
X269127Y-239455D01*
X268908Y-242080D01*
X269345Y-244705D01*
X270000Y-246455D01*
X271310Y-248205D01*
X272839Y-249372D01*
X274367Y-249955D01*
X275895D01*
X277424Y-249372D01*
X278734Y-248497D01*
X279826Y-247331D01*
G01X293613Y-240622D02*
X294487Y-239747D01*
X295142Y-238289D01*
X295579Y-236246D01*
X295142Y-234497D01*
X294269Y-233330D01*
X292740Y-232455D01*
X286845D01*
Y-249955D01*
X294050D01*
X295579Y-248789D01*
X296452Y-247038D01*
X296889Y-244997D01*
X296452Y-242955D01*
X295142Y-241205D01*
X293613Y-240622D01*
X286845D01*
G01X302817Y-255788D02*
X315917D01*
G01X321845Y-249955D02*
Y-232455D01*
X331889Y-249955D01*
Y-232455D01*
G01X344367Y-249955D02*
X342620Y-249663D01*
X341092Y-248497D01*
X339782Y-246747D01*
X338908Y-244705D01*
X338472Y-242372D01*
Y-240038D01*
X338908Y-237705D01*
X339782Y-235663D01*
X341092Y-233914D01*
X342620Y-232747D01*
X344367Y-232455D01*
X346113Y-232747D01*
X347642Y-233914D01*
X348952Y-235663D01*
X349826Y-237705D01*
X350262Y-240038D01*
Y-242372D01*
X349826Y-244705D01*
X348952Y-246747D01*
X347642Y-248497D01*
X346113Y-249663D01*
X344367Y-249955D01*
G01X265617Y-294955D02*
Y-277455D01*
X262997Y-280955D01*
G01Y-294955D02*
X268237D01*
G01X278314Y-292331D02*
X279623Y-293789D01*
X281152Y-294663D01*
X283117Y-294955D01*
X285082Y-294372D01*
X286610Y-293205D01*
X287702Y-291164D01*
X287920Y-288830D01*
X287484Y-286497D01*
X286392Y-285038D01*
X284863Y-283872D01*
X283335Y-283580D01*
X281807Y-283872D01*
X279842Y-285038D01*
X280497Y-277455D01*
X286392D01*
G01X296469Y-287664D02*
X297997Y-285622D01*
X299307Y-284455D01*
X301054Y-283872D01*
X302582Y-284455D01*
X303674Y-285622D01*
X304547Y-287372D01*
X304765Y-289413D01*
X304547Y-291164D01*
X303674Y-292914D01*
X302363Y-294372D01*
X300835Y-294955D01*
X299089Y-294372D01*
X297560Y-292622D01*
X296687Y-289997D01*
X296469Y-287080D01*
X296905Y-283289D01*
X297560Y-281246D01*
X298652Y-279205D01*
X300180Y-277747D01*
X301709Y-277455D01*
X303237Y-278038D01*
X304329Y-279497D01*
G01X313969Y-287664D02*
X315497Y-285622D01*
X316807Y-284455D01*
X318554Y-283872D01*
X320082Y-284455D01*
X321174Y-285622D01*
X322047Y-287372D01*
X322265Y-289413D01*
X322047Y-291164D01*
X321174Y-292914D01*
X319863Y-294372D01*
X318335Y-294955D01*
X316589Y-294372D01*
X315060Y-292622D01*
X314187Y-289997D01*
X313969Y-287080D01*
X314405Y-283289D01*
X315060Y-281246D01*
X316152Y-279205D01*
X317680Y-277747D01*
X319209Y-277455D01*
X320737Y-278038D01*
X321829Y-279497D01*
G01X331905Y-292914D02*
X333434Y-294372D01*
X335180Y-294955D01*
X336927Y-294372D01*
X338455Y-292622D01*
X339547Y-289997D01*
X339984Y-287372D01*
Y-284164D01*
X339547Y-281539D01*
X338455Y-279205D01*
X337145Y-278038D01*
X335617Y-277455D01*
X333870Y-278038D01*
X332560Y-279205D01*
X331687Y-280955D01*
X331250Y-283289D01*
X331687Y-285330D01*
X332779Y-287372D01*
X334089Y-288539D01*
X335617Y-288830D01*
X337363Y-288247D01*
X338674Y-286788D01*
X339984Y-284164D01*
G01X395208Y-232455D02*
X400667Y-249955D01*
X406126Y-232455D01*
G01X422534Y-249955D02*
X413800D01*
Y-232455D01*
X422534D01*
G01X419040Y-240913D02*
X413800D01*
G01X431300Y-249955D02*
Y-232455D01*
X436759D01*
X438505Y-233330D01*
X439597Y-234497D01*
X440034Y-236830D01*
X439597Y-239164D01*
X438287Y-240622D01*
X436759Y-241497D01*
X431300D01*
G01X436759D02*
X440034Y-249955D01*
G01X453167Y-250538D02*
X452730Y-250247D01*
Y-249663D01*
X453167Y-249372D01*
X453604Y-249663D01*
Y-250247D01*
X453167Y-250538D01*
G01X426917Y-294955D02*
Y-277455D01*
X424297Y-280955D01*
G01Y-294955D02*
X429537D01*
G01X528750Y-232455D02*
Y-249955D01*
X537484D01*
G01X554547D02*
Y-238289D01*
G01Y-240330D02*
X553674Y-239164D01*
X552363Y-238580D01*
X550835Y-238289D01*
X549307Y-238872D01*
X547997Y-240038D01*
X547123Y-241788D01*
X546687Y-244122D01*
X547123Y-246455D01*
X547997Y-248205D01*
X549307Y-249372D01*
X550835Y-249955D01*
X552363Y-249663D01*
X553674Y-248789D01*
X554547Y-247622D01*
G01X563532Y-255205D02*
X564842Y-255788D01*
X566589Y-255205D01*
X567680Y-254039D01*
X568554Y-252580D01*
X569863Y-247914D01*
X572702Y-238289D01*
G01X565715D02*
X569863Y-247914D01*
G01X582342Y-242080D02*
X589329D01*
X588674Y-240038D01*
X587582Y-238872D01*
X586054Y-238289D01*
X584525Y-238580D01*
X583215Y-239455D01*
X582342Y-241497D01*
X581905Y-243247D01*
Y-244997D01*
X582342Y-246747D01*
X583434Y-248497D01*
X584744Y-249663D01*
X586272Y-249955D01*
X587800Y-249372D01*
X589329Y-247622D01*
G01X600060Y-249955D02*
Y-238289D01*
G01Y-240622D02*
X601152Y-239455D01*
X602244Y-238580D01*
X603772Y-238289D01*
X604863Y-238580D01*
X606174Y-239455D01*
G01X555000Y-277455D02*
Y-294955D01*
X563734D01*
G01X576867D02*
Y-277455D01*
X574247Y-280955D01*
G01Y-294955D02*
X579487D01*
G01X670864Y-249955D02*
Y-232455D01*
X675230D01*
X676977Y-233330D01*
X678287Y-234497D01*
X679379Y-236246D01*
X680252Y-238289D01*
X680470Y-241205D01*
X680252Y-244122D01*
X679379Y-246164D01*
X678287Y-247914D01*
X676977Y-249080D01*
X675230Y-249955D01*
X670864D01*
G01X689892Y-242080D02*
X696879D01*
X696224Y-240038D01*
X695132Y-238872D01*
X693604Y-238289D01*
X692075Y-238580D01*
X690765Y-239455D01*
X689892Y-241497D01*
X689455Y-243247D01*
Y-244997D01*
X689892Y-246747D01*
X690984Y-248497D01*
X692294Y-249663D01*
X693822Y-249955D01*
X695350Y-249372D01*
X696879Y-247622D01*
G01X707392Y-247914D02*
X708484Y-249080D01*
X710012Y-249955D01*
X711322D01*
X712632Y-249372D01*
X713505Y-248497D01*
X713942Y-247331D01*
X713724Y-245580D01*
X712850Y-244705D01*
X708920Y-242955D01*
X708047Y-240913D01*
X708484Y-239455D01*
X709357Y-238580D01*
X710667Y-238289D01*
X711977Y-238580D01*
X713287Y-239455D01*
G01X728167Y-238289D02*
Y-249955D01*
G01Y-233622D02*
X727730Y-233330D01*
Y-232747D01*
X728167Y-232455D01*
X728604Y-232747D01*
Y-233330D01*
X728167Y-233622D01*
G01X742610Y-254330D02*
X744139Y-255497D01*
X745885Y-255788D01*
X747413Y-255497D01*
X748724Y-254039D01*
X749597Y-251997D01*
Y-238289D01*
G01Y-240622D02*
X748724Y-239455D01*
X747413Y-238580D01*
X745885Y-238289D01*
X744139Y-238872D01*
X743047Y-240038D01*
X742173Y-242080D01*
X741737Y-244122D01*
X741955Y-245872D01*
X742829Y-247914D01*
X744139Y-249372D01*
X745885Y-249955D01*
X747195Y-249663D01*
X748724Y-248497D01*
X749597Y-247331D01*
G01X759455Y-249955D02*
Y-238289D01*
G01Y-241205D02*
X760329Y-239747D01*
X761639Y-238580D01*
X763385Y-238289D01*
X764913Y-238580D01*
X766224Y-239747D01*
X766879Y-241788D01*
Y-249955D01*
G01X777392Y-242080D02*
X784379D01*
X783724Y-240038D01*
X782632Y-238872D01*
X781104Y-238289D01*
X779575Y-238580D01*
X778265Y-239455D01*
X777392Y-241497D01*
X776955Y-243247D01*
Y-244997D01*
X777392Y-246747D01*
X778484Y-248497D01*
X779794Y-249663D01*
X781322Y-249955D01*
X782850Y-249372D01*
X784379Y-247622D01*
G01X795110Y-249955D02*
Y-238289D01*
G01Y-240622D02*
X796202Y-239455D01*
X797294Y-238580D01*
X798822Y-238289D01*
X799913Y-238580D01*
X801224Y-239455D01*
G01X660367Y-277455D02*
X663423Y-294955D01*
X666917Y-277455D01*
X670410Y-294955D01*
X673467Y-277455D01*
G01X680050Y-294955D02*
Y-277455D01*
X685290D01*
X687037Y-278330D01*
X688347Y-280372D01*
X688784Y-282705D01*
X688347Y-285038D01*
X687255Y-286788D01*
X685290Y-287664D01*
X680050D01*
G01X697332Y-294955D02*
Y-277455D01*
G01X706502D02*
Y-294955D01*
G01Y-286205D02*
X697332D01*
G01X716579Y-289122D02*
X722255D01*
G01X732769Y-294955D02*
Y-277455D01*
X741065D01*
G01X738009Y-285913D02*
X732769D01*
G01X750050Y-277455D02*
Y-294955D01*
X758784D01*
G01X771917D02*
X770170Y-294663D01*
X768642Y-293497D01*
X767332Y-291747D01*
X766458Y-289705D01*
X766022Y-287372D01*
Y-285038D01*
X766458Y-282705D01*
X767332Y-280663D01*
X768642Y-278914D01*
X770170Y-277747D01*
X771917Y-277455D01*
X773663Y-277747D01*
X775192Y-278914D01*
X776502Y-280663D01*
X777376Y-282705D01*
X777812Y-285038D01*
Y-287372D01*
X777376Y-289705D01*
X776502Y-291747D01*
X775192Y-293497D01*
X773663Y-294663D01*
X771917Y-294955D01*
G01X785050D02*
Y-277455D01*
X790509D01*
X792255Y-278330D01*
X793347Y-279497D01*
X793784Y-281830D01*
X793347Y-284164D01*
X792037Y-285622D01*
X790509Y-286497D01*
X785050D01*
G01X790509D02*
X793784Y-294955D01*
G01X801458D02*
X806917Y-277455D01*
X812376Y-294955D01*
G01X810410Y-288830D02*
X803423D01*
G01X841867Y-294955D02*
Y-277455D01*
X839247Y-280955D01*
G01Y-294955D02*
X844487D01*
G01X859367D02*
Y-277455D01*
X856747Y-280955D01*
G01Y-294955D02*
X861987D01*
G01X872937Y-295538D02*
X880797Y-277455D01*
G01X894367Y-294955D02*
Y-277455D01*
X891747Y-280955D01*
G01Y-294955D02*
X896987D01*
G01X907719Y-287664D02*
X909247Y-285622D01*
X910557Y-284455D01*
X912304Y-283872D01*
X913832Y-284455D01*
X914924Y-285622D01*
X915797Y-287372D01*
X916015Y-289413D01*
X915797Y-291164D01*
X914924Y-292914D01*
X913613Y-294372D01*
X912085Y-294955D01*
X910339Y-294372D01*
X908810Y-292622D01*
X907937Y-289997D01*
X907719Y-287080D01*
X908155Y-283289D01*
X908810Y-281246D01*
X909902Y-279205D01*
X911430Y-277747D01*
X912959Y-277455D01*
X914487Y-278038D01*
X915579Y-279497D01*
G01X925437Y-295538D02*
X933297Y-277455D01*
G01X942719Y-280372D02*
X944029Y-278622D01*
X945557Y-277747D01*
X947304Y-277455D01*
X949487Y-278038D01*
X951015Y-279497D01*
X951452Y-281246D01*
X951234Y-282997D01*
X950360Y-284455D01*
X945994Y-287372D01*
X944029Y-289413D01*
X942719Y-292331D01*
X942282Y-294955D01*
X951452D01*
G01X964367Y-277455D02*
X962620Y-278038D01*
X961310Y-279497D01*
X960437Y-281246D01*
X959782Y-283580D01*
X959564Y-286205D01*
X959782Y-288830D01*
X960437Y-291164D01*
X961310Y-292914D01*
X962620Y-294372D01*
X964367Y-294955D01*
X966113Y-294372D01*
X967424Y-292914D01*
X968297Y-291164D01*
X968952Y-288830D01*
X969170Y-286205D01*
X968952Y-283580D01*
X968297Y-281246D01*
X967424Y-279497D01*
X966113Y-278038D01*
X964367Y-277455D01*
G01X981867Y-294955D02*
Y-277455D01*
X979247Y-280955D01*
G01Y-294955D02*
X984487D01*
G01X995219Y-287664D02*
X996747Y-285622D01*
X998057Y-284455D01*
X999804Y-283872D01*
X1001332Y-284455D01*
X1002424Y-285622D01*
X1003297Y-287372D01*
X1003515Y-289413D01*
X1003297Y-291164D01*
X1002424Y-292914D01*
X1001113Y-294372D01*
X999585Y-294955D01*
X997839Y-294372D01*
X996310Y-292622D01*
X995437Y-289997D01*
X995219Y-287080D01*
X995655Y-283289D01*
X996310Y-281246D01*
X997402Y-279205D01*
X998930Y-277747D01*
X1000459Y-277455D01*
X1001987Y-278038D01*
X1003079Y-279497D01*
G01X889564Y-249955D02*
Y-232455D01*
X893930D01*
X895677Y-233330D01*
X896987Y-234497D01*
X898079Y-236246D01*
X898952Y-238289D01*
X899170Y-241205D01*
X898952Y-244122D01*
X898079Y-246164D01*
X896987Y-247914D01*
X895677Y-249080D01*
X893930Y-249955D01*
X889564D01*
G01X915797D02*
Y-238289D01*
G01Y-240330D02*
X914924Y-239164D01*
X913613Y-238580D01*
X912085Y-238289D01*
X910557Y-238872D01*
X909247Y-240038D01*
X908373Y-241788D01*
X907937Y-244122D01*
X908373Y-246455D01*
X909247Y-248205D01*
X910557Y-249372D01*
X912085Y-249955D01*
X913613Y-249663D01*
X914924Y-248789D01*
X915797Y-247622D01*
G01X929367Y-232455D02*
Y-249955D01*
G01X926310Y-238289D02*
X932424D01*
G01X943592Y-242080D02*
X950579D01*
X949924Y-240038D01*
X948832Y-238872D01*
X947304Y-238289D01*
X945775Y-238580D01*
X944465Y-239455D01*
X943592Y-241497D01*
X943155Y-243247D01*
Y-244997D01*
X943592Y-246747D01*
X944684Y-248497D01*
X945994Y-249663D01*
X947522Y-249955D01*
X949050Y-249372D01*
X950579Y-247622D01*
G54D89*
X916500Y1725750D03*
G54D99*
G01X52066Y370649D02*
X34156Y388559D01*
Y644344D01*
X25987Y652513D01*
X14791D01*
X14019Y651741D01*
X8858D01*
G01Y654890D02*
X12798D01*
X14000Y653688D01*
X28312D01*
X36331Y645669D01*
Y390169D01*
X58308Y368192D01*
Y256808D01*
X56500Y255000D01*
Y216612D01*
G01X8858Y648591D02*
X13253D01*
X14662Y650000D01*
Y650722D01*
X15278Y651338D01*
X23662D01*
X31981Y643019D01*
Y387202D01*
X56024Y363159D01*
Y292549D01*
G01X111436Y260164D02*
X77970Y293630D01*
X64863D01*
X61134Y297359D01*
Y368442D01*
X38506Y391070D01*
Y647257D01*
X30088Y655675D01*
X22000D01*
X21325Y655000D01*
X15401D01*
X14662Y655739D01*
Y656838D01*
X13460Y658040D01*
X8858D01*
G01X27699Y737535D02*
X29936D01*
X37325Y730146D01*
Y652375D01*
X39086Y650614D01*
G01X8858Y752528D02*
X12972D01*
X15680Y749820D01*
X27680D01*
X41901Y735599D01*
Y716960D01*
G01X44576Y724360D02*
Y761198D01*
X25774Y780000D01*
X14000D01*
X13126Y780874D01*
X8858D01*
G01Y749378D02*
X14222D01*
X14955Y748645D01*
X22655D01*
X39500Y731800D01*
Y654139D01*
X43023Y650616D01*
Y393207D01*
X67022Y369208D01*
Y308554D01*
X106782Y268794D01*
G01X8858Y784024D02*
X12976D01*
X15825Y781175D01*
X27675D01*
X46751Y762099D01*
Y727673D01*
X47500Y726924D01*
Y660500D01*
G01X8858Y787174D02*
X12826D01*
X14596Y785404D01*
Y784999D01*
X16095Y783500D01*
X28426D01*
X48926Y763000D01*
Y728574D01*
X50560Y726940D01*
Y653500D01*
G01X43555Y776945D02*
X34872Y785628D01*
Y890906D01*
G01X8858Y919457D02*
X13957D01*
X16675Y922175D01*
X20099D01*
X27825Y929901D01*
Y995000D01*
G01X8858Y916308D02*
X12794D01*
X14596Y918110D01*
Y918434D01*
X16162Y920000D01*
X21000D01*
X30000Y929000D01*
Y991000D01*
G01X8858Y922607D02*
X14500D01*
X15393Y923500D01*
X17748D01*
X25650Y931402D01*
Y987350D01*
X25000Y988000D01*
G01X23291Y1062791D02*
X31707D01*
G01X41840Y1115552D02*
Y1119448D01*
X39286Y1122002D01*
X32335D01*
G01X8858Y1119457D02*
X12793D01*
X14596Y1121260D01*
Y1122096D01*
X15579Y1123079D01*
X29481D01*
X31467Y1125065D01*
X37657D01*
G01D02*
X41608D01*
G01X39959Y1128308D02*
X36827D01*
X35910Y1127391D01*
X30717D01*
X28580Y1125254D01*
X15754D01*
X13107Y1122607D01*
X8858D01*
G01X37396Y1130912D02*
X36355D01*
X35009Y1129566D01*
X29816D01*
X27679Y1127429D01*
X15929D01*
X14256Y1125756D01*
X8858D01*
G01X33971Y1131741D02*
X28915D01*
X26829Y1129655D01*
X16579D01*
X15830Y1128906D01*
X8858D01*
G01X40097Y1154992D02*
Y1157930D01*
X37070Y1160957D01*
Y1226805D01*
X33201Y1230674D01*
G01X36170Y1308434D02*
X36853Y1307751D01*
Y1285816D01*
X41420Y1281249D01*
Y1181843D01*
X46353Y1176910D01*
Y1081353D01*
X41000Y1076000D01*
Y1070000D01*
G01X42286Y1104286D02*
Y1106512D01*
X44178Y1108404D01*
Y1157152D01*
X39245Y1162085D01*
Y1277255D01*
X33699Y1282801D01*
Y1301782D01*
G01X8858Y1245441D02*
X13429D01*
X14162Y1244708D01*
X25792D01*
X30900Y1239600D01*
Y1236537D01*
X32959Y1234478D01*
G01X8858Y1248591D02*
X12909D01*
X15617Y1245883D01*
X29117D01*
X36000Y1239000D01*
Y1236000D01*
G01X8858Y1302134D02*
X12793D01*
X14596Y1303937D01*
Y1304200D01*
X16396Y1306000D01*
X21500D01*
X24500Y1303000D01*
X31000D01*
X33938Y1305938D01*
Y1311000D01*
G01X38500D02*
X39028Y1310472D01*
Y1286717D01*
X43595Y1282150D01*
Y1183828D01*
X48528Y1178895D01*
Y1080028D01*
X45000Y1076500D01*
G01X8858Y1305284D02*
X13025D01*
X15000Y1307259D01*
X27741D01*
X30000Y1305000D01*
G01X8858Y1308434D02*
X24934D01*
X25500Y1309000D01*
X30300D01*
X30700Y1308600D01*
G01X28000Y1444000D02*
Y1426605D01*
X20070Y1418675D01*
X15511D01*
X15506Y1418670D01*
X8858D01*
G01Y1415520D02*
X14018D01*
X15998Y1417500D01*
X27000D01*
G01X8858Y1412371D02*
X13371D01*
X14662Y1413662D01*
Y1414502D01*
X15739Y1415579D01*
X30579D01*
X32000Y1417000D01*
Y1417100D01*
X32500Y1417600D01*
G01X42644Y1521957D02*
X45193Y1524506D01*
Y1565807D01*
X33276Y1577724D01*
X8858D01*
G01X43000Y1554900D02*
Y1560500D01*
X26951Y1576549D01*
X15401D01*
X13426Y1574574D01*
X8858D01*
G01X39800Y1547400D02*
Y1557700D01*
X22500Y1575000D01*
X15901D01*
X14662Y1573761D01*
Y1573162D01*
X12925Y1571425D01*
X8858D01*
G01X47254Y1587961D02*
X34512Y1600703D01*
Y1653244D01*
X25725Y1662031D01*
X15169D01*
X14437Y1662763D01*
X8858D01*
G01Y1647015D02*
X14300D01*
X15033Y1647748D01*
X27924D01*
X31143Y1644529D01*
Y1644433D01*
X32337Y1643239D01*
Y1596270D01*
X38925Y1589682D01*
G01X47368Y1527323D02*
Y1571132D01*
X37500Y1581000D01*
G01D02*
X30162Y1588338D01*
Y1642338D01*
X27000Y1645500D01*
X23073D01*
X22000Y1646573D01*
X15673D01*
X12966Y1643866D01*
X8858D01*
G01Y1665913D02*
X12987D01*
X15694Y1663206D01*
X30532D01*
X41100Y1652638D01*
Y1633650D01*
G01X35900Y1706000D02*
X14858D01*
X14000Y1706858D01*
X8858D01*
G01X34224Y1709000D02*
X25324D01*
X23499Y1707175D01*
X15825D01*
X12993Y1710007D01*
X8858D01*
G01Y1713157D02*
X12793D01*
X14596Y1711354D01*
Y1711305D01*
X16401Y1709500D01*
X22700D01*
X28200Y1715000D01*
X38000D01*
G01X248500Y1713005D02*
X247680Y1713825D01*
X201540D01*
X139004Y1776361D01*
Y1789296D01*
X114665Y1813635D01*
Y1858956D01*
X95994Y1877627D01*
X65683D01*
X57272Y1869216D01*
X57271D01*
X54725Y1866670D01*
Y1803807D01*
X45315Y1794397D01*
X28697D01*
X20425Y1786125D01*
X14925D01*
X14398Y1785598D01*
X8858D01*
G01X248500Y1716808D02*
X247692Y1716000D01*
X202441D01*
X141179Y1777262D01*
Y1790197D01*
X116840Y1814536D01*
Y1859857D01*
X96895Y1879802D01*
X64782D01*
X56371Y1871391D01*
X56370D01*
X52550Y1867571D01*
Y1804708D01*
X44414Y1796572D01*
X27796D01*
X19524Y1788300D01*
X14846D01*
X14398Y1788748D01*
X8858D01*
G01X276500Y1709400D02*
X274100Y1707000D01*
X269560D01*
X268585Y1706025D01*
X201580D01*
X133789Y1773816D01*
X133788D01*
X132515Y1775089D01*
Y1789633D01*
X110315Y1811833D01*
Y1857154D01*
X94192Y1873277D01*
X67485D01*
X59075Y1864867D01*
Y1801225D01*
X47786Y1789936D01*
X31831D01*
X18478Y1776583D01*
X14625D01*
X14191Y1776149D01*
X8858D01*
G01X269000Y1709516D02*
X267684Y1708200D01*
X202481D01*
X134690Y1775991D01*
Y1790534D01*
X112490Y1812734D01*
Y1858055D01*
X95093Y1875452D01*
X66584D01*
X56900Y1865768D01*
Y1802126D01*
X46885Y1792111D01*
X30930D01*
X17577Y1778758D01*
X14939D01*
X14398Y1779299D01*
X8858D01*
G01X255495Y1738573D02*
X254681Y1737759D01*
Y1731645D01*
X245361Y1722325D01*
X199387D01*
X143833Y1777879D01*
Y1790991D01*
X119177Y1815647D01*
Y1860596D01*
X97796Y1881977D01*
X63881D01*
X55471Y1873567D01*
X55470D01*
X50375Y1868472D01*
Y1806009D01*
X43291Y1798925D01*
X27501D01*
X24118Y1795542D01*
X15024D01*
X14529Y1795047D01*
X8858D01*
G01X251692Y1738573D02*
X252506Y1737759D01*
Y1732546D01*
X244460Y1724500D01*
X200288D01*
X146008Y1778780D01*
Y1790090D01*
X146009Y1790091D01*
Y1791891D01*
X121352Y1816548D01*
Y1861497D01*
X98697Y1884152D01*
X62980D01*
X54570Y1875742D01*
X54569D01*
X48200Y1869373D01*
Y1806910D01*
X42390Y1801100D01*
X26600D01*
X23217Y1797717D01*
X15064D01*
X14585Y1798196D01*
X8858D01*
G01X33325Y1970275D02*
X30225D01*
X30200Y1970300D01*
G01X37300Y1964050D02*
X41800D01*
G01X33325Y1970275D02*
Y1968025D01*
X37300Y1964050D01*
G01X36825Y1970275D02*
X40825D01*
X41700Y1969400D01*
G01X113200Y59950D02*
X115925Y57225D01*
Y55525D01*
X115100Y54700D01*
X107924D01*
X103100Y49876D01*
X97824D01*
X95648Y47700D01*
X94389D01*
X94019Y48070D01*
X89764D01*
G01X120700Y59950D02*
X118100Y57350D01*
Y54624D01*
X116001Y52525D01*
X108825D01*
X104000Y47700D01*
X98724D01*
X96549Y45525D01*
X94525D01*
X93921Y44921D01*
X89764D01*
G01X112800Y49200D02*
X110600D01*
X107538Y46138D01*
X107529D01*
X106891Y45500D01*
X99600D01*
X95871Y41771D01*
X89764D01*
G01X78839Y61161D02*
X72500D01*
G01X78839Y66161D02*
X68839D01*
X56500Y78500D01*
Y167000D01*
X64771Y175271D01*
X70919D01*
X79945Y184297D01*
X102861D01*
X124625Y162533D01*
Y141900D01*
X120600Y137875D01*
Y124232D01*
X123174Y121658D01*
X239082D01*
X380250Y262826D01*
Y336100D01*
G01X78839Y96161D02*
X72500D01*
X58675Y109986D01*
Y165675D01*
X65875Y172875D01*
X110608D01*
X122450Y161033D01*
Y142801D01*
X118383Y138734D01*
Y123372D01*
X122272Y119483D01*
X239983D01*
X388250Y267750D01*
Y336000D01*
G01X77205Y118937D02*
X71624D01*
X69946Y120615D01*
G01D02*
X65060D01*
X60850Y124825D01*
Y164774D01*
X66776Y170700D01*
X109707D01*
X118832Y161575D01*
Y152559D01*
G01X69946Y120615D02*
X71417Y122086D01*
X77205D01*
G01X146400Y136250D02*
X130750D01*
X126800Y140200D01*
Y163700D01*
X104028Y186472D01*
X79044D01*
X77072Y184500D01*
X59400D01*
X54846Y189054D01*
Y214958D01*
X56500Y216612D01*
G01X92750Y201000D02*
X88500D01*
X87500Y202000D01*
G01X92750Y205500D02*
Y201000D01*
G01X75710Y206668D02*
X82832D01*
X87500Y202000D01*
G01X74711Y246388D02*
X71400D01*
X70500Y245488D01*
Y242988D01*
G01X78500Y239715D02*
Y237988D01*
X76750Y236238D01*
Y234322D01*
G01X78500Y239715D02*
Y245488D01*
X77600Y246388D01*
X74711D01*
G01X106782Y268794D02*
X117576Y258000D01*
X137700D01*
X143600Y252100D01*
G01X80708Y224359D02*
X82129D01*
X84325Y222163D01*
X86589D01*
X87589Y223163D01*
Y225909D01*
G01Y230965D02*
Y225909D01*
G01X83589Y234465D02*
X80300D01*
G01X87589D02*
X93529D01*
X94469Y235405D01*
Y243674D01*
X95218Y244423D01*
X97731D01*
G01X87589Y234465D02*
X83589D01*
G01X75710Y209868D02*
X87600D01*
G01D02*
X90268D01*
X90400Y210000D01*
X92750D01*
G01X101750Y220090D02*
X97410D01*
X97400Y220100D01*
Y220200D01*
G01X129000Y255500D02*
X116100D01*
X111436Y260164D01*
G01X86000Y253465D02*
X80750D01*
G01X91231Y246983D02*
Y251734D01*
X89500Y253465D01*
X86000D01*
G01X72000D02*
X62500D01*
X59625Y250590D01*
Y237715D01*
G01X77250Y253465D02*
X72000D01*
G01X73208Y220484D02*
X67784D01*
X64947Y217647D01*
X64734D01*
G01X63903Y212645D02*
Y216816D01*
X64734Y217647D01*
G01X69960Y209868D02*
X66680D01*
X63903Y212645D01*
G01X59859Y204921D02*
X58091D01*
X57021Y205991D01*
Y213110D01*
X59750Y215839D01*
Y223465D01*
G01D02*
Y228650D01*
X63500Y232400D01*
Y245215D01*
G01X59859Y204921D02*
X64140D01*
X65887Y206668D01*
X69960D01*
G01X70819Y230822D02*
X68178D01*
X67375Y231625D01*
Y237715D01*
G01X70819Y230822D02*
X76750D01*
G01X97731Y234237D02*
Y241863D01*
G01X94250Y223965D02*
X97731Y227446D01*
Y234237D01*
G01X92750Y214465D02*
X82852D01*
X80708Y216609D01*
G01X94250Y223965D02*
X90233Y219948D01*
X81483D01*
X80708Y219173D01*
Y216609D01*
G01X243156Y382060D02*
X240675D01*
X240256Y382480D01*
X240100Y382636D01*
Y389288D01*
X236213Y393175D01*
X191099D01*
X184424Y386500D01*
X75265D01*
X69233Y380468D01*
Y348586D01*
X95494Y322325D01*
X123425D01*
X124750Y321000D01*
G01X235656Y382060D02*
X237160D01*
X237925Y382825D01*
Y388387D01*
X235312Y391000D01*
X192000D01*
X185325Y384325D01*
X76166D01*
X71408Y379567D01*
Y349487D01*
X96395Y324500D01*
X123250D01*
X124750Y326000D01*
G01X39086Y650614D02*
X40848Y648852D01*
Y392306D01*
X64847Y368307D01*
Y297719D01*
X66610Y295956D01*
G01X90000Y372750D02*
X94500D01*
G01X85425Y377775D02*
Y375701D01*
X88376Y372750D01*
X90000D01*
G01X78675Y380704D02*
X81604Y377775D01*
X85425D01*
G01X94500Y372750D02*
X102750D01*
X104000Y371500D01*
Y367175D01*
X99575Y362750D01*
G01X91200Y341250D02*
X85950D01*
G01X95700D02*
X91200D01*
G01X99700D02*
X95700D01*
G01X107200Y342500D02*
X103000D01*
X101750Y341250D01*
X99700D01*
G01X84700Y348000D02*
Y342500D01*
X85950Y341250D01*
G01X90700Y349600D02*
X93100D01*
X93700Y349000D01*
X95950D01*
G01X90700Y349600D02*
Y345250D01*
X91200Y344750D01*
G01X95700Y355250D02*
Y351550D01*
X95950Y351300D01*
Y349000D01*
G01X84700Y357000D02*
X86450Y355250D01*
X95700D01*
G01X113650Y373900D02*
X107750D01*
G01X88925Y377775D02*
X93825D01*
G01X100250D02*
X93825D01*
G01X78839Y466673D02*
X72500D01*
G01X355250Y463900D02*
X352232D01*
X321132Y495000D01*
X155358D01*
X118957Y531401D01*
Y570543D01*
X113274Y576226D01*
Y576227D01*
X112000Y577501D01*
X70801D01*
X70800Y577500D01*
X69000D01*
X60325Y568825D01*
Y483848D01*
X72500Y471673D01*
X78839D01*
G01X108000Y456012D02*
X105088Y453100D01*
X94501D01*
X94019Y453582D01*
X89764D01*
G01X108000Y456012D02*
X111113Y452899D01*
X114149D01*
X115750Y454500D01*
G01X108000Y448512D02*
X105587Y450925D01*
X94512D01*
X94020Y450433D01*
X89764D01*
G01X115750Y449500D02*
X114526Y450724D01*
X110212D01*
X108000Y448512D01*
G01X89764Y447283D02*
X93583D01*
X94700Y448400D01*
X102600D01*
X104900Y446100D01*
X114300D01*
X115800Y444600D01*
G01X78839Y501673D02*
X72500D01*
X62500Y511673D01*
Y567924D01*
X69901Y575325D01*
X111099D01*
X116782Y569642D01*
Y530500D01*
X154929Y492353D01*
X320703D01*
X347250Y465806D01*
Y464000D01*
G01X77205Y524449D02*
X71015D01*
X71000Y524464D01*
G01X77205Y527598D02*
X74134D01*
X71000Y524464D01*
G01X92500Y606750D02*
Y608750D01*
X92750Y609000D01*
Y611000D01*
G01X92500Y606750D02*
X87850D01*
X86500Y608100D01*
G01X75710Y612180D02*
X82420D01*
X86500Y608100D01*
G01X80708Y629871D02*
X82129D01*
X84325Y627675D01*
X86589D01*
X87589Y628675D01*
Y631421D01*
G01X75710Y615380D02*
X78297D01*
X79555Y616638D01*
X82962D01*
G01X92750Y615500D02*
X89138D01*
X88000Y616638D01*
X82962D01*
G01X88600Y623300D02*
X94900D01*
X97202Y625602D01*
X101750D01*
G01X291955Y505017D02*
X283228D01*
X205445Y582800D01*
X188900D01*
X184100Y578000D01*
X168428D01*
X148090Y598338D01*
X128590D01*
X101750Y625178D01*
Y625602D01*
G01X67414Y628212D02*
X70992D01*
X73208Y625996D01*
G01X64734Y623159D02*
Y625532D01*
X67414Y628212D01*
G01X64734Y623159D02*
Y622775D01*
X69960Y617549D01*
Y615380D01*
G01X63623Y614620D02*
X64252D01*
X66692Y612180D01*
X69960D01*
G01X63623Y614620D02*
Y617569D01*
X61523Y619669D01*
Y630374D01*
G01X94250Y629477D02*
X90273Y625500D01*
X81523D01*
X80708Y624685D01*
Y622121D01*
G01X92750Y619977D02*
X82852D01*
X80708Y622121D01*
G01X94250Y629477D02*
X97731Y632958D01*
Y639749D01*
G01X74711Y651900D02*
X71400D01*
X70500Y651000D01*
Y648500D01*
G01X78500Y645227D02*
Y651000D01*
X77600Y651900D01*
X74711D01*
G01X76750Y639834D02*
Y641750D01*
X78500Y643500D01*
Y645227D01*
G01X48000Y649500D02*
X47240D01*
X41901Y654839D01*
Y716960D01*
G01X46500Y653500D02*
X44576Y655424D01*
Y724360D01*
G01X87589Y636477D02*
Y631421D01*
G01Y639977D02*
X93492D01*
X94492Y640977D01*
Y648969D01*
X95458Y649935D01*
X97731D01*
G01X83589Y639977D02*
X87589D01*
G01X83589D02*
X80300D01*
G01X86000Y658977D02*
X80750D01*
G01X91231Y652495D02*
Y657246D01*
X89500Y658977D01*
X86000D01*
G01X59625Y643227D02*
X60600Y644202D01*
Y657077D01*
X62500Y658977D01*
X72000D01*
G01X77250D02*
X72000D01*
G01X63500Y650727D02*
Y639000D01*
X61523Y637023D01*
Y630374D01*
G01X70621Y636334D02*
X76750D01*
G01X70621D02*
X68250D01*
X67375Y637209D01*
Y643227D01*
G01X97731Y639749D02*
Y647375D01*
G01X124750Y726500D02*
X123325Y727925D01*
X97499D01*
X75625Y749799D01*
Y783701D01*
X81099Y789175D01*
X173275D01*
X186500Y802400D01*
Y807525D01*
X185825Y808200D01*
X183344D01*
G01X124750Y731500D02*
X123350Y730100D01*
X98400D01*
X77800Y750700D01*
Y782800D01*
X82000Y787000D01*
X174176D01*
X188675Y801499D01*
Y807525D01*
X189350Y808200D01*
X190844D01*
G01X49500Y771000D02*
X43555Y776945D01*
G01X99575Y768250D02*
X101375D01*
X104000Y770875D01*
Y777000D01*
X102750Y778250D01*
X94500D01*
G01X84700Y753500D02*
Y748000D01*
X85950Y746750D01*
G01X91200D02*
X85950D01*
G01X95700D02*
X91200D01*
G01X99700D02*
X95700D01*
G01X107200Y748000D02*
X103100D01*
X101850Y746750D01*
X99700D01*
G01X90700Y755100D02*
X93100D01*
X93700Y754500D01*
X95950D01*
G01X90700Y755100D02*
Y750750D01*
X91200Y750250D01*
G01X84700Y762500D02*
X93950D01*
X95700Y760750D01*
G01X95950Y754500D02*
Y760500D01*
X95700Y760750D01*
G01X325750Y609000D02*
Y735750D01*
X248000Y813500D01*
X183000D01*
X161600Y792100D01*
X67745D01*
X47500Y812345D01*
Y901500D01*
G01X90000Y778250D02*
X94500D01*
G01X85425Y783275D02*
X90000Y778700D01*
Y778250D01*
G01X80215Y777137D02*
Y781715D01*
X81775Y783275D01*
X85425D01*
G01X113650Y779400D02*
X107750D01*
G01X100250Y783275D02*
X93825D01*
G01X88925D02*
X93825D01*
G01X78839Y872185D02*
X72500D01*
G01X78839Y877185D02*
X68315D01*
X60982Y884518D01*
Y1002773D01*
X67989Y1009780D01*
X83921D01*
X85194Y1008507D01*
Y1008506D01*
X165200Y928500D01*
X320650D01*
X355250Y893900D01*
G01X78839Y907185D02*
X68815D01*
X63157Y912843D01*
Y1001872D01*
X68890Y1007605D01*
X83019D01*
X164299Y926325D01*
X319491D01*
X347250Y898566D01*
Y894000D01*
G01X108000Y861524D02*
X105076Y858600D01*
X94513D01*
X94019Y859094D01*
X89764D01*
G01X108000Y861524D02*
X110749Y858775D01*
X114525D01*
X115750Y860000D01*
G01X108000Y854024D02*
X110576Y856600D01*
X114174D01*
X115750Y855024D01*
Y855000D01*
G01X108000Y854024D02*
X105599Y856425D01*
X94480D01*
X94000Y855945D01*
X89764D01*
G01X117000Y849400D02*
X114900Y851500D01*
X104100D01*
X101400Y854200D01*
X95100D01*
X93695Y852795D01*
X89764D01*
G01X72361Y929961D02*
X71000Y928600D01*
Y925500D01*
G01X77205Y929961D02*
X72361D01*
G01X77205Y933110D02*
X71854D01*
X71376Y932632D01*
Y930946D01*
X72361Y929961D01*
G01X92750Y1016500D02*
Y1014350D01*
X93000Y1014100D01*
Y1012250D01*
G01D02*
X87950D01*
X86000Y1014200D01*
G01X75710Y1017691D02*
X82509D01*
X86000Y1014200D01*
G01X41000Y1070000D02*
Y1064250D01*
G01X77750Y1044345D02*
Y1049386D01*
G01D02*
X75886D01*
X74000Y1047500D01*
G01X137500Y1014500D02*
X134000D01*
X108700Y1039800D01*
Y1055529D01*
X97812Y1066417D01*
G01X45000Y1076500D02*
Y1064250D01*
G01X88000Y1037507D02*
Y1034500D01*
X87000Y1033500D01*
X82590D01*
X80708Y1035382D01*
G01X88000Y1037507D02*
Y1042750D01*
G01X41000Y1060750D02*
Y1057500D01*
G01X45000Y1060750D02*
Y1057000D01*
G01X84000Y1046250D02*
X88000D01*
G01D02*
X92750D01*
X94492Y1047992D01*
Y1054792D01*
X95146Y1055446D01*
X97731D01*
G01X81689Y1049400D02*
Y1048561D01*
X84000Y1046250D01*
G01X75710Y1020891D02*
X78297D01*
X79555Y1022149D01*
X82962D01*
G01X92750Y1021000D02*
X88149D01*
X87000Y1022149D01*
X82962D01*
G01X101750Y1031113D02*
X104987D01*
X106100Y1030000D01*
G01X86000Y1064488D02*
X80750D01*
G01X86000D02*
X89612D01*
X91231Y1062869D01*
Y1058006D01*
G01X72000Y1064488D02*
X66488D01*
X63782Y1061782D01*
Y1051407D01*
X63125Y1050750D01*
G01X77250Y1064488D02*
X72000D01*
G01X73208Y1031507D02*
X67571D01*
X64734Y1028670D01*
G01X64040Y1023735D02*
Y1027976D01*
X64734Y1028670D01*
G01X64040Y1023735D02*
X64068Y1023707D01*
X68448D01*
X69960Y1022195D01*
Y1020891D01*
G01X67000Y1058250D02*
Y1049500D01*
X64500Y1047000D01*
Y1037500D01*
G01X69960Y1017691D02*
Y1015451D01*
X66945Y1012436D01*
G01D02*
Y1011812D01*
X64730Y1009597D01*
X62270D01*
X60982Y1010885D01*
Y1033982D01*
X64500Y1037500D01*
G01X77750Y1040845D02*
X71455D01*
X70875Y1041425D01*
Y1044000D01*
G01Y1050750D02*
Y1044000D01*
G01X94250Y1034988D02*
X90262Y1031000D01*
X81512D01*
X80708Y1030196D01*
Y1027632D01*
G01X92750Y1025488D02*
X82852D01*
X80708Y1027632D01*
G01X94250Y1034988D02*
X97731Y1038469D01*
Y1045260D01*
G01D02*
Y1052886D01*
G01X124750Y1132000D02*
X123425Y1133325D01*
X97994D01*
X77812Y1153507D01*
Y1188191D01*
X77811Y1188192D01*
Y1189992D01*
X84819Y1197000D01*
X265181D01*
X273875Y1188306D01*
Y1183643D01*
X274458Y1183060D01*
X276344D01*
G01X268844D02*
X271179D01*
X271700Y1183581D01*
Y1187405D01*
X264280Y1194825D01*
X85720D01*
X79987Y1189092D01*
Y1154408D01*
X98895Y1135500D01*
X123250D01*
X124750Y1137000D01*
G01X42286Y1089500D02*
Y1104286D01*
G01Y1085500D02*
X39319Y1088467D01*
Y1106897D01*
X41840Y1109418D01*
Y1115552D01*
G01X97812Y1066417D02*
X93869Y1070360D01*
X67090D01*
G01X40097Y1142513D02*
Y1154992D01*
G01X90000Y1183750D02*
X94500D01*
G01X85300Y1182000D02*
X88250D01*
X90000Y1183750D01*
G01X85425Y1188775D02*
Y1185925D01*
X85300Y1185800D01*
Y1182000D01*
G01X94500Y1183750D02*
X102750D01*
X104000Y1182500D01*
Y1178575D01*
X99575Y1174150D01*
G01X91200Y1152650D02*
X85950D01*
G01X95700D02*
X91200D01*
G01X99700D02*
X95700D01*
G01X107200Y1153900D02*
X102900D01*
X101650Y1152650D01*
X99700D01*
G01X84700Y1159400D02*
Y1153900D01*
X85950Y1152650D01*
G01X90700Y1161000D02*
Y1156650D01*
X91200Y1156150D01*
G01X90700Y1161000D02*
X93100D01*
X93700Y1160400D01*
X95950D01*
G01X95700Y1166650D02*
Y1162950D01*
X95950Y1162700D01*
Y1160400D01*
G01X84700Y1168400D02*
X93950D01*
X95700Y1166650D01*
G01X113650Y1184900D02*
X107750D01*
G01X88925Y1188775D02*
X93825D01*
G01X100250D02*
X93825D01*
G01X78839Y1277697D02*
X72500D01*
G01X78839Y1282697D02*
X72500D01*
X69500Y1285697D01*
Y1312500D01*
X64400Y1317600D01*
Y1324400D01*
X62000Y1326800D01*
Y1385076D01*
X65600Y1388676D01*
X67400D01*
X67401Y1388675D01*
X109401D01*
X120158Y1377918D01*
Y1339842D01*
X133856Y1326144D01*
X291488D01*
X351485Y1266147D01*
X354284D01*
X355029Y1265402D01*
G01X108000Y1267036D02*
X110936Y1264100D01*
X114350D01*
X115750Y1265500D01*
G01X108000Y1267036D02*
X105039Y1264075D01*
X94550D01*
X94019Y1264606D01*
X89764D01*
G01X108000Y1259536D02*
X110389Y1261925D01*
X114325D01*
X115750Y1260500D01*
G01X108000Y1259536D02*
X105636Y1261900D01*
X94463D01*
X94020Y1261457D01*
X89764D01*
G01Y1258307D02*
X93907D01*
X95100Y1259500D01*
X101700D01*
X104300Y1256900D01*
X114900D01*
X116300Y1255500D01*
G01X78839Y1312697D02*
X73303D01*
X67100Y1318900D01*
Y1333200D01*
X64500Y1335800D01*
Y1384500D01*
X66500Y1386500D01*
X108500D01*
X117983Y1377017D01*
Y1338941D01*
X132955Y1323969D01*
X290587D01*
X347250Y1267306D01*
Y1265500D01*
G01X77205Y1338622D02*
X74134D01*
X71000Y1335488D01*
G01X77205Y1335473D02*
X71015D01*
X71000Y1335488D01*
G01X58900Y1317000D02*
X60800Y1318900D01*
Y1323900D01*
X59825Y1324875D01*
Y1396082D01*
X63964Y1400221D01*
X79061D01*
X91104Y1412264D01*
X98364D01*
X102600Y1416500D01*
Y1435775D01*
X101750Y1436625D01*
G01X92750Y1417500D02*
X90500D01*
X87500Y1420500D01*
G01X75710Y1423203D02*
X84797D01*
X87500Y1420500D01*
G01X92750Y1422000D02*
Y1417500D01*
G01X82962Y1427661D02*
X79555D01*
X78297Y1426403D01*
X75710D01*
G01X92750Y1426500D02*
X89161D01*
X88000Y1427661D01*
X82962D01*
G01X63797Y1429238D02*
X66263D01*
X69098Y1426403D01*
X69960D01*
G01X64734Y1434182D02*
X63200Y1432648D01*
Y1429835D01*
X63797Y1429238D01*
G01X67590Y1417910D02*
Y1417154D01*
X65507Y1415071D01*
X62915D01*
X59877Y1418109D01*
Y1432401D01*
X62000Y1434524D01*
Y1441800D01*
G01X67590Y1417910D02*
X69047D01*
X69960Y1418823D01*
Y1423203D01*
G01X92750Y1492000D02*
X91550Y1493200D01*
X85724D01*
X82800Y1496124D01*
Y1539704D01*
X82368Y1540136D01*
X82005Y1540500D01*
G01X92750Y1497000D02*
X91125Y1495375D01*
X86625D01*
X84975Y1497025D01*
Y1539667D01*
X85808Y1540500D01*
G01X114000Y1476750D02*
X110000D01*
G01X104000Y1482000D02*
Y1485500D01*
X109346Y1490846D01*
X113957D01*
G01X73000Y1455100D02*
X76750D01*
G01D02*
Y1450857D01*
G01X82137Y1476495D02*
X98795D01*
X111837Y1463453D01*
X135114D01*
X140413Y1468752D01*
X148095D01*
G01X69365Y1474719D02*
X71141Y1476495D01*
X82137D01*
G01X96250Y1492000D02*
X97375Y1493125D01*
X101375D01*
X104000Y1490500D01*
G01X113957Y1493406D02*
X106906D01*
X104000Y1490500D01*
G01X96250Y1497000D02*
X97950Y1495300D01*
X100800D01*
X104000Y1498500D01*
G01X113957Y1495966D02*
X106534D01*
X104000Y1498500D01*
G01X87589Y1442444D02*
Y1440344D01*
X86745Y1439500D01*
X84000D01*
X82606Y1440894D01*
X80708D01*
G01X87589Y1447500D02*
Y1442444D01*
G01Y1451000D02*
X93492D01*
X94492Y1452000D01*
Y1459992D01*
X95458Y1460958D01*
X97731D01*
G01X83589Y1451000D02*
X87589D01*
G01X83589D02*
X80300D01*
G01X86000Y1470000D02*
X80750D01*
G01X86000D02*
X89200D01*
X91231Y1467969D01*
Y1463518D01*
G01X77250Y1470000D02*
X72000D01*
G01X59625Y1454250D02*
X60200Y1454825D01*
Y1467700D01*
X62500Y1470000D01*
X72000D01*
G01X73208Y1437019D02*
X66919D01*
X64734Y1434834D01*
Y1434182D01*
G01X62000Y1441800D02*
Y1447500D01*
X63500Y1449000D01*
Y1461750D01*
G01X70273Y1447357D02*
X76750D01*
G01X67375Y1454250D02*
Y1448425D01*
X68443Y1447357D01*
X70273D01*
G01X94250Y1440500D02*
X90750Y1437000D01*
X82000D01*
X80708Y1435708D01*
Y1433144D01*
G01X92750Y1431000D02*
X82852D01*
X80708Y1433144D01*
G01X94250Y1440500D02*
X97731Y1443981D01*
Y1450772D01*
G01D02*
Y1458398D01*
G01X46893Y1519979D02*
X49543Y1522629D01*
Y1585672D01*
X47254Y1587961D01*
G01X46845Y1514264D02*
X51718Y1519137D01*
Y1595562D01*
G01X83875Y1583625D02*
X85999D01*
X86580Y1584206D01*
X92437D01*
X98875Y1577768D01*
Y1570250D01*
G01X75256Y1583625D02*
Y1567742D01*
X77607Y1565391D01*
G01X99000Y1548750D02*
X100650D01*
X102900Y1551000D01*
Y1552300D01*
X104700Y1554100D01*
X106700D01*
G01X84000Y1555500D02*
Y1550000D01*
X85250Y1548750D01*
G01X90500D02*
X85250D01*
G01X95000D02*
X90500D01*
G01X99000D02*
X95000D01*
G01X95250Y1556500D02*
X93000D01*
X92400Y1557100D01*
X90300D01*
G01X95000Y1562750D02*
X95250Y1562500D01*
Y1556500D01*
G01X84000Y1564500D02*
X86800D01*
X88550Y1562750D01*
X95000D01*
G01X90500Y1552250D02*
X90000Y1552750D01*
Y1556800D01*
X90300Y1557100D01*
G01X43000Y1554900D02*
Y1526000D01*
G01Y1554900D02*
X42855D01*
G01X42960Y1517408D02*
X39800Y1520568D01*
Y1547400D01*
G01X38925Y1589682D02*
X42919Y1585688D01*
Y1583175D01*
G01X51718Y1595562D02*
Y1665272D01*
X51635Y1665355D01*
G01X158575Y1614225D02*
X154350Y1610000D01*
X83509D01*
X64525Y1591016D01*
G01X83875Y1583625D02*
X79375D01*
G01X75256D02*
X79375D01*
G01X103025Y1589654D02*
X108121D01*
X109125Y1588650D01*
G01X103025Y1584775D02*
X97125D01*
G01X103025D02*
Y1589654D01*
G01X89625Y1588650D02*
X83200D01*
G01D02*
X76781D01*
X75256Y1587125D01*
G01X78839Y1683209D02*
X72500D01*
G01X344750Y1636100D02*
X342650Y1634000D01*
X208500D01*
X120175Y1722325D01*
Y1784743D01*
X111243Y1793675D01*
X70975D01*
X62325Y1785025D01*
Y1715108D01*
X69000Y1708433D01*
Y1691709D01*
X72500Y1688209D01*
X78839D01*
G01Y1718209D02*
X72500D01*
X64500Y1726209D01*
Y1784000D01*
X71700Y1791200D01*
X110642D01*
X118000Y1783842D01*
Y1721424D01*
X207642Y1631782D01*
X348532D01*
X352750Y1636000D01*
G01X74100Y1796200D02*
X70424D01*
X60150Y1785926D01*
Y1713150D01*
X66400Y1706900D01*
G01X108000Y1672548D02*
X105127Y1669675D01*
X94962D01*
X94519Y1670118D01*
X89764D01*
G01X108000Y1672548D02*
X110873Y1669675D01*
X114425D01*
X115750Y1671000D01*
G01X108000Y1665048D02*
X105548Y1667500D01*
X95051D01*
X94520Y1666969D01*
X89764D01*
G01X108000Y1665048D02*
X110452Y1667500D01*
X114250D01*
X115750Y1666000D01*
G01X117000Y1661250D02*
X115750Y1662500D01*
X105800D01*
X103100Y1665200D01*
X94843D01*
X93462Y1663819D01*
X89764D01*
G01X77205Y1740985D02*
X71714D01*
G01D02*
X70776Y1741923D01*
Y1743603D01*
X71307Y1744134D01*
X77205D01*
G01X71015Y1738000D02*
Y1740286D01*
X71714Y1740985D01*
G01X93750Y1821500D02*
X91600D01*
X88100Y1825000D01*
G01X93737Y1825915D02*
Y1821513D01*
X93750Y1821500D01*
G01X88100Y1825000D02*
Y1827227D01*
X86612Y1828715D01*
X75710D01*
G01X98000Y1848800D02*
X97850Y1848650D01*
Y1839900D01*
G01X101850D02*
X97850D01*
G01X84350Y1840600D02*
X82900D01*
X82100Y1841400D01*
X79500D01*
G01D02*
X77484Y1843416D01*
X73984D01*
X65250Y1852150D01*
X63725D01*
G01X87850Y1840600D02*
Y1836300D01*
G01Y1840600D02*
Y1842977D01*
X88200Y1843327D01*
Y1847150D01*
G01X87850Y1836300D02*
Y1834300D01*
X89150Y1833000D01*
X102000D01*
X103900Y1831100D01*
Y1820200D01*
X101500Y1817800D01*
X85700D01*
X85000Y1817100D01*
G01X82964Y1831400D02*
X80315D01*
X79800Y1831915D01*
X75710D01*
G01X93750Y1830000D02*
X89074D01*
X87674Y1831400D01*
X82964D01*
G01X69225Y1859650D02*
Y1856625D01*
X67800Y1855200D01*
G01X140300Y1724100D02*
X143500Y1727300D01*
Y1747857D01*
X122350Y1769007D01*
Y1785644D01*
X112144Y1795850D01*
X98550D01*
X93625Y1800775D01*
Y1802200D01*
G01X90760Y1860311D02*
Y1862740D01*
X89600Y1863900D01*
X88350D01*
X84850Y1867400D01*
G01X90749Y1860311D02*
X90760D01*
G01D02*
Y1853650D01*
G01X93200Y1867400D02*
X97425Y1863175D01*
Y1853150D01*
G01X65100Y1838100D02*
Y1842150D01*
X67600Y1844650D01*
G01X70060Y1837270D02*
Y1832015D01*
X69960Y1831915D01*
G01X70060Y1837270D02*
X69936Y1837394D01*
X65806D01*
X65100Y1838100D01*
G01X101300Y1860650D02*
Y1862876D01*
X93074Y1871102D01*
X70160D01*
X61250Y1862192D01*
Y1828050D01*
X62900Y1826400D01*
G01X68225Y1823331D02*
X65969D01*
X62900Y1826400D01*
G01X68225Y1823331D02*
Y1825681D01*
X69960Y1827416D01*
Y1828715D01*
G01X105350Y1846300D02*
Y1839900D01*
G01Y1846300D02*
Y1849125D01*
X105175Y1849300D01*
Y1853150D01*
G01X77100Y1846150D02*
X74550D01*
X71475Y1849225D01*
Y1852150D01*
G01X83467Y1862457D02*
X78774Y1867150D01*
X73100D01*
G01X71475Y1852150D02*
Y1855775D01*
X72300Y1856600D01*
Y1866350D01*
X73100Y1867150D01*
G01X85640Y1847150D02*
Y1849172D01*
X87711Y1851243D01*
Y1858213D01*
X83467Y1862457D01*
G01X52000Y1880750D02*
X56000D01*
G01X52000D02*
Y1877500D01*
G01X48000Y1884250D02*
Y1886633D01*
X46868Y1887765D01*
G01X83911Y1886506D02*
X61555D01*
X60897Y1885848D01*
G01X113500Y1875970D02*
X110195D01*
X99659Y1886506D01*
X83911D01*
G01X55750Y1932750D02*
X61000D01*
G01X54500Y1939500D02*
Y1934000D01*
X55750Y1932750D01*
G01X61000D02*
X65500D01*
G01D02*
X69500D01*
G01X79500Y1934000D02*
X75000D01*
X73750Y1932750D01*
X69500D01*
G01X60500Y1941100D02*
Y1936750D01*
X61000Y1936250D01*
G01X48000Y1880750D02*
Y1877500D01*
G01X93200Y1867400D02*
X88350D01*
G01X41800Y1964050D02*
X50850D01*
X56600Y1958300D01*
X65325D01*
X69375Y1954250D01*
G01X65500Y1946750D02*
X65750Y1946500D01*
Y1940500D01*
G01X54500Y1948500D02*
X63750D01*
X65500Y1946750D01*
G01X60500Y1941100D02*
X62900D01*
X63500Y1940500D01*
X65750D01*
G01X60600Y1970300D02*
Y1967250D01*
X61050Y1966800D01*
Y1965300D01*
G01X60600Y1970300D02*
X62600D01*
X63825Y1969075D01*
X66950D01*
G01X55350Y1965300D02*
X61050D01*
G01X47850Y1969175D02*
X41925D01*
X41700Y1969400D01*
G01X180850Y22721D02*
X175754D01*
X174750Y23725D01*
G01X180850Y27600D02*
Y22721D01*
G01Y27600D02*
X186750D01*
G01X114300Y69250D02*
Y70940D01*
X115713Y72353D01*
Y76189D01*
X136199Y96675D01*
X237780D01*
X416013Y274908D01*
Y479611D01*
X351399Y544225D01*
X284400D01*
X284000Y543825D01*
Y541344D01*
G01X119300Y69250D02*
Y70941D01*
X117888Y72353D01*
Y75288D01*
X137100Y94500D01*
X238681D01*
X418188Y274007D01*
Y480512D01*
X352300Y546400D01*
X284700D01*
X284000Y547100D01*
Y548844D01*
G01X113200Y59950D02*
X115925Y62675D01*
Y64125D01*
X114300Y65750D01*
G01X120700Y59950D02*
X118100Y62550D01*
Y64550D01*
X119300Y65750D01*
G01X121600Y47850D02*
X125700D01*
G01X112800Y49200D02*
X118500D01*
X119850Y47850D01*
X121600D01*
G01X174135Y160211D02*
X177289D01*
X178547Y158953D01*
X181387D01*
G01D02*
X185304D01*
X186257Y158000D01*
X192250D01*
G01X170402Y151203D02*
X167298D01*
G01X175400Y152000D02*
X177004D01*
X177904Y151100D01*
Y147453D01*
G01X175400Y152000D02*
X172969D01*
X172172Y151203D01*
X170402D01*
G01X114579Y137775D02*
Y140322D01*
X118832Y144575D01*
Y152559D01*
G01X140375Y148750D02*
Y141625D01*
X141500Y140500D01*
G01X146400Y139750D02*
X142250D01*
X141500Y140500D01*
G01X150557Y136250D02*
X155750D01*
X157953Y138453D01*
X162904D01*
G01X146400Y136250D02*
X150557D01*
G01X174135Y163411D02*
X185445D01*
X186487Y164453D01*
G01X154875Y156250D02*
Y160500D01*
G01X169404Y135893D02*
X172707D01*
X173600Y135000D01*
X182582D01*
G01D02*
X190250D01*
G01X168385Y163411D02*
Y168032D01*
X167606Y168811D01*
G01X158497Y163411D02*
X145511D01*
X138350Y156250D01*
X136500D01*
G01X167606Y168811D02*
X163897D01*
X158497Y163411D01*
G01X168385Y160211D02*
X163414D01*
X162054Y158851D01*
Y156726D01*
X163994Y154786D01*
G01X187608Y154749D02*
X164031D01*
X163994Y154786D01*
G01X187625Y148250D02*
Y139381D01*
X186644Y138400D01*
X182526D01*
X181404Y139522D01*
Y142546D01*
G01Y147453D02*
Y142546D01*
G01X162904Y141013D02*
X157065D01*
X155421Y142657D01*
G01X151000Y148750D02*
X147750Y152000D01*
X137700D01*
X134450Y148750D01*
X132625D01*
G01Y162475D02*
Y148750D01*
G01X155421Y142657D02*
X151000Y147078D01*
Y148750D01*
G01X165256Y273917D02*
X171595D01*
X184500Y261012D01*
Y235924D01*
X189690Y230734D01*
X291565D01*
X352750Y291919D01*
Y336000D01*
G01X166890Y251141D02*
X171159D01*
X172900Y249400D01*
G01X166890Y247992D02*
X171492D01*
X172900Y249400D01*
G01X165256Y308917D02*
X171595D01*
G01X344750Y336100D02*
Y286995D01*
X290664Y232909D01*
X190591D01*
X186717Y236783D01*
Y288795D01*
X171595Y303917D01*
X165256D01*
G01X128250Y321000D02*
X129475Y322225D01*
X134148D01*
X136795Y319578D01*
G01D02*
X139517Y322300D01*
X149707D01*
X149953Y322054D01*
X150000Y322008D01*
X154331D01*
G01X128250Y326000D02*
X129850Y324400D01*
X134117D01*
X136795Y327078D01*
G01D02*
X139398Y324475D01*
X149298D01*
X149980Y325157D01*
X154331D01*
G01X126445Y331567D02*
X128433D01*
X130400Y329600D01*
X138800D01*
X141600Y326800D01*
X148800D01*
X150307Y328307D01*
X154331D01*
G01X126445Y331567D02*
X120370D01*
G01X114295D02*
X120370D01*
G01X153625Y402375D02*
X149125D01*
G01X158200Y397350D02*
Y398700D01*
X154525Y402375D01*
X153625D01*
G01X158200Y397350D02*
X160839Y399989D01*
Y405661D01*
X158500Y408000D01*
G01X144525Y412850D02*
X142725D01*
X139625Y409750D01*
Y403625D01*
X140875Y402375D01*
X149125D01*
G01X129975Y396346D02*
X124879D01*
X123875Y397350D01*
G01X129975Y401225D02*
Y396346D01*
G01Y401225D02*
X135875D01*
G01X113650Y373900D02*
Y378779D01*
G01D02*
X118746D01*
X119750Y377775D01*
G01X143375Y397350D02*
X149800D01*
G01X154700D02*
X149800D01*
G01X119250Y454500D02*
X120575Y453175D01*
X218325D01*
X225000Y446500D01*
Y439175D01*
X225675Y438500D01*
X228156D01*
G01X119250Y449500D02*
X120750Y451000D01*
X217424D01*
X222825Y445599D01*
Y439175D01*
X222150Y438500D01*
X220656D01*
G01X158150Y434350D02*
X152900D01*
G01X159400Y427600D02*
Y433100D01*
X158150Y434350D01*
G01X152900D02*
X148400D01*
G01D02*
X144400D01*
G01D02*
X142150D01*
X140900Y433100D01*
X136900D01*
G01X159400Y418600D02*
X150150D01*
X148400Y420350D01*
G01X153400Y426000D02*
Y430350D01*
X152900Y430850D01*
G01X153400Y426000D02*
X151000D01*
X150400Y426600D01*
X148150D01*
G01X148400Y420350D02*
Y423850D01*
X148150Y424100D01*
Y426600D01*
G01X120800Y444550D02*
X125300D01*
G01X115800Y444600D02*
X120750D01*
X120800Y444550D01*
G01X150000Y541250D02*
X141321D01*
G01D02*
X135250D01*
X129375Y547125D01*
Y556250D01*
G01X154500Y544750D02*
X150000D01*
G01X153500Y556750D02*
Y550000D01*
X150000Y546500D01*
Y544750D01*
G01X154500D02*
X157750D01*
G01X165138Y544587D02*
X168837D01*
X170325Y543099D01*
Y533500D01*
G01D02*
Y531875D01*
X174075Y528125D01*
X180625D01*
X181750Y527000D01*
G01X169000Y533500D02*
X170325D01*
G01X165138Y547147D02*
X169353D01*
X172500Y544000D01*
Y532776D01*
X174976Y530300D01*
X176657D01*
G01Y531625D02*
Y530300D01*
G01D02*
X181050D01*
X181750Y531000D01*
G01X193750Y535250D02*
X186973Y542027D01*
X181318D01*
G01Y539467D02*
X184533D01*
X192000Y532000D01*
Y529750D01*
X194000Y527750D01*
G01X154500Y536000D02*
X158599D01*
X160000Y537401D01*
Y541000D01*
X161027Y542027D01*
X165138D01*
G01X167250Y556330D02*
X164070D01*
X162300Y558100D01*
G01X170750Y556330D02*
X172815D01*
X172823Y556338D01*
X178427D01*
X178435Y556330D01*
X179565D01*
X179573Y556338D01*
X185677D01*
X185685Y556330D01*
X185870D01*
X187075Y555125D01*
X194000D01*
G01X150940Y556750D02*
Y550940D01*
X149500Y549500D01*
X144750D01*
G01D02*
X141500D01*
X140200Y550800D01*
Y556050D01*
X140000Y556250D01*
G01X121625D02*
X121775Y556400D01*
X123400D01*
X126900Y559900D01*
X136350D01*
X140000Y556250D01*
G01X121625D02*
Y566178D01*
X122025Y566578D01*
Y569625D01*
G01X181318Y544587D02*
X190413D01*
X191500Y543500D01*
G01X174135Y565723D02*
X177500D01*
X178758Y564465D01*
X181387D01*
G01X191750Y564500D02*
X189035D01*
X189000Y564465D01*
X181387D01*
G01X165256Y679429D02*
X171595D01*
X184000Y667024D01*
Y619186D01*
X288404Y514782D01*
X331968D01*
X382750Y464000D01*
G01X174135Y568923D02*
X185445D01*
X186487Y569965D01*
G01X143875Y563750D02*
Y567375D01*
X150850Y574350D01*
G01X156060Y563250D02*
X159250D01*
X162300Y560200D01*
Y558100D01*
G01X135000Y570000D02*
X129500D01*
X125500Y566000D01*
Y563750D01*
G01X168385Y568923D02*
Y572332D01*
X165432Y575285D01*
X162144D01*
G01X135000Y570000D02*
X142500Y577500D01*
X159929D01*
X162144Y575285D01*
G01X170745Y560416D02*
X170055Y561106D01*
Y562264D01*
X168385Y563934D01*
Y565723D01*
G01X187500Y559000D02*
X186084Y560416D01*
X170745D01*
G01X165256Y709429D02*
X171595D01*
X186175Y694849D01*
Y620087D01*
X289305Y516957D01*
X333543D01*
X386600Y463900D01*
X390750D01*
G01X166890Y656653D02*
X171547D01*
X173000Y655200D01*
G01X166890Y653504D02*
X171304D01*
X173000Y655200D01*
G01X165256Y714429D02*
X171595D01*
G01X128250Y726500D02*
X129750Y728000D01*
X133485D01*
X136395Y725090D01*
G01D02*
X139130Y727825D01*
X149695D01*
X150000Y727520D01*
X154331D01*
G01X128250Y731500D02*
X129575Y730175D01*
X133980D01*
X136395Y732590D01*
G01D02*
X138985Y730000D01*
X149331D01*
X150000Y730669D01*
X154331D01*
G01X122445Y737167D02*
X127433D01*
X127500Y737100D01*
G01X117945Y737167D02*
X122445D01*
G01X154331Y733819D02*
X150940D01*
X149521Y732400D01*
X142400D01*
X139700Y735100D01*
X130600D01*
X128600Y737100D01*
X127500D01*
G01X149500Y808250D02*
X154000D01*
G01X158500Y807750D02*
X156500D01*
X156000Y808250D01*
X154000D01*
G01X149500D02*
X148650Y807400D01*
X143800D01*
G01X144525Y818350D02*
X142725D01*
X140000Y815625D01*
Y809500D01*
X142100Y807400D01*
X143800D01*
G01X148400Y839850D02*
X144400D01*
G01X152900D02*
X148400D01*
G01X158150D02*
X152900D01*
G01X159400Y833100D02*
Y838600D01*
X158150Y839850D01*
G01X144400D02*
X142150D01*
X140900Y838600D01*
X136900D01*
G01X148150Y832100D02*
X150400D01*
X151400Y831100D01*
X153400D01*
G01D02*
Y835850D01*
X152900Y836350D01*
G01X148400Y825850D02*
X148150Y826100D01*
Y832100D01*
G01X159400Y824100D02*
X150150D01*
X148400Y825850D01*
G01X130350Y802221D02*
X125254D01*
X124250Y803225D01*
G01X130350Y807100D02*
Y802221D01*
G01Y807100D02*
X136250D01*
G01X113650Y779400D02*
Y784279D01*
G01D02*
X118746D01*
X119750Y783275D01*
G01X143750Y803225D02*
X150175D01*
G01X158500Y804250D02*
X155525D01*
X154500Y803225D01*
X150175D01*
G01X126221Y861250D02*
Y859292D01*
X125704Y858775D01*
X120475D01*
X119250Y860000D01*
G01X126221Y853750D02*
Y856161D01*
X125782Y856600D01*
X120850D01*
X119250Y855000D01*
G01X122251Y848996D02*
X126746D01*
X126800Y849050D01*
G01X122251Y848996D02*
X117404D01*
X117000Y849400D01*
G01X183838Y968275D02*
X180725D01*
X177765Y971235D01*
X174135D01*
G01X183838Y968275D02*
X188275D01*
X189500Y969500D01*
X192250D01*
G01X178000Y952750D02*
X172705D01*
G01X174500Y960000D02*
X169667D01*
G01X172705Y952750D02*
X170500D01*
X169667Y953583D01*
Y960000D01*
G01X174135Y974435D02*
X179000D01*
X180042Y975477D01*
X186487D01*
G01X191000Y964300D02*
X181050D01*
X180250Y963500D01*
G01X171477Y965000D02*
X169477Y967000D01*
X152600D01*
X149350Y963750D01*
X147625D01*
G01X176750Y963500D02*
X172977D01*
X171477Y965000D01*
G01X150000Y955000D02*
X147478D01*
X143520Y958958D01*
Y971222D01*
X155860Y983562D01*
X165727D01*
X168280Y981009D01*
Y979729D01*
G01X150000Y955000D02*
X156962Y948038D01*
X174962D01*
X182900Y940100D01*
X217100D01*
X219500Y942500D01*
Y945227D01*
G01X168385Y974435D02*
Y979624D01*
X168280Y979729D01*
G01X161226Y971250D02*
X161241Y971235D01*
X168385D01*
G01X156996Y976999D02*
X154325D01*
X151500Y974174D01*
Y971250D01*
G01X156996Y976999D02*
X157574Y976421D01*
Y974902D01*
X161226Y971250D01*
G01X155375Y963750D02*
X161507D01*
X161512Y963755D01*
G01X166167Y960000D02*
Y962572D01*
X164984Y963755D01*
X161512D01*
G01X166890Y1062165D02*
X171235D01*
X173000Y1060400D01*
G01X166890Y1059016D02*
X171616D01*
X173000Y1060400D01*
G01X165256Y1119941D02*
X171595D01*
G01X165256Y1114941D02*
X171595D01*
X186766Y1099770D01*
Y1024264D01*
X258218Y952812D01*
X331933D01*
X390750Y893995D01*
Y893900D01*
G01X165256Y1084941D02*
X171595D01*
X184591Y1071945D01*
Y1023363D01*
X257436Y950518D01*
X331151D01*
X382750Y898919D01*
Y894000D01*
G01X128250Y1132000D02*
X129650Y1133400D01*
X133097D01*
X135895Y1130602D01*
G01D02*
X138818Y1133525D01*
X149507D01*
X150000Y1133032D01*
X154331D01*
G01X128250Y1137000D02*
X129675Y1135575D01*
X133368D01*
X135895Y1138102D01*
G01D02*
X138297Y1135700D01*
X149519D01*
X150000Y1136181D01*
X154331D01*
G01X127500Y1142500D02*
X129300Y1140700D01*
X137800D01*
X140500Y1138000D01*
X148800D01*
X150131Y1139331D01*
X154331D01*
G01X158575Y1208725D02*
Y1210799D01*
X155624Y1213750D01*
X154000D01*
G01X163170Y1210999D02*
X160896Y1208725D01*
X158575D01*
G01X122400Y1142550D02*
X117900D01*
G01X122400D02*
X127450D01*
X127500Y1142500D01*
G01X130350Y1207721D02*
X125254D01*
X124250Y1208725D01*
G01X130350Y1212600D02*
Y1207721D01*
G01X113650Y1184900D02*
Y1189779D01*
G01D02*
X118746D01*
X119750Y1188775D01*
G01X155075Y1208725D02*
X150175D01*
G01X143750D02*
X150175D01*
G01X119250Y1265500D02*
X120550Y1264200D01*
X240244D01*
X242700Y1266656D01*
G01X119250Y1260500D02*
X120775Y1262025D01*
X239831D01*
X242700Y1259156D01*
G01X154000Y1213750D02*
X149500D01*
G01X144825Y1223850D02*
X142725D01*
X140000Y1221125D01*
Y1215000D01*
X141250Y1213750D01*
X149500D01*
G01X137200Y1244100D02*
X141100D01*
X142350Y1245350D01*
X144700D01*
G01X158450D02*
X153200D01*
G01X159700Y1238600D02*
Y1244100D01*
X158450Y1245350D01*
G01X153200D02*
X148700D01*
G01D02*
X144700D01*
G01X159700Y1229600D02*
X150450D01*
X148700Y1231350D01*
G01X153700Y1237000D02*
Y1241350D01*
X153200Y1241850D01*
G01X153700Y1237000D02*
X151300D01*
X150700Y1237600D01*
X148450D01*
G01X148700Y1231350D02*
Y1231950D01*
X148450Y1232200D01*
Y1237600D01*
G01X121500Y1255550D02*
X126000D01*
G01X121500D02*
X116350D01*
X116300Y1255500D01*
G01X130350Y1212600D02*
X136250D01*
G01X144375Y1357194D02*
Y1364285D01*
G01X151209Y1352302D02*
X145698D01*
X144375Y1353625D01*
Y1357194D01*
G01X154709Y1347802D02*
Y1344513D01*
G01Y1352302D02*
X157814D01*
X159500Y1353988D01*
X162904D01*
G01X154709Y1352302D02*
Y1347802D01*
G01X169404Y1351428D02*
X173572D01*
X178400Y1346600D01*
X186100D01*
G01X188279Y1361238D02*
Y1354500D01*
X187779Y1354000D01*
X182000D01*
X181404Y1354596D01*
Y1357558D01*
G01X162904Y1356548D02*
X156287D01*
X155000Y1357835D01*
G01X174135Y1376746D02*
X176754D01*
X178700Y1374800D01*
X181300D01*
G01X186750Y1373000D02*
X185000D01*
X183200Y1374800D01*
X181300D01*
G01X170402Y1366738D02*
X167401D01*
X167301Y1366838D01*
G01X170402Y1366738D02*
X173154D01*
X173575Y1367159D01*
X175554D01*
G01X177904Y1362488D02*
Y1366150D01*
X176895Y1367159D01*
X175554D01*
G01X174135Y1379946D02*
X176446D01*
X178900Y1382400D01*
X181500D01*
G01X186750Y1382000D02*
X184000D01*
X183600Y1382400D01*
X181500D01*
G01X158875Y1371785D02*
Y1376100D01*
G01X158497Y1379946D02*
X148661D01*
X140500Y1371785D01*
G01X168385Y1379946D02*
Y1384562D01*
X167624Y1385323D01*
G01D02*
X163874D01*
X158497Y1379946D01*
G01X169100Y1371600D02*
X170800Y1369900D01*
X187700D01*
X192154Y1365446D01*
Y1353738D01*
G01X164066Y1371577D02*
Y1375490D01*
X165322Y1376746D01*
X168385D01*
G01X164066Y1371577D02*
X169077D01*
X169100Y1371600D01*
G01X181404Y1362488D02*
Y1357558D01*
G01X155000Y1364285D02*
Y1357835D01*
G01X136625Y1364285D02*
X139940Y1367600D01*
X151685D01*
X155000Y1364285D01*
G01X136625Y1378010D02*
Y1364285D01*
G01X114000Y1476750D02*
Y1482000D01*
G01X130137Y1493406D02*
X125406D01*
X114000Y1482000D01*
G01X122000D02*
Y1485500D01*
X127346Y1490846D01*
X130137D01*
G01X122000Y1476750D02*
X118000D01*
G01X122000Y1482000D02*
Y1476750D01*
G01X130000Y1482000D02*
Y1483500D01*
X130137Y1483637D01*
Y1488286D01*
G01X130000Y1476750D02*
Y1482000D01*
G01Y1476750D02*
X126000D01*
G01X165256Y1490453D02*
X171595D01*
X183825Y1478223D01*
Y1430384D01*
X259360Y1354849D01*
X293651D01*
X382750Y1265750D01*
Y1265500D01*
G01X166890Y1467677D02*
X171723D01*
X173100Y1466300D01*
G01X166890Y1464528D02*
X171328D01*
X173100Y1466300D01*
G01X124750Y1537500D02*
X123450Y1538800D01*
X118400D01*
X117387Y1537787D01*
Y1536250D01*
G01X124750Y1542500D02*
X123225Y1540975D01*
X117925D01*
X117387Y1541513D01*
Y1543750D01*
G01X165256Y1525453D02*
X171595D01*
G01X390750Y1265400D02*
X389631Y1266519D01*
X385057D01*
X294509Y1357067D01*
X260218D01*
X186000Y1431285D01*
Y1506048D01*
X171595Y1520453D01*
X165256D01*
G01X128250Y1537500D02*
X129650Y1538900D01*
X132909D01*
X135695Y1536114D01*
G01D02*
X138681Y1539100D01*
X149444D01*
X150000Y1538544D01*
X154331D01*
G01X128250Y1542500D02*
X129675Y1541075D01*
X133156D01*
X135695Y1543614D01*
G01D02*
X138034Y1541275D01*
X149582D01*
X150000Y1541693D01*
X154331D01*
G01Y1544843D02*
X149942D01*
X148632Y1543533D01*
X141567D01*
X139100Y1546000D01*
X129000D01*
X127600Y1547400D01*
X122500D01*
G01X112550Y1548200D02*
X118100D01*
X118900Y1547400D01*
X122500D01*
G01X112550Y1548200D02*
Y1543700D01*
G01X146025Y1629350D02*
X142725D01*
X140000Y1626625D01*
Y1620500D01*
X141250Y1619250D01*
X149500D01*
G01X158575Y1614225D02*
Y1616299D01*
X155624Y1619250D01*
X154000D01*
G01X149500D02*
X154000D01*
G01X160900Y1644100D02*
Y1649600D01*
X159650Y1650850D01*
G01X149650Y1643100D02*
Y1637100D01*
X149900Y1636850D01*
G01X154900Y1642500D02*
Y1646850D01*
X154400Y1647350D01*
G01X154900Y1642500D02*
X152500D01*
X151900Y1643100D01*
X149650D01*
G01X160900Y1635100D02*
X157000D01*
X155250Y1636850D01*
X149900D01*
G01X130350Y1613221D02*
X125254D01*
X124250Y1614225D01*
G01X130350Y1613221D02*
Y1619100D01*
G01D02*
X132588D01*
X133588Y1618100D01*
X136250D01*
G01X143750Y1614225D02*
X150175D01*
G01X155075D02*
X150175D01*
G01X122844Y1672400D02*
X124338D01*
X125013Y1671725D01*
Y1670408D01*
X124080Y1669475D01*
X120775D01*
X119250Y1671000D01*
G01Y1666000D02*
X120550Y1667300D01*
X124981D01*
X127188Y1669507D01*
Y1671725D01*
X127863Y1672400D01*
X130344D01*
G01X159650Y1650850D02*
X154400D01*
G01D02*
X149900D01*
G01D02*
X145900D01*
G01X138400Y1649600D02*
X141900D01*
X143150Y1650850D01*
X145900D01*
G01X121950Y1661250D02*
X126900D01*
G01X121950D02*
X117000D01*
G01X174135Y1782258D02*
X177000D01*
X178258Y1781000D01*
X181387D01*
G01X191250Y1781500D02*
X186000D01*
X185500Y1781000D01*
X181387D01*
G01X232344Y1740000D02*
X234825D01*
X235100Y1739725D01*
Y1734100D01*
X231000Y1730000D01*
X201669D01*
X152400Y1779269D01*
Y1791800D01*
X125702Y1818498D01*
Y1867696D01*
X119500Y1873898D01*
Y1934400D01*
X120612Y1935512D01*
X121638D01*
X123050Y1934100D01*
G01X239844Y1740000D02*
X238350D01*
X237275Y1738925D01*
Y1733199D01*
X231901Y1727825D01*
X200768D01*
X150225Y1778368D01*
Y1790899D01*
X123527Y1817597D01*
Y1866795D01*
X117325Y1872997D01*
Y1935301D01*
X119711Y1937687D01*
X121637D01*
X123050Y1939100D01*
G01X157898Y1780145D02*
Y1788144D01*
X163284Y1793530D01*
X199470D01*
X215950Y1777050D01*
Y1776200D01*
G01X179042Y1786500D02*
X178000Y1785458D01*
X174135D01*
G01X186400Y1786700D02*
X179242D01*
X179042Y1786500D01*
G01X181596Y1774500D02*
X175000D01*
G01D02*
X173773Y1773273D01*
Y1771466D01*
X178423Y1766816D01*
X182692D01*
X188096Y1761412D01*
Y1759625D01*
G01X235500Y1756250D02*
X228250Y1749000D01*
X186500D01*
X171506Y1763994D01*
G01X168385Y1785458D02*
Y1789749D01*
X167442Y1790692D01*
G01D02*
X164199D01*
X160625Y1787118D01*
Y1774875D01*
X171506Y1763994D01*
G01X170080Y1773478D02*
X171554Y1772004D01*
Y1767870D01*
X175924Y1763500D01*
X180596D01*
G01X168385Y1782258D02*
X164158D01*
X162800Y1780900D01*
Y1776200D01*
X165000Y1774000D01*
G01X170080Y1773478D02*
X165522D01*
X165000Y1774000D01*
G01X347250Y1764000D02*
Y1786063D01*
X279199Y1854114D01*
X186168D01*
X183464Y1856818D01*
Y1884096D01*
X171595Y1895965D01*
X165256D01*
G01Y1930965D02*
X171595D01*
G01X355250Y1763900D02*
Y1781139D01*
X280100Y1856289D01*
X187069D01*
X185639Y1857719D01*
Y1911921D01*
X171595Y1925965D01*
X165256D01*
G01X166890Y1873189D02*
X172011D01*
X173500Y1871700D01*
G01X166890Y1870040D02*
X171840D01*
X173500Y1871700D01*
G01X131795Y1932826D02*
X134369Y1935400D01*
X136876D01*
X145876Y1944400D01*
X149156D01*
X149500Y1944056D01*
X154331D01*
G01X126550Y1934100D02*
X127875Y1935425D01*
X129196D01*
X131795Y1932826D01*
G01Y1940326D02*
X134546Y1937575D01*
X135975D01*
X144975Y1946575D01*
X148850D01*
X149480Y1947205D01*
X154331D01*
G01X126550Y1939100D02*
X128050Y1937600D01*
X129069D01*
X131795Y1940326D01*
G01X154331Y1950355D02*
X148755D01*
X147600Y1949200D01*
X141300D01*
X138100Y1946000D01*
G01X126500Y1943750D02*
X135850D01*
X138100Y1946000D01*
G01X122450Y1943900D02*
X126350D01*
X126500Y1943750D01*
G01X193125Y38750D02*
X190500Y36125D01*
Y30000D01*
X191750Y28750D01*
X200000D01*
G01X204500D02*
X200000D01*
G01X209075Y23725D02*
Y25799D01*
X206124Y28750D01*
X204500D01*
G01X213244Y23725D02*
X209075D01*
G01X197000Y46250D02*
X196750Y46500D01*
Y52500D01*
G01X208000Y44500D02*
X198750D01*
X197000Y46250D01*
G01X194250Y23725D02*
X200675D01*
G01X205575D02*
X200675D01*
G01X208000Y53500D02*
Y59000D01*
X206750Y60250D01*
G01D02*
X201500D01*
G01D02*
X197000D01*
G01D02*
X193000D01*
G01D02*
X190750D01*
X189500Y59000D01*
X185500D01*
G01X201500Y56750D02*
X202000Y56250D01*
Y52300D01*
X201600Y51900D01*
G01D02*
X199600D01*
X199000Y52500D01*
X196750D01*
G01X192250Y162500D02*
Y158000D01*
G01Y167000D02*
X189034D01*
X186487Y164453D01*
G01X193750Y135000D02*
X201920D01*
X203154Y136234D01*
Y139453D01*
G01X195375Y148250D02*
X201499D01*
X203154Y146595D01*
Y139453D01*
G01X191500Y140750D02*
Y153500D01*
X190251Y154749D01*
X187608D01*
G01X188854Y527099D02*
X188053Y527900D01*
X186150D01*
X185250Y527000D01*
G01X188854Y530902D02*
X188027Y530075D01*
X186175D01*
X185250Y531000D01*
G01X199000Y535250D02*
X193750D01*
G01X199000D02*
X203000D01*
G01X199000Y527750D02*
X194000D01*
G01X199000D02*
X203000D01*
G01X209750Y555125D02*
X194000D01*
G01X199000Y542750D02*
X203000D01*
G01X191500Y543500D02*
X192250Y542750D01*
X199000D01*
G01X191750Y569000D02*
Y564500D01*
G01X206700Y575000D02*
X204675D01*
X203750Y574075D01*
Y569000D01*
G01X206700Y575000D02*
X208100D01*
X209250Y573850D01*
Y569000D01*
G01X191750Y573500D02*
X190022D01*
X186487Y569965D01*
G01X202250Y559000D02*
X187500D01*
G01X209750Y562875D02*
X216200D01*
X217200Y563875D01*
Y565700D01*
G01X212750Y569000D02*
X215400D01*
X217200Y567200D01*
Y565700D01*
G01X192250Y974000D02*
Y969500D01*
G01X207350Y960977D02*
X212277D01*
X212300Y961000D01*
G01D02*
X214300D01*
X215625Y959675D01*
Y952727D01*
G01X198900Y965477D02*
X203850D01*
G01Y960977D02*
Y965477D01*
G01Y960977D02*
X198400D01*
X195500Y958077D01*
Y954300D01*
X194200Y953000D01*
X190500D01*
X190000Y952500D01*
Y949750D01*
G01X192250Y978500D02*
X189227Y975477D01*
X186487D01*
G01X208875Y952727D02*
Y957200D01*
G01X192560Y956250D02*
Y962740D01*
X191000Y964300D01*
G01X187440Y949750D02*
Y943460D01*
X188400Y942500D01*
X191500D01*
G01D02*
X202273D01*
X205000Y945227D01*
G01X223375Y952727D02*
X219648Y949000D01*
X215000D01*
X211227Y945227D01*
X205000D01*
G01X229500Y953227D02*
X223875D01*
X223375Y952727D01*
G01X191404Y1346488D02*
X186212D01*
X186100Y1346600D01*
G01X194904Y1346488D02*
X199900D01*
G01D02*
X201200Y1347788D01*
Y1353400D01*
X196029Y1358571D01*
Y1361238D01*
G01X186750Y1377500D02*
Y1373000D01*
G01X191250Y1786000D02*
Y1781500D01*
G01X194750Y1753000D02*
X196304D01*
X197804Y1751500D01*
X201447D01*
G01X200198Y1758750D02*
Y1756711D01*
X201447Y1755462D01*
Y1751500D01*
G01X200198Y1758750D02*
X202299D01*
X203299Y1759750D01*
G01X219450Y1772100D02*
X228181D01*
G01D02*
X230444D01*
X231625Y1770919D01*
Y1763750D01*
G01X215950Y1776200D02*
Y1772100D01*
G01X207596Y1772000D02*
X215850D01*
X215950Y1772100D01*
G01X186400Y1786700D02*
X187450D01*
X191250Y1790500D01*
G01X224875Y1763750D02*
Y1768100D01*
G01X190266Y1776603D02*
X195782D01*
X197825Y1774560D01*
X201096D01*
G01X185096Y1774500D02*
X186374D01*
X188477Y1776603D01*
X190266D01*
G01X194750Y1756500D02*
Y1762000D01*
G01X188096Y1767375D02*
X190967D01*
X194750Y1763592D01*
Y1762000D01*
G01X239375Y1763750D02*
X235725Y1760100D01*
X231600D01*
X227750Y1756250D01*
X221000D01*
G01D02*
X215650D01*
X210500Y1761400D01*
G01X207596Y1769440D02*
Y1764304D01*
X210500Y1761400D01*
G01X244850Y1769900D02*
X241089D01*
X239375Y1768186D01*
Y1763750D01*
G01X388500Y348750D02*
X391750D01*
X394718Y345782D01*
Y268973D01*
X292700Y166955D01*
X292600D01*
G01X330750Y381000D02*
X329060D01*
X328160Y381900D01*
X323724D01*
X320825Y384799D01*
Y390765D01*
X320150Y391440D01*
X318656D01*
G01X330750Y385000D02*
X329060D01*
X328135Y384075D01*
X324625D01*
X323000Y385700D01*
Y390765D01*
X323675Y391440D01*
X326156D01*
G01X328250Y421000D02*
X333500D01*
G01X328250Y413000D02*
X333500D01*
G01X328250Y417000D02*
Y413000D01*
G01X296470Y555500D02*
X295600Y556370D01*
Y562900D01*
X298450Y565750D01*
G01X292667Y555500D02*
X293425Y556258D01*
Y562905D01*
X290580Y565750D01*
G01X297300Y505017D02*
X291955D01*
G01X339500Y572667D02*
X338642Y573525D01*
X332195D01*
X329250Y570580D01*
G01X323750Y572500D02*
X324675Y573425D01*
X326405D01*
X329250Y570580D01*
G01X339500Y576470D02*
X338730Y575700D01*
X332150D01*
X329250Y578600D01*
G01X323750Y576500D02*
X324650Y575600D01*
X326250D01*
X329250Y578600D01*
G01Y605000D02*
X332500D01*
G01X329250Y609000D02*
Y605000D01*
G01X284000Y605250D02*
X287125Y602125D01*
Y599799D01*
X289724Y597200D01*
X294000D01*
X295079Y596121D01*
Y593600D01*
G01X286130Y615700D02*
X286925Y614905D01*
Y608175D01*
X284000Y605250D01*
G01X270000Y579030D02*
X270870Y579900D01*
X277350D01*
X280250Y577000D01*
G01X292200Y582547D02*
X290223D01*
X287576Y579900D01*
X283150D01*
X280250Y577000D01*
G01X299016Y577700D02*
Y574606D01*
X299222Y574400D01*
Y573041D01*
X295575Y569394D01*
Y568625D01*
X298450Y565750D01*
G01X310030Y615500D02*
X310925Y614605D01*
Y608175D01*
X308000Y605250D01*
G01X302953Y593300D02*
Y597029D01*
X305899Y599975D01*
X309875D01*
X310800Y600900D01*
Y602450D01*
X308000Y605250D01*
G01X298030Y621000D02*
X298925Y620105D01*
Y608175D01*
X296000Y605250D01*
G01X299016Y593300D02*
Y596791D01*
X299025Y596800D01*
Y602225D01*
X296000Y605250D01*
G01X269800Y590930D02*
X270770Y591900D01*
X277350D01*
X280250Y589000D01*
G01D02*
X283150Y591900D01*
X285919D01*
X289366Y588453D01*
X292200D01*
G01X270000Y567130D02*
X270770Y567900D01*
X277350D01*
X280250Y565000D01*
G01X295079Y577400D02*
X294176D01*
X284701Y567925D01*
X283175D01*
X280250Y565000D01*
G01X292000Y605250D02*
X289300Y602550D01*
Y600700D01*
X290625Y599375D01*
X294901D01*
X297047Y597229D01*
Y593300D01*
G01X289933Y615700D02*
X289100Y614867D01*
Y608150D01*
X292000Y605250D01*
G01X270000Y582833D02*
X270758Y582075D01*
X277325D01*
X280250Y585000D01*
G01X292200Y584516D02*
X289116D01*
X286675Y582075D01*
X283175D01*
X280250Y585000D01*
G01X290580Y565750D02*
X293400Y568570D01*
Y570295D01*
X297047Y573942D01*
Y577700D01*
G01X304921Y593600D02*
Y595921D01*
X306800Y597800D01*
X310776D01*
X312975Y599999D01*
Y602225D01*
X316000Y605250D01*
G01X313833Y615500D02*
X313100Y614767D01*
Y608150D01*
X316000Y605250D01*
G01X301833Y621000D02*
X301100Y620267D01*
Y608150D01*
X304000Y605250D01*
G01X300984Y593300D02*
Y596684D01*
X301200Y596900D01*
Y602450D01*
X304000Y605250D01*
G01X269800Y594733D02*
X270458Y594075D01*
X277325D01*
X280250Y597000D01*
G01X291900Y590421D02*
X290474D01*
X286820Y594075D01*
X283175D01*
X280250Y597000D01*
G01X270000Y570933D02*
X270858Y570075D01*
X277325D01*
X280250Y573000D01*
G01X291900Y580579D02*
Y578200D01*
X283800Y570100D01*
X283150D01*
X280250Y573000D01*
G01X315400Y598400D02*
X312600Y595600D01*
X311900D01*
X308100Y591800D01*
Y590421D01*
G01X325750Y605000D02*
X322000D01*
X315400Y598400D01*
G01X325750Y589000D02*
X322549D01*
X322149Y589400D01*
X316400D01*
X314000Y587000D01*
G01D02*
X311000D01*
X310484Y586484D01*
X307800D01*
G01X325750Y593000D02*
Y589000D01*
G01X320900Y593000D02*
X314923D01*
X311825Y589902D01*
Y589825D01*
X310453Y588453D01*
X307800D01*
G01X325750Y601000D02*
Y597000D01*
G01D02*
X324900D01*
X320900Y593000D01*
G01X313000Y565750D02*
X317500D01*
G01X306500Y568400D02*
X304921Y569979D01*
Y577400D01*
G01X306500Y568400D02*
X309150Y565750D01*
X313000D01*
G01X320250Y572500D02*
X316500D01*
X315000Y571000D01*
G01X308100Y580579D02*
X309615D01*
X315000Y575194D01*
Y571000D01*
G01X320250Y576500D02*
X317000D01*
X315000Y578500D01*
G01X307800Y582547D02*
X310723D01*
X314770Y578500D01*
X315000D01*
G01X339500Y572667D02*
X340233Y573400D01*
X342581D01*
X348188Y579007D01*
Y722993D01*
X284900Y786281D01*
Y811400D01*
X289012Y815512D01*
X318612D01*
X322324Y811800D01*
X325466D01*
X326167Y811099D01*
G01X339500Y576470D02*
X340395Y575575D01*
X341680D01*
X346013Y579908D01*
Y722092D01*
X282725Y785380D01*
Y812301D01*
X288111Y817687D01*
X319513D01*
X323225Y813975D01*
X325240D01*
X326167Y814902D01*
G01X330750Y811000D02*
X329950Y811800D01*
X326868D01*
X326167Y811099D01*
G01X330750Y815000D02*
X329725Y813975D01*
X327094D01*
X326167Y814902D01*
G01X328250Y843000D02*
Y847000D01*
G01X333500Y843000D02*
X328250D01*
G01Y851000D02*
X333500D01*
G01X330750Y1182500D02*
X329060D01*
X328160Y1183400D01*
X322724D01*
X319325Y1186799D01*
Y1192765D01*
X318650Y1193440D01*
X317156D01*
G01X330750Y1186500D02*
X329060D01*
X328135Y1185575D01*
X323625D01*
X321500Y1187700D01*
Y1192765D01*
X322175Y1193440D01*
X324656D01*
G01X328250Y1222500D02*
X333500D01*
G01X328250Y1214500D02*
X333500D01*
G01X328250Y1218500D02*
Y1214500D01*
G01X284900Y1390250D02*
X287900Y1393250D01*
Y1394850D01*
X287000Y1395750D01*
G01X287167Y1380000D02*
X287825Y1380658D01*
Y1387325D01*
X284900Y1390250D01*
G01X293100D02*
X290100Y1393250D01*
Y1394850D01*
X291000Y1395750D01*
G01X290970Y1380000D02*
X290000Y1380970D01*
Y1387150D01*
X293100Y1390250D01*
G01X319500Y1392250D02*
Y1389000D01*
G01X308100Y1426421D02*
X309945D01*
X311725Y1428201D01*
Y1431725D01*
X314781Y1434781D01*
X316831D01*
X319750Y1437700D01*
G01X330000Y1423470D02*
X329305Y1422775D01*
X322675D01*
X319750Y1425700D01*
G01X307800Y1422484D02*
X310993D01*
X311200Y1422691D01*
X316741D01*
X319750Y1425700D01*
G01X291600Y1441250D02*
X294519Y1438331D01*
Y1434605D01*
X297047Y1432077D01*
Y1429300D01*
G01X270100Y1425697D02*
X270803Y1426400D01*
X277350D01*
X280250Y1423500D01*
G01X292200Y1422484D02*
X288516D01*
X284594Y1426406D01*
X283156D01*
X280250Y1423500D01*
G01X307800Y1418547D02*
X311253D01*
X314175Y1415625D01*
Y1412025D01*
X315400Y1410800D01*
X317050D01*
X319750Y1413500D01*
G01D02*
X322750Y1410500D01*
X329700D01*
X330300Y1411100D01*
G01X302953Y1429300D02*
Y1433529D01*
X306000Y1436576D01*
Y1438850D01*
X303600Y1441250D01*
G01X291900Y1426421D02*
Y1427724D01*
X282919Y1436705D01*
Y1437981D01*
X279650Y1441250D01*
G01X280250Y1411500D02*
X280225D01*
X277325Y1414400D01*
X270870D01*
X270000Y1413530D01*
G01X292200Y1418547D02*
X287728D01*
X283881Y1414700D01*
X283000D01*
X280250Y1411950D01*
Y1411500D01*
G01X330000Y1431367D02*
X328767Y1432600D01*
X322650D01*
X319750Y1429700D01*
G01X307800Y1424453D02*
X311053D01*
X313900Y1427300D01*
Y1430824D01*
X315682Y1432606D01*
X316844D01*
X319750Y1429700D01*
G01X330000Y1419667D02*
X329067Y1420600D01*
X322850D01*
X319750Y1417500D01*
G01X307800Y1420516D02*
X316734D01*
X319750Y1417500D01*
G01X299600Y1441250D02*
X296694Y1438344D01*
Y1435506D01*
X299016Y1433184D01*
Y1429300D01*
G01X270100Y1429500D02*
X271025Y1428575D01*
X277325D01*
X280250Y1431500D01*
G01X292200Y1424453D02*
X289623D01*
X285495Y1428581D01*
X283169D01*
X280250Y1431500D01*
G01X308100Y1416579D02*
X310145D01*
X312000Y1414724D01*
Y1411124D01*
X314499Y1408625D01*
X316700D01*
X319750Y1405575D01*
Y1405400D01*
G01X330300Y1407297D02*
X329272Y1408325D01*
X322675D01*
X319750Y1405400D01*
G01X304921Y1429600D02*
Y1432421D01*
X308175Y1435675D01*
Y1437825D01*
X311600Y1441250D01*
G01X295079Y1429600D02*
X293100D01*
X285094Y1437606D01*
Y1438744D01*
X287600Y1441250D01*
G01X280250Y1419500D02*
X277325Y1416575D01*
X270758D01*
X270000Y1417333D01*
G01X292200Y1420516D02*
X286621D01*
X282980Y1416875D01*
X282325D01*
X280250Y1418950D01*
Y1419500D01*
G01X313500Y1406300D02*
X306400Y1413400D01*
X304921D01*
G01X319500Y1395750D02*
Y1400300D01*
X313500Y1406300D01*
G01X301500Y1407500D02*
Y1410500D01*
X300984Y1411016D01*
Y1413700D01*
G01X301500Y1407500D02*
X303500Y1405500D01*
Y1395750D01*
G01X307500D02*
X303500D01*
G01X311500D02*
X315500D01*
G01X307400Y1400800D02*
Y1406600D01*
X302953Y1411047D01*
Y1413700D01*
G01X311500Y1395750D02*
Y1396700D01*
X307400Y1400800D01*
G01X280250Y1403500D02*
Y1407500D01*
G01X291900Y1416579D02*
X289479D01*
X285100Y1412200D01*
G01X280250Y1407500D02*
X283304Y1410554D01*
X283454D01*
X285100Y1412200D01*
G01X287000Y1399250D02*
Y1401100D01*
X285700Y1402400D01*
Y1404100D01*
G01D02*
Y1405100D01*
X287100Y1406500D01*
X289524D01*
X295079Y1412055D01*
Y1413400D01*
G01X293200Y1406100D02*
Y1404100D01*
X291000Y1401900D01*
Y1399250D01*
G01X297047Y1413700D02*
Y1410947D01*
X293200Y1407100D01*
Y1406100D01*
G01X330000Y1435170D02*
X329605Y1434775D01*
X322675D01*
X319750Y1437700D01*
G01X293830Y1451500D02*
X294525Y1450805D01*
Y1444175D01*
X291600Y1441250D01*
G01X305830Y1451300D02*
X306525Y1450605D01*
Y1444175D01*
X303600Y1441250D01*
G01X282030Y1451400D02*
X282525Y1450905D01*
Y1444125D01*
X279650Y1441250D01*
G01X297633Y1451500D02*
X296700Y1450567D01*
Y1444150D01*
X299600Y1441250D01*
G01X309633Y1451300D02*
X308700Y1450367D01*
Y1444150D01*
X311600Y1441250D01*
G01X285833Y1451400D02*
X284700Y1450267D01*
Y1444150D01*
X287600Y1441250D01*
G01X318156Y1692440D02*
X319650D01*
X320325Y1691765D01*
Y1685099D01*
X323399Y1682025D01*
X328035D01*
X329060Y1681000D01*
X330750D01*
G01Y1685000D02*
X329060D01*
X328260Y1684200D01*
X324300D01*
X322500Y1686000D01*
Y1691765D01*
X323175Y1692440D01*
X325656D01*
G01X276500Y1717750D02*
Y1721750D01*
X276750Y1722000D01*
G01X272500Y1717750D02*
Y1721750D01*
X272250Y1722000D01*
G01X276500Y1709400D02*
Y1714250D01*
G01X272500D02*
Y1713016D01*
X269000Y1709516D01*
G01X328250Y1721000D02*
X333500D01*
G01X328250Y1713000D02*
Y1717000D01*
G01X333500Y1713000D02*
X328250D01*
G01X287500Y1788250D02*
Y1783000D01*
G01X291500Y1788250D02*
X287500D01*
G01X280840Y1774600D02*
Y1777840D01*
X282900Y1779900D01*
X284400D01*
X287500Y1783000D01*
G01X279500Y1788250D02*
Y1783000D01*
G01X283500Y1788250D02*
X279500D01*
G01X278280Y1774600D02*
Y1779180D01*
X279500Y1780400D01*
Y1783000D01*
G01X271500D02*
Y1788250D01*
G01X275500D02*
X271500D01*
G01X275720Y1774600D02*
Y1778780D01*
X271500Y1783000D01*
G01X276500Y1734750D02*
Y1740000D01*
G01X275720Y1752400D02*
Y1744280D01*
X276500Y1743500D01*
Y1740000D01*
G01X273160Y1752400D02*
Y1747660D01*
X271000Y1745500D01*
G01D02*
Y1736250D01*
X272500Y1734750D01*
G01X280500D02*
X281000Y1735250D01*
Y1744500D01*
X282000Y1745500D01*
G01X278280Y1752400D02*
Y1749220D01*
X282000Y1745500D01*
G01X276402Y1726146D02*
X275575Y1725319D01*
Y1723175D01*
X276750Y1722000D01*
G01X276402Y1726146D02*
X275475Y1727073D01*
Y1730225D01*
X276500Y1731250D01*
G01X272599Y1726146D02*
X273400Y1725345D01*
Y1723150D01*
X272250Y1722000D01*
G01X272599Y1726146D02*
X273300Y1726847D01*
Y1730450D01*
X272500Y1731250D01*
G01X352500Y75250D02*
X348500D01*
G01X352500D02*
Y81500D01*
G01D02*
Y82435D01*
X354565Y84500D01*
Y88350D01*
G01X358000Y70750D02*
Y76000D01*
G01X356530Y88350D02*
Y77470D01*
X358000Y76000D01*
G01X348500Y123750D02*
Y118500D01*
G01X354565Y104650D02*
Y108499D01*
X348500Y114564D01*
Y118500D01*
G01X352500Y123750D02*
Y114500D01*
X355000Y112000D01*
G01X356530Y104650D02*
Y110470D01*
X355000Y112000D01*
G01X348500Y127250D02*
X349406Y128156D01*
Y198006D01*
X439300Y287900D01*
Y298124D01*
X437699Y299725D01*
X428325D01*
X427500Y298900D01*
Y297156D01*
G01X352500Y127250D02*
X351581Y128169D01*
Y197105D01*
X441475Y286999D01*
Y299025D01*
X438600Y301900D01*
X428373D01*
X427381Y302892D01*
Y304537D01*
X427500Y304656D01*
G01X380250Y341000D02*
Y336100D01*
G01X344750D02*
Y341000D01*
G01X388250D02*
Y336000D01*
G01X352750Y341000D02*
Y336000D01*
G01X380500Y345250D02*
Y341250D01*
X380250Y341000D01*
G01X345000Y345250D02*
Y341250D01*
X344750Y341000D01*
G01X380500Y348750D02*
Y352250D01*
X380250Y352500D01*
G01D02*
Y356250D01*
X381500Y357500D01*
G01X376890Y382585D02*
Y377940D01*
X383000Y371830D01*
Y359000D01*
X381500Y357500D01*
G01X359175Y382585D02*
Y378675D01*
X348782Y368282D01*
Y360282D01*
X346000Y357500D01*
G01D02*
X344750Y356250D01*
Y352500D01*
G01X345000Y348750D02*
Y352250D01*
X344750Y352500D01*
G01X388500Y345250D02*
Y341250D01*
X388250Y341000D01*
G01X353000Y345250D02*
Y341250D01*
X352750Y341000D01*
G01X333500Y421000D02*
X336500Y418000D01*
Y417000D01*
X339987Y413513D01*
X345487D01*
X350140Y408860D01*
X352585D01*
G01X333500Y413000D02*
X337424D01*
X339086Y411338D01*
X345662D01*
X350110Y406890D01*
X352585D01*
G01X338250Y393000D02*
X343500D01*
G01X338250Y389000D02*
Y393000D01*
G01X352585Y395080D02*
X349420D01*
X348500Y396000D01*
X346500D01*
X343500Y393000D01*
G01X334250Y377000D02*
Y373000D01*
G01X352585Y389175D02*
X350175D01*
X348000Y387000D01*
Y378100D01*
X345900Y376000D01*
G01D02*
X344400Y374500D01*
X343000D01*
X341500Y373000D01*
X334250D01*
G01X388250Y352500D02*
X388500Y352250D01*
Y348750D01*
G01X388250Y352500D02*
Y358250D01*
X385175Y361325D01*
Y371655D01*
X378860Y377970D01*
Y382585D01*
G01X352750Y352500D02*
Y358250D01*
X350957Y360043D01*
Y368457D01*
X361140Y378640D01*
Y382585D01*
G01X349870Y348870D02*
X349990Y348750D01*
X353000D01*
G01D02*
Y352250D01*
X352750Y352500D01*
G01X387415Y406890D02*
X392500D01*
G01D02*
X397860D01*
X398000Y406750D01*
G01X392500Y406890D02*
X392000Y407390D01*
Y408000D01*
X391140Y408860D01*
X387415D01*
G01Y391140D02*
X393140D01*
X394000Y392000D01*
G01D02*
X392890Y393110D01*
X387415D01*
G01X394000Y392000D02*
X404000D01*
X406000Y394000D01*
Y399000D01*
G01D02*
Y402500D01*
X401750Y406750D01*
X398000D01*
G01X352585Y391140D02*
X349216D01*
X345500Y387424D01*
Y384600D01*
X343500Y382600D01*
X342600D01*
X339000Y379000D01*
G01X334250Y381000D02*
X337000D01*
X339000Y379000D01*
G01X334250Y385000D02*
X342500D01*
X343000Y385500D01*
G01X352585Y393110D02*
X348110D01*
X343325Y388325D01*
Y385825D01*
X343000Y385500D01*
G01X355000Y454750D02*
Y458750D01*
X355250Y459000D01*
G01D02*
Y463900D01*
G01X390500Y454750D02*
Y458750D01*
X390750Y459000D01*
G01D02*
Y463900D01*
G01X361140Y417415D02*
Y421260D01*
X351218Y431182D01*
Y439718D01*
X354000Y442500D01*
G01D02*
X355250Y443750D01*
Y447500D01*
G01X355000Y451250D02*
Y447750D01*
X355250Y447500D01*
G01X389500Y442500D02*
X390750Y443750D01*
Y447500D01*
G01X389500Y442500D02*
X386718Y439718D01*
Y429998D01*
X378860Y422140D01*
Y417415D01*
G01X390500Y451250D02*
Y447750D01*
X390750Y447500D01*
G01X347000Y454750D02*
Y458750D01*
X347250Y459000D01*
G01D02*
Y464000D01*
G01X382750Y459000D02*
Y464000D01*
G01X382500Y454750D02*
Y458750D01*
X382750Y459000D01*
G01X347250Y447500D02*
Y442150D01*
X349000Y440400D01*
Y431400D01*
X349043Y431357D01*
Y430757D01*
X350976Y428824D01*
X351576D01*
X359175Y421225D01*
Y417415D01*
G01X350137Y451250D02*
X347000D01*
G01D02*
Y447750D01*
X347250Y447500D01*
G01X382750D02*
Y441650D01*
X384543Y439857D01*
Y430043D01*
X376890Y422390D01*
Y417415D01*
G01X382750Y447500D02*
X382500Y447750D01*
Y451250D01*
G01D02*
X385589D01*
X385607Y451232D01*
G01X373750Y766100D02*
Y684618D01*
X860368Y198000D01*
X904500D01*
X914500Y208000D01*
Y289358D01*
X899941Y303917D01*
X893602D01*
G01X381750Y766000D02*
Y679694D01*
X861269Y200175D01*
X903599D01*
X912325Y208901D01*
Y261533D01*
X899941Y273917D01*
X893602D01*
G01X374000Y775250D02*
Y771250D01*
X373750Y771000D01*
G01D02*
Y766100D01*
G01X381750Y771000D02*
Y766000D01*
G01X382000Y775250D02*
Y771250D01*
X381750Y771000D01*
G01X361140Y847415D02*
Y851360D01*
X351218Y861282D01*
Y869718D01*
X354000Y872500D01*
G01X412500Y810500D02*
X410000Y813000D01*
X400280D01*
X392140Y821140D01*
X387415D01*
G01X374000Y778750D02*
Y782250D01*
X373750Y782500D01*
G01X375100Y787700D02*
X376400Y789000D01*
Y802140D01*
X376890Y802630D01*
Y812585D01*
G01X373750Y782500D02*
Y786350D01*
X375100Y787700D01*
G01X378860Y847415D02*
Y852140D01*
X386675Y859955D01*
Y869675D01*
X389500Y872500D01*
G01X333500Y851000D02*
X336500Y848000D01*
Y846800D01*
X339787Y843513D01*
X345487D01*
X350140Y838860D01*
X352585D01*
G01X333500Y843000D02*
X337224D01*
X338886Y841338D01*
X345662D01*
X350110Y836890D01*
X352585D01*
G01Y825080D02*
X349420D01*
X348500Y826000D01*
X346500D01*
X343500Y823000D01*
G01X338250D02*
X343500D01*
G01X338250Y819000D02*
Y823000D01*
G01X334250Y807000D02*
Y803000D01*
G01X345300Y804400D02*
X343900Y803000D01*
X334250D01*
G01X345300Y804400D02*
X348000Y807100D01*
Y817000D01*
X350175Y819175D01*
X352585D01*
G01X347250Y877500D02*
Y870450D01*
X349000Y868700D01*
Y861500D01*
X359175Y851325D01*
Y847415D01*
G01X387415Y823110D02*
X392390D01*
X399825Y815675D01*
X410175D01*
X411750Y817250D01*
X417500D01*
G01X381750Y782500D02*
Y788750D01*
X379600Y790900D01*
Y795300D01*
G01X381750Y782500D02*
X382000Y782250D01*
Y778750D01*
G01X379600Y795300D02*
Y802900D01*
X378860Y803640D01*
Y812585D01*
G01X382000Y778750D02*
X384834D01*
X385196Y779112D01*
G01X376890Y847415D02*
Y852390D01*
X384500Y860000D01*
Y870000D01*
X382750Y871750D01*
Y877500D01*
G01X387415Y836890D02*
X391000D01*
X391500Y837390D01*
Y838500D01*
G01X402000Y844000D02*
X401000D01*
X397500Y840500D01*
X397250D01*
G01X391500Y838500D02*
X391140Y838860D01*
X387415D01*
G01X397250Y840500D02*
X394500D01*
X392500Y838500D01*
X391500D01*
G01X360100Y808080D02*
X361140Y809120D01*
Y812585D01*
G01X359175D02*
Y809005D01*
X360100Y808080D01*
G01X339000Y809000D02*
X339041Y809041D01*
X339941D01*
X345500Y814600D01*
Y817224D01*
X349416Y821140D01*
X352585D01*
G01X339000Y809000D02*
X337000Y811000D01*
X334250D01*
G01X343000Y815500D02*
X343325Y815825D01*
Y818125D01*
X348310Y823110D01*
X352585D01*
G01X343000Y815500D02*
Y815176D01*
X340999Y813175D01*
X336075D01*
X334250Y815000D01*
G01X355250Y893900D02*
Y889000D01*
G01X355000Y884750D02*
Y888750D01*
X355250Y889000D01*
G01X390750Y893900D02*
Y889000D01*
G01X390500Y884750D02*
Y888750D01*
X390750Y889000D01*
G01X354000Y872500D02*
X355250Y873750D01*
Y877500D01*
G01X355000Y881250D02*
Y877750D01*
X355250Y877500D01*
G01X389500Y872500D02*
X390750Y873750D01*
Y877500D01*
G01X390500Y881250D02*
Y877750D01*
X390750Y877500D01*
G01X347250Y894000D02*
Y889000D01*
G01X347000Y884750D02*
Y888750D01*
X347250Y889000D01*
G01X382750Y894000D02*
Y889000D01*
G01X382500Y884750D02*
Y888750D01*
X382750Y889000D01*
G01X343894Y880707D02*
X344437Y881250D01*
X347000D01*
G01D02*
Y877750D01*
X347250Y877500D01*
G01X379372Y880728D02*
X379894Y881250D01*
X382500D01*
G01D02*
X382750Y881000D01*
Y877500D01*
G01X380250Y1142500D02*
Y1137600D01*
G01D02*
Y1118674D01*
X489599Y1009325D01*
X906901D01*
X915112Y1017536D01*
Y1099770D01*
X899941Y1114941D01*
X893602D01*
G01X388250Y1142500D02*
Y1137500D01*
G01D02*
Y1113750D01*
X490500Y1011500D01*
X901400D01*
X904600Y1014700D01*
X909200D01*
X912937Y1018437D01*
Y1071945D01*
X899941Y1084941D01*
X893602D01*
G01X380500Y1146750D02*
Y1142750D01*
X380250Y1142500D01*
G01X412500Y1213000D02*
X411000Y1214500D01*
X397470D01*
X391360Y1208390D01*
X387415D01*
G01X380500Y1150250D02*
Y1153750D01*
X380250Y1154000D01*
G01D02*
Y1157750D01*
X381500Y1159000D01*
G01D02*
X383200Y1160700D01*
Y1173030D01*
X376890Y1179340D01*
Y1184085D01*
G01X388500Y1146750D02*
Y1142750D01*
X388250Y1142500D01*
G01X333500Y1222500D02*
X335300D01*
X336500Y1221300D01*
Y1218184D01*
X339671Y1215013D01*
X345487D01*
X350140Y1210360D01*
X352585D01*
G01X333500Y1214500D02*
X337108D01*
X338770Y1212838D01*
X345662D01*
X350110Y1208390D01*
X352585D01*
G01X338250Y1194500D02*
Y1190500D01*
G01X343500Y1194500D02*
X338250D01*
G01X352585Y1196580D02*
X349420D01*
X348500Y1197500D01*
X346500D01*
X343500Y1194500D01*
G01X334250Y1178500D02*
Y1174500D01*
G01D02*
X344000D01*
X345600Y1176100D01*
G01X352585Y1190675D02*
X350175D01*
X348000Y1188500D01*
Y1178500D01*
X345600Y1176100D01*
G01X417500Y1219750D02*
X411750D01*
X408675Y1216675D01*
X397645D01*
X391330Y1210360D01*
X387415D01*
G01X388250Y1154000D02*
X388500Y1153750D01*
Y1150250D01*
G01X385900Y1166100D02*
Y1172000D01*
X378860Y1179040D01*
Y1184085D01*
G01X388250Y1154000D02*
Y1160150D01*
X385900Y1162500D01*
Y1166100D01*
G01X388500Y1150250D02*
X391900D01*
G01X359175Y1184085D02*
Y1179640D01*
G01X387415Y1194610D02*
X391390D01*
X392500Y1193500D01*
G01D02*
X394000Y1192000D01*
X398750D01*
G01X387415Y1192640D02*
X391640D01*
X392500Y1193500D01*
G01X398750Y1192000D02*
Y1188250D01*
G01X361140Y1184085D02*
Y1181605D01*
X359175Y1179640D01*
G01X339000Y1180500D02*
X342825Y1184325D01*
X343825D01*
X345600Y1186100D01*
Y1189424D01*
X348816Y1192640D01*
X352585D01*
G01X334250Y1182500D02*
X337000D01*
X339000Y1180500D01*
G01X334250Y1186500D02*
X342500D01*
X343000Y1187000D01*
G01X352585Y1194610D02*
X350005D01*
X349800Y1194815D01*
X347915D01*
X343425Y1190325D01*
Y1187425D01*
X343000Y1187000D01*
G01X355250Y1260500D02*
Y1265181D01*
X355029Y1265402D01*
G01X355000Y1256250D02*
Y1260250D01*
X355250Y1260500D01*
G01X390750Y1265400D02*
Y1260500D01*
G01X390500Y1256250D02*
Y1260250D01*
X390750Y1260500D01*
G01X361140Y1218915D02*
Y1222360D01*
X351000Y1232500D01*
Y1241000D01*
X354000Y1244000D01*
G01D02*
X355250Y1245250D01*
Y1249000D01*
G01X355000Y1252750D02*
Y1249250D01*
X355250Y1249000D01*
G01X389500Y1244000D02*
X390750Y1245250D01*
Y1249000D01*
G01X378860Y1218915D02*
Y1223640D01*
X386500Y1231280D01*
Y1241000D01*
X389500Y1244000D01*
G01X390500Y1252750D02*
Y1249250D01*
X390750Y1249000D01*
G01X347250Y1265500D02*
Y1260500D01*
G01X347000Y1256250D02*
Y1260250D01*
X347250Y1260500D01*
G01X382750Y1265500D02*
Y1260500D01*
G01X382500Y1256250D02*
Y1260250D01*
X382750Y1260500D01*
G01X359175Y1218915D02*
Y1222325D01*
X348500Y1233000D01*
Y1241796D01*
X347347Y1242949D01*
Y1248903D01*
X347250Y1249000D01*
G01X343822Y1252222D02*
X344350Y1252750D01*
X347000D01*
G01D02*
X347250Y1252500D01*
Y1249000D01*
G01X382750D02*
Y1243350D01*
X384282Y1241818D01*
Y1231282D01*
X376890Y1223890D01*
Y1218915D01*
G01X382750Y1249000D02*
X382500Y1249250D01*
Y1252750D01*
G01D02*
X379871D01*
X379395Y1252274D01*
G01X358156Y1411000D02*
X355987D01*
X354900Y1412087D01*
Y1436900D01*
X456925Y1538925D01*
X851325D01*
X852750Y1537500D01*
G01Y1542500D02*
X851350Y1541100D01*
X456024D01*
X352725Y1437801D01*
Y1411675D01*
X352050Y1411000D01*
X350656D01*
G01X345000Y1645250D02*
Y1641250D01*
X344750Y1641000D01*
G01D02*
Y1636100D01*
G01X353000Y1645250D02*
Y1641250D01*
X352750Y1641000D01*
G01D02*
Y1636000D01*
G01X387415Y1706890D02*
X392690D01*
X398800Y1713000D01*
X411000D01*
X412500Y1711500D01*
G01X346000Y1657500D02*
X344750Y1656250D01*
Y1652500D01*
G01X346000Y1657500D02*
X348782Y1660282D01*
Y1667472D01*
X359175Y1677865D01*
Y1682585D01*
G01X345000Y1648750D02*
Y1652250D01*
X344750Y1652500D01*
G01X361140Y1717415D02*
Y1720860D01*
X351000Y1731000D01*
Y1739500D01*
X354000Y1742500D01*
G01X333500Y1721000D02*
X336500Y1718000D01*
Y1716800D01*
X339787Y1713513D01*
X345487D01*
X350140Y1708860D01*
X352585D01*
G01X333500Y1713000D02*
X337224D01*
X338886Y1711338D01*
X345662D01*
X350110Y1706890D01*
X352585D01*
G01X338250Y1691000D02*
Y1695000D01*
G01X344000Y1693600D02*
X342300D01*
X340900Y1695000D01*
X338250D01*
G01X352585Y1695080D02*
X347680D01*
X346200Y1693600D01*
X344000D01*
G01X346000Y1676500D02*
X348300Y1678800D01*
Y1687300D01*
X350175Y1689175D01*
X352585D01*
G01X334250Y1673000D02*
Y1677000D01*
G01X346000Y1676500D02*
X342000D01*
X338500Y1673000D01*
X334250D01*
G01X417500Y1718250D02*
X412600D01*
X409525Y1715175D01*
X399175D01*
X392860Y1708860D01*
X387415D01*
G01X356174Y1649291D02*
X355633Y1648750D01*
X353000D01*
G01X361140Y1682585D02*
Y1678140D01*
X350957Y1667957D01*
Y1660043D01*
X352750Y1658250D01*
Y1652500D01*
G01X353000Y1648750D02*
X352750Y1649000D01*
Y1652500D01*
G01X347250Y1747500D02*
Y1743831D01*
X348825Y1742256D01*
Y1731175D01*
X359175Y1720825D01*
Y1717415D01*
G01X387415Y1693110D02*
X391390D01*
X392500Y1692000D01*
G01D02*
X391640Y1691140D01*
X387415D01*
G01X395500Y1690500D02*
X394000Y1692000D01*
X392500D01*
G01X376890Y1682585D02*
Y1678000D01*
G01X378860Y1682585D02*
Y1679970D01*
X376890Y1678000D01*
G01X378860Y1725860D02*
X376890Y1723890D01*
Y1717415D01*
G01X378860Y1725860D02*
Y1717415D01*
G01X339100Y1679600D02*
X339600D01*
X345145Y1685145D01*
Y1686569D01*
X349716Y1691140D01*
X352585D01*
G01X339100Y1679600D02*
X338400D01*
X337000Y1681000D01*
X334250D01*
G01X342700Y1686200D02*
Y1687200D01*
X348610Y1693110D01*
X352585D01*
G01X342700Y1686200D02*
Y1685776D01*
X340099Y1683175D01*
X336075D01*
X334250Y1685000D01*
G01X376808Y1755434D02*
X376075Y1756167D01*
Y1758975D01*
X377800Y1760700D01*
X386300D01*
X413900Y1733100D01*
X703044D01*
X778369Y1808425D01*
X797825D01*
X799250Y1807000D01*
G01X373005Y1755434D02*
X373900Y1756329D01*
Y1759876D01*
X376899Y1762875D01*
X387201D01*
X414801Y1735275D01*
X702143D01*
X777468Y1810600D01*
X797850D01*
X799250Y1812000D01*
G01X355250Y1763900D02*
Y1759000D01*
G01X355000Y1754750D02*
Y1758750D01*
X355250Y1759000D01*
G01X354000Y1742500D02*
X355250Y1743750D01*
Y1747500D01*
G01X355000Y1751250D02*
Y1747750D01*
X355250Y1747500D01*
G01X347250Y1764000D02*
Y1759000D01*
G01X347000Y1754750D02*
Y1758750D01*
X347250Y1759000D01*
G01X343668Y1750741D02*
X344177Y1751250D01*
X347000D01*
G01D02*
X347250Y1751000D01*
Y1747500D01*
G01X379000Y1726000D02*
Y1729250D01*
G01Y1726000D02*
X378860Y1725860D01*
G01X433900Y809250D02*
X445701Y797449D01*
Y646463D01*
X488664Y603500D01*
X904500D01*
X915112Y614112D01*
Y694258D01*
X899941Y709429D01*
X893602D01*
G01X434000Y817250D02*
X443750D01*
X447876Y813124D01*
Y647364D01*
X489565Y605675D01*
X903599D01*
X912937Y615013D01*
Y666433D01*
X899941Y679429D01*
X893602D01*
G01X433900Y809250D02*
X429000D01*
G01X424750Y809500D02*
X428750D01*
X429000Y809250D01*
G01X412500Y810500D02*
X413750Y809250D01*
X417500D01*
G01X421250Y809500D02*
X417750D01*
X417500Y809250D01*
G01X434000Y817250D02*
X429000D01*
G01X424750Y817500D02*
X428750D01*
X429000Y817250D01*
G01X420722Y820627D02*
X421250Y820099D01*
Y817500D01*
G01D02*
X421000Y817250D01*
X417500D01*
G01X412500Y1130750D02*
X415169Y1133419D01*
X851331D01*
X852750Y1132000D01*
G01Y1137000D02*
X851344Y1135594D01*
X415156D01*
X412500Y1138250D01*
G01X424750Y1212000D02*
X428750D01*
X429000Y1211750D01*
G01X412500Y1213000D02*
X413750Y1211750D01*
X417500D01*
G01X421250Y1212000D02*
X417750D01*
X417500Y1211750D01*
G01X433900D02*
X504750D01*
X708000Y1415000D01*
X905500D01*
X915112Y1424612D01*
Y1505282D01*
X899941Y1520453D01*
X893602D01*
G01X433900Y1211750D02*
X429000D01*
G01X434000Y1219750D02*
X429000D01*
G01X434000D02*
X509674D01*
X707099Y1417175D01*
X901875D01*
X912937Y1428237D01*
Y1477457D01*
X899941Y1490453D01*
X893602D01*
G01X424750Y1220000D02*
X428750D01*
X429000Y1219750D01*
G01X420763Y1223185D02*
X421250Y1222698D01*
Y1220000D01*
G01D02*
X417750D01*
X417500Y1219750D01*
G01X438656Y1669000D02*
X436669D01*
X435994Y1668325D01*
Y1660687D01*
X449993Y1646688D01*
X902982D01*
X923382Y1667088D01*
X948147D01*
X949559Y1668500D01*
X951250D01*
G01X431156Y1669000D02*
X433144D01*
X433819Y1668325D01*
Y1659786D01*
X449092Y1644513D01*
X903883D01*
X924283Y1664913D01*
X948147D01*
X949560Y1663500D01*
X951250D01*
G01X893602Y1925965D02*
X899941D01*
X914500Y1911406D01*
Y1828924D01*
X905401Y1819825D01*
X875901D01*
X871457Y1815381D01*
Y1794357D01*
X845600Y1768500D01*
X755500D01*
X702764Y1715764D01*
X449062D01*
X443548Y1710250D01*
X433900D01*
G01D02*
X429000D01*
G01X424750Y1710500D02*
X428750D01*
X429000Y1710250D01*
G01X412500Y1711500D02*
X413750Y1710250D01*
X417500D01*
G01X421250Y1710500D02*
X417750D01*
X417500Y1710250D01*
G01X434000Y1718250D02*
X429000D01*
G01X424750Y1718500D02*
X428750D01*
X429000Y1718250D01*
G01X893602Y1895965D02*
X899941D01*
X912325Y1883581D01*
Y1829825D01*
X904500Y1822000D01*
X875000D01*
X869282Y1816282D01*
Y1797527D01*
X842755Y1771000D01*
X754924D01*
X701863Y1717939D01*
X434311D01*
X434000Y1718250D01*
G01X420732Y1721757D02*
X421250Y1721239D01*
Y1718500D01*
G01D02*
X421000Y1718250D01*
X417500D01*
G01X458156Y1743000D02*
X455675D01*
X455000Y1743675D01*
Y1747945D01*
X459118Y1752063D01*
X713240D01*
X827431Y1866254D01*
Y1919955D01*
X844701Y1937225D01*
X850325D01*
X851750Y1935800D01*
G01X450656Y1743000D02*
X452131D01*
X452825Y1743694D01*
Y1748846D01*
X458217Y1754238D01*
X712339D01*
X825256Y1867155D01*
Y1920856D01*
X843800Y1939400D01*
X850350D01*
X851750Y1940800D01*
G01X852750Y726500D02*
X851325Y727925D01*
X820825D01*
X710428Y617528D01*
X517975D01*
X515319Y620184D01*
Y622825D01*
X514644Y623500D01*
X512656D01*
G01X852750Y731500D02*
X851350Y730100D01*
X819924D01*
X709527Y619703D01*
X518876D01*
X517494Y621085D01*
Y622825D01*
X518169Y623500D01*
X520156D01*
G01X555000Y524344D02*
Y526331D01*
X555675Y527006D01*
X563503D01*
X768097Y322412D01*
X851338D01*
X852750Y321000D01*
G01X555000Y531844D02*
Y529856D01*
X555675Y529181D01*
X564404D01*
X768998Y324587D01*
X851337D01*
X852750Y326000D01*
G01X769239Y1963257D02*
X764739D01*
G01X755995Y1968282D02*
X760164D01*
G01D02*
Y1964582D01*
X761489Y1963257D01*
X764739D01*
G01X763664Y1968282D02*
X768564D01*
G01X799250Y193000D02*
X797838Y194412D01*
X793156D01*
X792343Y193599D01*
G01X836830Y194193D02*
X831693D01*
X820500Y183000D01*
G01X816500Y177750D02*
X820500D01*
G01Y183000D02*
Y177750D01*
G01X828500D02*
X824500D01*
G01X828500D02*
Y183000D01*
G01D02*
Y186500D01*
X833633Y191633D01*
X836830D01*
G01X836500Y177750D02*
Y183000D01*
G01X832500Y177750D02*
X836500D01*
G01Y183000D02*
Y184500D01*
X836830Y184830D01*
Y189073D01*
G01X820650Y191633D02*
X815633D01*
X810500Y186500D01*
Y183000D01*
G01X802750Y193000D02*
X804162Y194412D01*
X807588D01*
X810500Y191500D01*
G01D02*
X813385Y194385D01*
X816335D01*
X816527Y194193D01*
X820650D01*
G01X792343Y197402D02*
X793158Y196587D01*
X797837D01*
X799250Y198000D01*
G01X802750D02*
X804163Y196587D01*
X807587D01*
X810500Y199500D01*
G01D02*
X813440Y196560D01*
X816335D01*
X816528Y196753D01*
X820650D01*
G01X811925Y377775D02*
Y375701D01*
X814876Y372750D01*
X816500D01*
G01X807756Y377775D02*
X811925D01*
G01X821000Y372750D02*
X816500D01*
G01X827875Y362750D02*
Y365375D01*
X830000Y367500D01*
Y372000D01*
X829250Y372750D01*
X821000D01*
G01X828000Y341250D02*
X830050D01*
X831300Y342500D01*
X835500D01*
G01X819500Y341250D02*
X824000D01*
G01X819500D02*
X814250D01*
G01X824000D02*
X828000D01*
G01X813000Y348000D02*
Y342500D01*
X814250Y341250D01*
G01X819000Y349600D02*
X821400D01*
X822000Y349000D01*
X824250D01*
G01X819500Y344750D02*
X819000Y345250D01*
Y349600D01*
G01X824250Y349000D02*
Y355000D01*
X824000Y355250D01*
G01X813000Y357000D02*
X822250D01*
X824000Y355250D01*
G01X840150Y373900D02*
X834250D01*
G01X826750Y377775D02*
X820325D01*
G01X815425D02*
X820325D01*
G01X827875Y768250D02*
Y770625D01*
X830500Y773250D01*
Y777000D01*
X829250Y778250D01*
X821000D01*
G01X824000Y746750D02*
X828000D01*
G01X819500D02*
X824000D01*
G01X819500D02*
X814250D01*
G01X828000D02*
X830050D01*
X831300Y748000D01*
X835500D01*
G01X813000Y753500D02*
Y748000D01*
X814250Y746750D01*
G01X819000Y755100D02*
X821400D01*
X822000Y754500D01*
X824250D01*
G01X819500Y750250D02*
X819000Y750750D01*
Y755100D01*
G01X824250Y754500D02*
Y760500D01*
X824000Y760750D01*
G01X813000Y762500D02*
X822250D01*
X824000Y760750D01*
G01X811925Y783275D02*
Y781201D01*
X814876Y778250D01*
X816500D01*
G01X821000D02*
X816500D01*
G01X808256Y783275D02*
X811925D01*
G01X840150Y779400D02*
X834250D01*
G01X826750Y783275D02*
X820325D01*
G01X815425D02*
X820325D01*
G01X827875Y1173750D02*
X830000Y1175875D01*
Y1182500D01*
X828750Y1183750D01*
X821000D01*
G01X816500D02*
X814876D01*
X811925Y1186701D01*
Y1188775D01*
G01X807756D02*
X811925D01*
G01X821000Y1183750D02*
X816500D01*
G01X824000Y1152250D02*
X828000D01*
G01X819500D02*
X824000D01*
G01X819500D02*
X814250D01*
G01X828000D02*
X830050D01*
X831300Y1153500D01*
X835500D01*
G01X813000Y1159000D02*
Y1153500D01*
X814250Y1152250D01*
G01X819000Y1160600D02*
X821400D01*
X822000Y1160000D01*
X824250D01*
G01X819500Y1155750D02*
X819000Y1156250D01*
Y1160600D01*
G01X824250Y1160000D02*
Y1166000D01*
X824000Y1166250D01*
G01X813000Y1168000D02*
X822250D01*
X824000Y1166250D01*
G01X840150Y1184900D02*
X834250D01*
G01X826750Y1188775D02*
X820325D01*
G01X815425D02*
X820325D01*
G01X828000Y1557750D02*
X829950D01*
X831200Y1559000D01*
X835500D01*
G01X819500Y1557750D02*
X824000D01*
G01X819500D02*
X814250D01*
G01X824000D02*
X828000D01*
G01X813000Y1564500D02*
Y1559000D01*
X814250Y1557750D01*
G01X824250Y1565500D02*
X822400D01*
X821400Y1566500D01*
X819600D01*
X819200Y1566100D01*
G01X824250Y1565500D02*
Y1571500D01*
X824000Y1571750D01*
G01X819500Y1561250D02*
X819200Y1561550D01*
Y1566100D01*
G01X813000Y1573500D02*
X822250D01*
X824000Y1571750D01*
G01X816500Y1589250D02*
X814876D01*
X811925Y1592201D01*
Y1594275D01*
G01X827875Y1579250D02*
Y1581875D01*
X830000Y1584000D01*
Y1588000D01*
X828750Y1589250D01*
X821000D01*
G01X807756Y1594275D02*
X811925D01*
G01X821000Y1589250D02*
X816500D01*
G01X840150Y1590400D02*
X834250D01*
G01X826750Y1594275D02*
X820325D01*
G01X815425D02*
X820325D01*
G01X815000Y1791750D02*
X819000D01*
G01Y1797000D02*
Y1791750D01*
G01X829500D02*
X825500D01*
G01X829500D02*
Y1797000D01*
G01X841500Y1791750D02*
X837500D01*
G01Y1797000D02*
Y1791750D01*
G01X836830Y1808367D02*
X831867D01*
X823750Y1800250D01*
X822250D01*
X819000Y1797000D01*
G01X829500D02*
Y1801500D01*
X833807Y1805807D01*
X836830D01*
G01Y1803247D02*
Y1797670D01*
X837500Y1797000D01*
G01X820650Y1805807D02*
X815807D01*
X810500Y1800500D01*
Y1797000D01*
G01X802750Y1807000D02*
X804162Y1808412D01*
X807588D01*
X810500Y1805500D01*
G01D02*
X813559Y1808559D01*
X816335D01*
X816527Y1808367D01*
X820650D01*
G01Y1810927D02*
X816528D01*
X816335Y1810734D01*
X813266D01*
X810500Y1813500D01*
G01D02*
X807587Y1810587D01*
X804163D01*
X802750Y1812000D01*
G01X788839Y1931757D02*
X792839D01*
G01X784339D02*
X788839D01*
G01X777839Y1938507D02*
Y1933007D01*
X779089Y1931757D01*
G01D02*
X784339D01*
G01X802439Y1934107D02*
X797639D01*
X795289Y1931757D01*
X792839D01*
G01X783939Y1940107D02*
Y1935657D01*
X784339Y1935257D01*
G01X792714Y1953257D02*
Y1956132D01*
X791339Y1957507D01*
X783639D01*
X777889Y1963257D01*
X769239D01*
G01X789089Y1939507D02*
Y1945507D01*
X788839Y1945757D01*
G01X783939Y1940107D02*
X786239D01*
X786839Y1939507D01*
X789089D01*
G01X777839Y1947507D02*
X787089D01*
X788839Y1945757D01*
G01X788389Y1964407D02*
Y1969286D01*
G01Y1964407D02*
X782489D01*
G01X794489Y1968282D02*
X793485Y1969286D01*
X788389D01*
G01X774989Y1968282D02*
X768564D01*
G01X902481Y160211D02*
X905000D01*
X906258Y158953D01*
X909733D01*
G01D02*
X914447D01*
X917900Y155500D01*
X919750D01*
G01X904728Y151181D02*
X906250D01*
X907250Y150181D01*
Y146453D01*
G01X899648Y150703D02*
X896647D01*
X896547Y150803D01*
G01X904728Y151181D02*
X902580D01*
X902102Y150703D01*
X899648D01*
G01X883412Y149000D02*
X885000D01*
X886250Y150250D01*
Y157000D01*
G01X880036Y155911D02*
Y149964D01*
X881000Y149000D01*
X883412D01*
G01X889750Y161000D02*
Y164085D01*
X890469Y164804D01*
G01X889750Y157000D02*
Y161000D01*
G01Y157000D02*
Y148886D01*
X893768Y144868D01*
Y143505D01*
X895500Y141773D01*
Y138619D01*
X894334Y137453D01*
X892250D01*
G01X902481Y163411D02*
X905000D01*
X906042Y164453D01*
X914833D01*
G01X869250Y148875D02*
X864975D01*
G01X909881Y131990D02*
X905748D01*
X902845Y134893D01*
X898750D01*
G01X909881Y131990D02*
X913313D01*
X915350Y129953D01*
X919750D01*
G01X876161Y163411D02*
Y166661D01*
X879000Y169500D01*
G01D02*
X880693Y171193D01*
X888241D01*
X890566Y168868D01*
Y168354D01*
G01X896731Y163411D02*
X894089D01*
X893000Y164500D01*
Y165920D01*
X890566Y168354D01*
G01X910750Y141223D02*
Y146453D01*
G01Y141223D02*
Y138573D01*
X911744Y137579D01*
X915126D01*
X916625Y139078D01*
Y144703D01*
G01X896731Y160211D02*
Y156718D01*
X898725Y154724D01*
G01D02*
X908876D01*
X910098Y153502D01*
X915037D01*
G01X872286Y155911D02*
X866961D01*
G01X876750Y145000D02*
Y151447D01*
X872286Y155911D01*
G01X892250Y140013D02*
X884000D01*
G01D02*
X881737D01*
X876750Y145000D01*
G01X895236Y251141D02*
X900259D01*
X901600Y249800D01*
G01X895236Y247992D02*
X899792D01*
X901600Y249800D01*
G01X893602Y308917D02*
X899941D01*
G01X856250Y321000D02*
X857662Y322412D01*
X861107D01*
X863941Y319578D01*
G01D02*
X866858Y322495D01*
X877412D01*
X877899Y322008D01*
X882677D01*
G01X856250Y326000D02*
X857663Y324587D01*
X861450D01*
X863941Y327078D01*
G01D02*
X866349Y324670D01*
X877412D01*
X877899Y325157D01*
X882677D01*
G01X844050Y330750D02*
X850125D01*
G01X856200D02*
X857450Y329500D01*
X870500D01*
X871693Y328307D01*
X882677D01*
G01X850125Y330750D02*
X856200D01*
G01X840150Y378779D02*
X845246D01*
X846250Y377775D01*
G01X840150Y373900D02*
Y378779D01*
G01X903728Y556693D02*
X905498D01*
X906250Y555941D01*
Y551965D01*
G01X898754Y556215D02*
X895647D01*
X895547Y556315D01*
G01X903728Y556693D02*
X901457D01*
X900979Y556215D01*
X898754D01*
G01X881500Y548965D02*
X879500D01*
X878375Y550090D01*
Y555715D01*
G01X884500Y556715D02*
Y549965D01*
X883500Y548965D01*
X881500D01*
G01X894500Y547800D02*
Y543965D01*
X893500Y542965D01*
X891250D01*
G01X888000Y556715D02*
Y560715D01*
G01X894500Y547800D02*
Y547988D01*
X888000Y554488D01*
Y556715D01*
G01X865125Y539715D02*
Y544000D01*
G01X907492Y536837D02*
X905413D01*
X901845Y540405D01*
X897750D01*
G01X919750Y535465D02*
X916047D01*
X914675Y536837D01*
X907492D01*
G01X916625Y550215D02*
Y544590D01*
X915126Y543091D01*
X910744D01*
X909750Y544085D01*
Y546735D01*
G01Y551965D02*
Y546735D01*
G01X869000Y547215D02*
X872500D01*
X878201Y541514D01*
X880636D01*
G01X870625Y555715D02*
Y552090D01*
X869000Y550465D01*
Y547215D01*
G01X870625Y555715D02*
X867500D01*
X865250Y553465D01*
G01X880636Y541514D02*
X883549D01*
X887560Y545525D01*
X891250D01*
G01X902481Y565723D02*
X905500D01*
X906758Y564465D01*
X909733D01*
G01D02*
X914135D01*
X917600Y561000D01*
X919750D01*
G01X888000Y560715D02*
Y563800D01*
X888719Y564519D01*
G01X902481Y568923D02*
X905000D01*
X906042Y569965D01*
X914833D01*
G01X886843Y568923D02*
X876958D01*
X874500Y566465D01*
Y563215D01*
G01X896731Y568923D02*
Y573617D01*
X895926Y574422D01*
G01D02*
X892342D01*
X886843Y568923D01*
G01X896731Y565723D02*
Y560668D01*
X896991Y560408D01*
G01D02*
X907092D01*
X908486Y559014D01*
X914186D01*
X916600Y556600D01*
G01X895236Y656653D02*
X899647D01*
X901200Y655100D01*
G01X895236Y653504D02*
X899604D01*
X901200Y655100D01*
G01X893602Y714429D02*
X899941D01*
G01X856250Y726500D02*
X857662Y727912D01*
X861019D01*
X863841Y725090D01*
G01D02*
X866758Y728007D01*
X877412D01*
X877899Y727520D01*
X882677D01*
G01X856250Y731500D02*
X857663Y730087D01*
X861338D01*
X863841Y732590D01*
G01D02*
X866249Y730182D01*
X877412D01*
X877899Y730669D01*
X882677D01*
G01X856100Y736750D02*
X857350D01*
X858900Y735200D01*
X867200D01*
X868581Y733819D01*
X882677D01*
G01X851150Y736750D02*
X846200D01*
G01X851150D02*
X856100D01*
G01X840150Y784279D02*
X845246D01*
X846250Y783275D01*
G01X840150Y779400D02*
Y784279D01*
G01X902481Y971235D02*
X905500D01*
X906758Y969977D01*
X909733D01*
G01D02*
X913023D01*
X916500Y966500D01*
X919750D01*
G01X898648Y961727D02*
X895647D01*
X895547Y961827D01*
G01X903728Y962205D02*
X905250D01*
X906250Y961205D01*
Y957477D01*
G01X898648Y961727D02*
X901167D01*
X901645Y962205D01*
X903728D01*
G01X881500Y954477D02*
X879500D01*
X878375Y955602D01*
Y961227D01*
G01X884500Y962227D02*
Y955477D01*
X883500Y954477D01*
X881500D01*
G01X888000Y966227D02*
Y969312D01*
X888719Y970031D01*
G01X888000Y966227D02*
Y962227D01*
G01D02*
Y960000D01*
X890550Y957450D01*
G01X891250Y948477D02*
X893500D01*
X894500Y949477D01*
Y953500D01*
X890550Y957450D01*
G01X902481Y974435D02*
X905500D01*
X906542Y975477D01*
X914833D01*
G01X865125Y949600D02*
Y945227D01*
G01X908177Y942729D02*
X905033D01*
X901845Y945917D01*
X897750D01*
G01X919750Y940977D02*
X913929D01*
X912177Y942729D01*
X908177D01*
G01X879800Y975800D02*
X878323D01*
X874500Y971977D01*
Y968727D01*
G01X889909Y977357D02*
X881357D01*
X879800Y975800D01*
G01X889909Y977357D02*
X891522D01*
X894444Y974435D01*
X896731D01*
G01Y971235D02*
Y966406D01*
X897224Y965913D01*
G01D02*
X906787D01*
X908486Y964214D01*
X914646D01*
G01X916625Y955727D02*
Y950102D01*
X915126Y948603D01*
X910744D01*
X909750Y949597D01*
Y952247D01*
G01Y957477D02*
Y952247D01*
G01X870625Y961227D02*
Y957602D01*
X869000Y955977D01*
Y952727D01*
G01X870625Y961227D02*
X867500D01*
X865250Y958977D01*
G01X869000Y952727D02*
X872500D01*
X878201Y947026D01*
X880636D01*
G01D02*
X883549D01*
X887560Y951037D01*
X891250D01*
G01X895236Y1062165D02*
X899835D01*
X901300Y1060700D01*
G01X895236Y1059016D02*
X899616D01*
X901300Y1060700D01*
G01X893602Y1119941D02*
X899941D01*
G01X856250Y1132000D02*
X857514Y1133264D01*
X861579D01*
X864241Y1130602D01*
G01D02*
X867158Y1133519D01*
X877412D01*
X877899Y1133032D01*
X882677D01*
G01X856250Y1137000D02*
X857811Y1135439D01*
X861578D01*
X864241Y1138102D01*
G01D02*
X866649Y1135694D01*
X877412D01*
X877899Y1136181D01*
X882677D01*
G01X854500Y1142150D02*
X857350D01*
X859000Y1140500D01*
X867231D01*
X868400Y1139331D01*
X882677D01*
G01X849550Y1142150D02*
X844600D01*
G01X854500D02*
X849550D01*
G01X840150Y1189779D02*
X845246D01*
X846250Y1188775D01*
G01X840150Y1184900D02*
Y1189779D01*
G01X891250Y1353988D02*
X893688D01*
X894500Y1354800D01*
Y1360500D01*
X893438Y1361562D01*
X893395D01*
X889970Y1364987D01*
Y1365030D01*
X889800Y1365200D01*
X887438D01*
G01X865125Y1350738D02*
Y1346488D01*
G01X908530Y1348458D02*
X903542D01*
X900572Y1351428D01*
X897750D01*
G01X908530Y1348458D02*
X913142D01*
X915112Y1346488D01*
X919750D01*
G01X916625Y1361238D02*
Y1355613D01*
X915126Y1354114D01*
X910744D01*
X909750Y1355108D01*
Y1357758D01*
G01X869000Y1358238D02*
X872250D01*
X877951Y1352537D01*
X880636D01*
G01D02*
X883549D01*
X887560Y1356548D01*
X891250D01*
G01X902481Y1376746D02*
X905500D01*
X906758Y1375488D01*
X909733D01*
G01X919750Y1372000D02*
X917500D01*
X914012Y1375488D01*
X909733D01*
G01X903900Y1367659D02*
X905241D01*
X906250Y1366650D01*
Y1362988D01*
G01X898748Y1367238D02*
X901500D01*
X901921Y1367659D01*
X903900D01*
G01X898748Y1367238D02*
X895747D01*
X895647Y1367338D01*
G01X881500Y1359988D02*
X879500D01*
X878375Y1361113D01*
Y1366738D01*
G01X883938Y1365200D02*
Y1360426D01*
X883500Y1359988D01*
X881500D01*
G01X887438Y1369700D02*
Y1365200D01*
G01Y1373374D02*
Y1369700D01*
G01X902481Y1379946D02*
X905446D01*
X906488Y1380988D01*
X914833D01*
G01X880100Y1380100D02*
X879946Y1379946D01*
X876958D01*
X874500Y1377488D01*
Y1374238D01*
G01X880100Y1380100D02*
X880254Y1379946D01*
X890213D01*
G01D02*
X896731D01*
G01Y1376746D02*
Y1371455D01*
X896835Y1371351D01*
G01X915037Y1370037D02*
X898149D01*
X896835Y1371351D01*
G01X909750Y1362988D02*
Y1357758D01*
G01X870625Y1366738D02*
X867500D01*
X865250Y1364488D01*
G01X870625Y1366738D02*
Y1363113D01*
X869000Y1361488D01*
Y1358238D01*
G01X895236Y1464528D02*
X899828D01*
X901400Y1466100D01*
G01X895236Y1467677D02*
X899823D01*
X901400Y1466100D01*
G01X893602Y1525453D02*
X899941D01*
G01X882677Y1538544D02*
X877899D01*
X877412Y1539031D01*
X867358D01*
X864441Y1536114D01*
G01D02*
X861643Y1538912D01*
X857662D01*
X856250Y1537500D01*
G01Y1542500D02*
X857663Y1541087D01*
X861914D01*
X864441Y1543614D01*
G01D02*
X866849Y1541206D01*
X877412D01*
X877899Y1541693D01*
X882677D01*
G01X855500Y1547750D02*
X857250Y1546000D01*
X867000D01*
X868157Y1544843D01*
X882677D01*
G01X855500Y1547750D02*
X850550D01*
G01D02*
X845600D01*
G01X840150Y1595279D02*
X845246D01*
X846250Y1594275D01*
G01X840150Y1590400D02*
Y1595279D01*
G01X903728Y1773228D02*
X905250D01*
X906250Y1772228D01*
Y1768500D01*
G01X898800Y1772750D02*
X901522D01*
X902000Y1773228D01*
X903728D01*
G01X898800Y1772750D02*
X895647D01*
X895547Y1772850D01*
G01X884500Y1773250D02*
Y1766500D01*
X883500Y1765500D01*
X881500D01*
G01D02*
X879500D01*
X878375Y1766625D01*
Y1772250D01*
G01X919750Y1777500D02*
X917600D01*
X914100Y1781000D01*
X909733D01*
G01X902481Y1782258D02*
X906000D01*
X907258Y1781000D01*
X909733D01*
G01X888000Y1777250D02*
Y1780335D01*
X888719Y1781054D01*
G01X891250Y1759500D02*
X893500D01*
X894500Y1760500D01*
Y1764819D01*
X888000Y1771319D01*
Y1773250D01*
G01D02*
Y1777250D01*
G01X902481Y1785458D02*
X905958D01*
X907000Y1786500D01*
X914833D01*
G01X865125Y1756250D02*
Y1751800D01*
G01X897750Y1756940D02*
X901329D01*
X906269Y1752000D01*
X913923D01*
G01X886843Y1785458D02*
X876958D01*
X874500Y1783000D01*
Y1779750D01*
G01X895442Y1790816D02*
X892428D01*
X887070Y1785458D01*
X886843D01*
G01X896731D02*
Y1789527D01*
X895442Y1790816D01*
G01X916100Y1773800D02*
X913184Y1776716D01*
X897334D01*
X897150Y1776900D01*
G01X896731Y1782258D02*
Y1779757D01*
X897150Y1779338D01*
Y1776900D01*
G01X909750Y1763270D02*
Y1760871D01*
X910995Y1759626D01*
X915126D01*
X916625Y1761125D01*
Y1766750D01*
G01X909750Y1768500D02*
Y1763270D01*
G01X891250Y1762060D02*
X887560D01*
X883049Y1757549D01*
X881636D01*
G01X870625Y1772250D02*
Y1768425D01*
X869000Y1766800D01*
Y1763750D01*
G01X870625Y1772250D02*
X867500D01*
X865250Y1770000D01*
G01X881636Y1757549D02*
X878251D01*
X872050Y1763750D01*
X869000D01*
G01X893602Y1930965D02*
X899941D01*
G01X895236Y1873189D02*
X899611D01*
X901200Y1871600D01*
G01X895236Y1870040D02*
X899640D01*
X901200Y1871600D01*
G01X882677Y1944056D02*
X877899D01*
X877412Y1944543D01*
X874243D01*
X866688Y1936988D01*
X863000D01*
X862241Y1936229D01*
Y1934326D01*
G01D02*
X859355Y1937212D01*
X856662D01*
X855250Y1935800D01*
G01X882677Y1947205D02*
X877899D01*
X877412Y1946718D01*
X873342D01*
X865787Y1939163D01*
X862900D01*
X862241Y1939822D01*
Y1941826D01*
G01D02*
X859802Y1939387D01*
X856663D01*
X855250Y1940800D01*
G01X851350Y1945200D02*
Y1949700D01*
G01D02*
X854800D01*
X856900Y1947600D01*
G01D02*
X859800Y1944700D01*
X868248D01*
X872448Y1948900D01*
X875900D01*
X877354Y1950354D01*
X882676D01*
X882677Y1950355D01*
G01X919750Y160000D02*
Y155500D01*
G01Y164453D02*
X914833D01*
G01X931500Y139453D02*
Y142453D01*
X929250Y144703D01*
X924375D01*
G01X923250Y129953D02*
X927500D01*
X931500Y133953D01*
Y139453D01*
G01X920500Y137203D02*
Y150000D01*
X916998Y153502D01*
X915037D01*
G01X931500Y544965D02*
Y547965D01*
X929250Y550215D01*
X924375D01*
G01X923250Y535465D02*
X927500D01*
X931500Y539465D01*
Y544965D01*
G01X920500Y542715D02*
Y552700D01*
X916600Y556600D01*
G01X919750Y561000D02*
Y565500D01*
G01Y569965D02*
X914833D01*
G01X919750Y971000D02*
Y966500D01*
G01Y975477D02*
X914833D01*
G01X931500Y950477D02*
Y953477D01*
X929250Y955727D01*
X924375D01*
G01X923250Y940977D02*
X927500D01*
X931500Y944977D01*
Y950477D01*
G01X914646Y964214D02*
X918286D01*
X920500Y962000D01*
Y948227D01*
G01X931500Y1355988D02*
Y1358988D01*
X929250Y1361238D01*
X924375D01*
G01X923250Y1346488D02*
X927500D01*
X931500Y1350488D01*
Y1355988D01*
G01X920500Y1353738D02*
Y1365800D01*
X916263Y1370037D01*
X915037D01*
G01X919750Y1376500D02*
Y1372000D01*
G01Y1380988D02*
X914833D01*
G01X926500Y1660000D02*
X942500Y1644000D01*
X992000D01*
X994898Y1641102D01*
X1009744D01*
G01X943500Y1646989D02*
X982989D01*
X987102Y1651102D01*
X1009744D01*
G01X969000Y1641500D02*
X973000D01*
G01X976000Y1636000D02*
X979500Y1639500D01*
X993000D01*
X996398Y1636102D01*
X1009744D01*
G01X931000Y1659000D02*
X938500D01*
X945500Y1652000D01*
X984500D01*
X986500Y1654000D01*
X997500D01*
X999602Y1656102D01*
X1009744D01*
G01X969500Y1671000D02*
X965587Y1667087D01*
X960163D01*
X959000Y1668250D01*
G01X979500Y1669750D02*
Y1667762D01*
X978825Y1667087D01*
X973413D01*
X969500Y1671000D01*
G01X954750Y1668500D02*
X958750D01*
X959000Y1668250D01*
G01X969500Y1661000D02*
X965588Y1664912D01*
X960162D01*
X959000Y1663750D01*
G01X979500Y1662250D02*
Y1664237D01*
X978825Y1664912D01*
X973412D01*
X969500Y1661000D01*
G01X954750Y1663500D02*
X958750D01*
X959000Y1663750D01*
G01X934825Y1682285D02*
X975715D01*
X986898Y1671102D01*
X1009744D01*
G01X947000Y1654500D02*
X983500D01*
X990102Y1661102D01*
X1009744D01*
G01Y1666102D02*
X999398D01*
X996898Y1668602D01*
X985898D01*
X978000Y1676500D01*
X969500D01*
G01X919750Y1782000D02*
Y1777500D01*
G01Y1786500D02*
X914833D01*
G01X913923Y1752000D02*
X919750D01*
G01X924375Y1766750D02*
X929250D01*
X931500Y1764500D01*
Y1761500D01*
G01X923250Y1752000D02*
X927500D01*
X931500Y1756000D01*
Y1761500D01*
G01X920500Y1759250D02*
Y1769400D01*
X916100Y1773800D01*
M02*
